DO NOT SCALE DRAWING SHEET 
B
AA
B
B
SIZE 
SCALE: 
234
1234
DEPARTMENT CODE 
1
DOCUMENT NUMBER REV 
1 OF 270 
Wed Feb 08 16:34:24 2017 
WIWYNN CORPORATION 
PCB NUMBER: 15126_1B 
TIOGA PASS 



DO NOT SCALE DRAWING 
REV 
4
DEPARTMENT 
SHEET 
3 2 1
4 3 2 1
SCALE: 
DOCUMENT NUMBER CODE SIZE 
B
B
A A
B
POWER BLOCK DIAGRAM 
SYSTEM BLOCK DIAGRAM 
CPU SIDE BAND: MISC 
SKYLAKE - SKT0 - 15 OF 21 
INDEX (1 OF 3) 
SKYLAKE - SKT1 - 2 OF 21 
X24 SLOT (2 OF 2) 
19 
SKYLAKE - SKT0 - 21 OF 21 
CPU0 DDR4 CH D DIMM0 
PCIE TX CAPS 
SKYLAKE - SKT1 - 9 OF 21 
CPU0 DDR4 CH E DIMM0 
CLOCK BLOCK DIAGRAM 
CPU SIDE BAND:CPU0 DIMM CA VREF 
CPU0 DDR4 CH D DIMM1 
CPU0 DDR4 CH A DIMM1 INDEX (3 OF 3) 
HFI OSCILLATORS 
CPU0 DDR4 CH C DIMM1 
CPU1 DDR4 CH K DIMM1 
PWRGD/RESET 
INTERRUPTS AND ERROR PROPAGATION 
XDP BLOCK DIAGRAM 
TITLE 
SMBUS BLOCK DIAGRAM 
FAN BLOCK DIAGRAM 
ADR BLOCK DIAGRAM 
MCP JTAG BLOCK DIAGRAM 
POWER/RESET TIMING G3>S5 
POWER/RESET TIMING G3 > S5 > S0 > S5 
FAST_PROCHOT BLOCK DIAGRAM 
1
2
3
4
5
6
7
8
9
10 
12 
13 
14 
15 
16 
17 
18 
11 
SMBUS BLOCK DIAGRAM 
INDEX (2 OF 3) 
LEWISBURG 7/11 GPIO E-J 120 
Wed Feb 08 16:34:24 2017 
LEWISBURG 6/11 GPIO A-D 
SKYLAKE - SKT1 - 21 OF 21 
2 OF 270 
CPU SIDE BAND:DIMM SMBUS TRANSLATORS 
CPU SIDE BAND: PROCHOT & MEMHOT (2/2) 
CPU SIDE BAND: PROCHOT & MEMHOT (1/2) 
HFI-IO CONNECTOR 
CPU SIDE BAND: HW STRAPS 
CPU1 DDR4 CH L DIMM1 
118 LEWISBURG 5/11 LAN 
LEWISBURG 4/11 DMI, PCIE 
CPU1 DDR4 CH H DIMM1 
SKYLAKE - SKT0 - 3 OF 21 
SKYLAKE - SKT1 - 1 OF 21 
PCIE-LANE REVERSAL & POLARITY INV 
68 
SKYLAKE - SKT1 - 13 OF 21 
SKYLAKE - SKT1 - 12 OF 21 
SKYLAKE - SKT1 - 11 OF 21 
SKYLAKE - SKT1 - 10 OF 21 
SKYLAKE - SKT1 - 8 OF 21 
SKYLAKE - SKT1 - 7 OF 21 
SKYLAKE - SKT1 - 6 OF 21 
SKYLAKE - SKT1 - 5 OF 21 
SKYLAKE - SKT1 - 3 OF 21 
CPU0 DDR4 CH E DIMM1 
48 
52 
SKYLAKE - SKT1 - 14 OF 21 
71 
SKYLAKE - SKT0 - 20 OF 21 
MISC. VOLTAGE INFO 
SKYLAKE - SKT0 - 1 OF 21 
SKYLAKE - SKT0 - 2 OF 21 
SKYLAKE - SKT0 - 4 OF 21 
SKYLAKE - SKT0 - 5 OF 21 
SKYLAKE - SKT0 - 6 OF 21 
SKYLAKE - SKT0 - 7 OF 21 
SKYLAKE - SKT0 - 8 OF 21 
SKYLAKE - SKT0 - 9 OF 21 
SKYLAKE - SKT0 - 10 OF 21 
SKYLAKE - SKT0 - 11 OF 21 
SKYLAKE - SKT0 - 13 OF 21 
SKYLAKE - SKT0 - 14 OF 21 
SKYLAKE - SKT0 - 16 OF 21 
SKYLAKE - SKT0 - 17 OF 21 
SKYLAKE - SKT0 - 18 OF 21 
SKYLAKE - SKT0 - 19 OF 21 
CPU0 DDR4 CH B DIMM0 
CPU0 DDR4 CH B DIMM1 
CPU0 DDR4 CH C DIMM0 
CPU0 DDR4 CH F DIMM0 
CPU0 DDR4 CH F DIMM1 
SKYLAKE - SKT1 - 4 OF 21 
SKYLAKE - SKT1 - 15 OF 21 
SKYLAKE - SKT1 - 16 OF 21 
SKYLAKE - SKT1 - 17 OF 21 
SKYLAKE - SKT1 - 18 OF 21 
SKYLAKE - SKT1 - 19 OF 21 
SKYLAKE - SKT1 - 20 OF 21 
CPU1 DECOUPLING CAVITY CAPS 
CPU1 DDR4 CH G DIMM0 
CPU1 DDR4 CH J DIMM0 
CPU1 DDR4 CH J DIMM1 
CPU1 DDR4 CH K DIMM0 
CPU1 DDR4 CH L DIMM0 
CPU1 DDR4 CH M DIMM0 
CPU1 DDR4 CH M DIMM1 
NVDIMM SUPPORT 
ERRORS CIRCUITRY 
CPU SIDE BAND:RESETS & POWER GOODS 
CPU SIDE BAND:PULL-UPS/PULL-DOWNS 
CPU SIDE BAND:CPU1 DIMM CA VREF 
CKMNG+ 
DB1200ZL 
DB1200ZL CLOCK TERMINATION 
CPU OCP TX CAPS 
PCIE STEERING 
X24 SLOT (1 OF 2) 
ANCHORS - LABELS 
CPU & PCH XDP (2-2) 
LEWISBURG 1/11 CLOCKS 
LEWISBURG 2/11 USB 
20 
21 
22 
23 
24 
25 
26 
27 
28 
29 
30 
31 
32 
33 
34 
35 
36 
37 
38 
39 
40 
41 
42 
43 
44 
45 
46 
47 
49 
50 
51 
53 
54 
55 
56 
57 
58 
59 
60 
61 
62 
63 
64 
65 
66 
67 
69 
70 
72 
73 
74 
75 
76 
77 
78 
79 
80 
81 
82 
83 
84 
85 
86 
87 
88 
89 
90 
91 
92 
93 
94 
95 
96 
97 
98 
99 
100 
101 
102 
103 
104 
105 
107 
110 
111 
112 
113 
114 
115 
116 
117 
119 
CPU0 DDR4 CH A DIMM0 
CPU0 DECOUPLING CAVITY CAPS 
106 
108 
109 
CPU & PCH XDP (1-2) 
MCP JTAG 
LEWISBURG 3/11 IO 
CPU1 DDR4 CH G DIMM1 
SKYLAKE - SKT0 - 12 OF 21 
CPU1 DDR4 CH H DIMM0 
CONTENTS PAGE(S) CONTENTS PAGE(S) CONTENTS PAGE(S) 
INDEX (1 OF 3) 
WIWYNN CORPORATION 



DO NOT SCALE DRAWING 
REV 
4
DEPARTMENT 
SHEET 
3 2 1
4 3 2 1
SCALE: 
DOCUMENT NUMBER CODE SIZE 
B
B
A A
B
124 
PCH STRAPS (1/2) 
PVCCIO CPU0 (2 OF 2) 
BMC DEBUG HEADER 
LEWISBURG 9/11 PWR 
USB3 EXTERNAL RIGHT ANGLE CONNECTOR 
DDR VTT VR CHANNEL GHJ 
139 
VOLTAGE MONITORING 
VDDQ GHJ DECAP (3 OF 3) 
I2C/SPI TO UART BRIDGE CONTROLLER 
FAST PROCHOT LOGIC 
VDDQ KLM DECAP (3 OF 3) 
LEWISBURG 10/11 PWR, GND 
BOARD AND SKU ID STRAPS LEWISBURG 11/11 GND 
123 
VDDQ GHJ VR(2 OF 3) 
PCH STRAPS (2/2) 
UART MUX CONTROL 
122 
Wed Feb 08 16:34:24 2017 
LBG HEADERS (1/3) 
121 
PCH DECOUPLING 1/3 
MOUNTING HOLES + POWER INPUT CONNECTOR 
3 OF 270 
PVNN P1V05 PCH STBY VR (2 OF 2) 
PVNN P1V05 PCH STBY VR (1 OF 2) 
DDR VTT VR CHANNEL KLM 
VDDQ KLM VR (2 OF 3) 
VDDQ KLM_VR (1 OF 3) 
224 
223 
PWR, RESET BTN & LEDS 
MINI_SAS (2/2) 
MINI_SAS (1/2) 
SATA DOWN CONNECTOR 
170 
169 
168 
167 
166 
165 
164 
SMBUS: CPU PCIE HP 
BMC DEDICATED SPI FLASH 
FAN HEADERS 
BATTERY CIRCUIT/VOLTAGE SUPERVISORS 
POWER MISC: RAPL RESISTOR 
HOT SWAP CONTROLLER (1/2) 
HOT SWAP CONTROLLER (2/2) 
235 
VPP GHJ VR 
VPP DEF VR 
VPP ABC VR 
126 
127 
SPARE 
LEWISBURG 8/11 RMII, SPI 
LAN SPRINGVILLE I210 (1/3) 
AIRMAX 1X8 MID-PLANE CONNECTOR A 
158 
MEMHOT LVT3 LEVEL TRANSLATION 
BMC (6 OF 7) 
LAN SPRINGVILLE I210 (3/3) 
LBG HEADERS (3/3) 
157 
240 
239 
238 
237 
236 
234 
233 
232 
231 
230 
229 
228 
227 
226 
225 
222 
221 
220 
219 
218 
217 
216 
215 
214 
213 
212 
211 
210 
209 
208 
207 
206 
205 
204 
203 
202 
201 
200 
199 
198 
197 
196 
195 
194 
193 
192 
191 
190 
189 
188 
187 
186 
185 
184 
183 
182 
181 
180 
179 
178 
177 
176 
175 
174 
173 
172 
171 
163 
162 
161 
160 
159 
156 
155 
154 
153 
152 
151 
150 
149 
148 
147 
146 
145 
144 
143 
142 
141 
140 
138 
137 
136 
135 
134 
133 
132 
131 
130 
129 
128 
125 
P3V3 STBY VR 
P1V2 & P2V5 BMC STBY VR 
P1V15 BMC STBY VR 
P1V8 PCH STBY VR 
VPP KLM VR 
VDDQ GHJ_VR (1 OF 3) 
DDR VTT VR CHANNEL DEF 
DDR VTT VR CHANNEL ABC 
VDDQ DEF DECAP (3 OF 3) 
VDDQ DEF_VR (2 OF 3) 
VDDQ DEF_VR (1 OF 3) 
VDDQ ABC DECAP (3 OF 3) 
VDDQ ABC VR (2 OF 3) 
VDDQ ABC VR (1 OF 3) 
PVCCIO CPU1 (2 OF 2) 
PVCCIO CPU1 (1 OF 2) 
PVCCIO CPU0 (1 OF 2) 
VSA CPU1 
VCCIN CPU1 (4 OF 4) 
VCCIN CPU1 (3 OF 4) 
VCCIN CPU1 (2 OF 4) 
VCCIN CPU1 (1 OF 4) 
VSA CPU0 
VCCIN CPU0 (4 OF 4) 
VCCIN CPU0 (3 OF 4) 
VCCIN CPU0 (2 OF 4) 
VCCIN CPU0 (1 OF 4) 
POWER SWITCHES 
MCP CPU0 VRM 
MCP CPU1 VRM 
CPLD (3 OF 3) 
CPLD (2 OF 3) 
CPLD (1 OF 3) 
BMC JTAG HEADER 
OCP MODULE CONN C 
OCP MODULE CONN B 
OCP MODULE CONN A 
M.2 CONNECTOR 
SPI TPM CONNECTOR 
AIRMAX 1X8 MID-PLANE CONNECTOR B 
SPARE 
SPARE 
SATA SGPIO CONNECTORS 
SYSTEM LEDS 
SPARE 
TEMPERATURE SENSORS AND FRU 
PECI 
VOLTAGE MONITORING IC 
SMBUS PULLUPS (2 OF 2) 
SMBUS PULLUPS (1 OF 2) 
UART MUX 
BMC MISC (2 OF 2) 
BMC MISC (1 OF 2) 
PCH AND BMC SHARED SPI FLASH MUX 
BMC AND PCH SHARED SPI FLASH 
BMC DDR4 MEMORY 
BMC STRAPS 
BMC DECOUPLING CAPS 
BMC (7 OF 7) 
BMC (4 & 5 OF 7) 
BMC (3 OF 7) 
BMC (2 OF 7) 
BMC (1 OF 7) 
PCIE WAKE TRI-STATE BUFFER 
LAN SPRINGVILLE I210 (2/3) 
LBG SMBUS RESISTORS 
LBG HEADERS (2/3) 
THERMTRIP AND FIVRBREAK 
LBG PULLUPS/PULLDOWNS 
PCH DECOUPLING 3/3 
PCH DECOUPLING 2/3 
DMI AC COUPLING 
LBG PLL FILTERS 
CONTENTS PAGE(S) CONTENTS PAGE(S) CONTENTS PAGE(S) 
INDEX (2 OF 3) 
WIWYNN CORPORATION 



DO NOT SCALE DRAWING 
REV 
4
DEPARTMENT 
SHEET 
3 2 1
4 3 2 1
SCALE: 
DOCUMENT NUMBER CODE SIZE 
B
B
A A
B
TPM PRESENT AND RESET CIRCUIT 
244 
X8 SLOT FOR PCIE RISER CARD 
ADD DIMM CAP FOR SINGLE SIDE MB (1/2) 
259 
ADD DIMM CAP FOR SINGLE SIDE MB (2/2) 
BMC REMOTE DEBUG CIRCUIT - 1 OF 2 
USB3.0 DEBUG PORT, SMBUS MASTER SWITCH & BIOS SPFT BOARD ID 
x8 PCIe Co-lay path 
243 
BMC SECURE FLASH 
241 
242 
Wed Feb 08 16:34:25 2017 
CPU0 HOT PLUG AND M.2 RESET CIRCUIT 
BMC REMOTE DEBUG CIRCUIT - 2 OF 2 
MEZZ PRESENT CIRCUIT 
4 OF 270 
P5V STBY VR 
PUMP HEADER 
VGA 
USB TYPE C CONNECTOR 
COUPON - 1 OF 3 
COUPON - 2 OF 3 
COUPON - 3 OF 3 
SMBUS BLOCK DIAGRAM - 1 OF 2 
SMBUS BLOCK DIAGRAM - 2 OF 2 
UART BLOCK DIAGRAM 
SPI BLOCK DIAGRAM 1 OF 2 
SPI BLOCK DIAGRAM 2 OF 2 
SYMBOL DEFINITIONS 
TPM BLOCK DIAGRAM 
BUTTON BLOCK DIAGRAM 
XDP BLOCK DIAGRAM 
FAST PROCHOT BLOCK DIAGRAM 
MCP JTAG BLOCK DIAGRAM 
JTAG DEBUG HEADER BLOCK DIAGRAM 
245 
246 
247 
248 
249 
250 
251 
252 
253 
254 
255 
256 
257 
258 
260 
261 
262 
263 
264 
265 
266 
267 
268 
269 
270 
CONTENTS PAGE(S) CONTENTS PAGE(S) CONTENTS PAGE(S) 
INDEX (3 OF 3) 
WIWYNN CORPORATION 



DO NOT SCALE DRAWING SHEET 
B
AA
B
B
SIZE 
SCALE: 
234
1234
DEPARTMENT CODE 
1
DOCUMENT NUMBER REV 
5 OF 270 
Wed Feb 08 16:34:25 2017 
SYSTEM BLOCK DIAGRAM 
WIWYNN CORPORATION 



DO NOT SCALE DRAWING SHEET 
B
AA
B
B
SIZE 
SCALE: 
234
1234
DEPARTMENT CODE 
1
DOCUMENT NUMBER REV 
6 OF 270 
Wed Feb 08 16:34:26 2017 
CLOCK BLOCK DIAGRAM 
WIWYNN CORPORATION 



DO NOT SCALE DRAWING SHEET 
B
AA
B
B
SIZE 
SCALE: 
234
1234
DEPARTMENT CODE 
1
DOCUMENT NUMBER REV 
7 OF 270 
Wed Feb 08 16:34:28 2017 SMBUS BLOCK DIAGRAM 
WIWYNN CORPORATION 



DO NOT SCALE DRAWING SHEET 
B
AA
B
B
SIZE 
SCALE: 
234
1234
DEPARTMENT CODE 
1
DOCUMENT NUMBER REV 
8 OF 270 
Wed Feb 08 16:34:28 2017 
SMBUS BLOCK DIAGRAM 
WIWYNN CORPORATION 



DO NOT SCALE DRAWING SHEET 
B
AA
B
B
SIZE 
SCALE: 
234
1234
DEPARTMENT CODE 
1
DOCUMENT NUMBER REV 
9 OF 270 
Wed Feb 08 16:34:28 2017 
POWER BLOCK DIAGRAM 
WIWYNN CORPORATION 



DO NOT SCALE DRAWING SHEET 
B
AA
B
B
SIZE 
SCALE: 
234
1234
DEPARTMENT CODE 
1
DOCUMENT NUMBER REV 
10 OF 270 
Wed Feb 08 16:34:29 2017 
INTERRUPTS AND ERROR PROPAGATION 
WIWYNN CORPORATION 



DO NOT SCALE DRAWING SHEET 
B
AA
B
B
SIZE 
SCALE: 
234
1234
DEPARTMENT CODE 
1
DOCUMENT NUMBER REV 
11 OF 270 
Wed Feb 08 16:34:29 2017 
FAN BLOCK DIAGRAM 
WIWYNN CORPORATION 



DO NOT SCALE DRAWING SHEET 
B
AA
B
B
SIZE 
SCALE: 
234
1234
DEPARTMENT CODE 
1
DOCUMENT NUMBER REV 
12 OF 270 
Wed Feb 08 16:34:29 2017 
12 OF 270 ADR BLOCK DIAGRAM 
WIWYNN CORPORATION 



DO NOT SCALE DRAWING SHEET 
B
AA
B
B
SIZE 
SCALE: 
234
1234
DEPARTMENT CODE 
1
DOCUMENT NUMBER REV 
13 OF 270 
Wed Feb 08 16:34:30 2017 
XDP BLOCK DIAGRAM 
WIWYNN CORPORATION 



DO NOT SCALE DRAWING SHEET 
B
AA
B
B
SIZE 
SCALE: 
234
1234
DEPARTMENT CODE 
1
DOCUMENT NUMBER REV 
14 OF 270 
Wed Feb 08 16:34:30 2017 
MCP JTAG BLOCK DIAGRAM 
WIWYNN CORPORATION 



DO NOT SCALE DRAWING SHEET 
B
AA
B
B
SIZE 
SCALE: 
234
1234
DEPARTMENT CODE 
1
DOCUMENT NUMBER REV 
Wed Feb 08 16:34:30 2017 
15 OF 270 PWRGD/RESET 
WIWYNN CORPORATION 



DO NOT SCALE DRAWING SHEET 
B
AA
B
B
SIZE 
SCALE: 
234
1234
DEPARTMENT CODE 
1
DOCUMENT NUMBER REV 
16 OF 270 
Wed Feb 08 16:34:30 2017 
POWER/RESET TIMING G3>S5 
WIWYNN CORPORATION 



DO NOT SCALE DRAWING SHEET 
B
AA
B
B
SIZE 
SCALE: 
234
1234
DEPARTMENT CODE 
1
DOCUMENT NUMBER REV 
17 OF 270 
Wed Feb 08 16:34:31 2017 
POWER/RESET TIMING G3 > S5 > S0 > S5 
WIWYNN CORPORATION 



DO NOT SCALE DRAWING SHEET 
B
AA
B
B
SIZE 
SCALE: 
234
1234
DEPARTMENT CODE 
1
DOCUMENT NUMBER REV 
Wed Feb 08 16:34:31 2017 
18 OF 270 FAST_PROCHOT BLOCK DIAGRAM 
WIWYNN CORPORATION 



DO NOT SCALE DRAWING SHEET 
B
AA
B
B
SIZE 
SCALE: 
234
1234
DEPARTMENT CODE 
1
DOCUMENT NUMBER REV 
19 OF 270 
Wed Feb 08 16:34:31 2017 
PCIE-LANE REVERSAL & POLARITY INV 
WIWYNN CORPORATION 



DO NOT SCALE DRAWING SHEET 
B
AA
B
B
SIZE 
SCALE: 
234
1234
DEPARTMENT CODE 
1
DOCUMENT NUMBER REV 
20 OF 270 
Wed Feb 08 16:34:31 2017 
MISC. VOLTAGE INFO 
WIWYNN CORPORATION 



1/16W 
1/16W 
1/16W 
1/16W 
1/16W 
1/16W 
SOCKET_P_MECH_A 
SOCKET_P_MECH_A 
H_CPU0_MEMDEF_MEMHOT_G_N 
FM_CPU0_PKGID1 
PLASTIC 
DL44 
AD17 
R5N5 
G21796-047 
AY19 
XLU1 
1% 
CHIP 
0402 
1
2 CHIP 
R6N1 
49.9 
SVID_ALERT0_CPU0_R_N 
100.0 
SVID_CLK0_CPU0_R 
SVID_DIO0_CPU0_R 
SVID_ALERT1_CPU0_R_N 
0402 
0402 CHIP 
2
PWRGD_CPU0_DRAMPWROK_ABC_G 
1
2
1% 
R5N3 
10.0K 
1/16W 
CHIP 
1/16W 
1% 
1.8K 
R5N4 
1.8K 
TP_CPU0_SOCKET_ID_2 
FM_CPU0_PROC_ID1 
FM_CPU0_PROC_ID0 
FM_CPU0_PKGID2 
PU_CPU0_TSC_SYNC 
FM_CPU0_SM_WP 
TP_NMI_CPU0 
PU_CPU0_LEGACY_SKT 
49.9 
H_CPU0_THERMTRIP_G_N 
PU_CPU0_FRMAGENT 
H_CPU0_BMCINIT 
H_CPU0_CATERR_G_N 
H_CPU0_ERR2_G_N 
SVID_CLK1_CPU0_R 
SVID_DIO1_CPU0_R 
SVID_DIO0_CPU0 
H_PMSYNC_CLK_24M 
SVID_CLK0_CPU0 
SVID_ALERT0_CPU0_N 
SVID_ALERT1_CPU0_N 
SVID_CLK1_CPU0 
SVID_DIO1_CPU0 
PECI_CPU_G 
FM_CPU0_SKTOCC_LVT3_N 
XDP_CPU0_TDO 
XDP_CPU_TMS 
XDP_CPU_TDI 
XDP_CPU_MBP1_N 
XDP_CPU_OBSFN_B0_MBP6_N 
A_CPU0_UPI01_RBIAS 
A_CPU0_UPI2_RBIAS 
A_CPU0_PE012_RBIAS 
A_CPU0_PE3_RBIAS 
A_CPU0_DEF_RCOMP0 
A_CPU0_DEF_RCOMP1 
A_CPU0_DEF_RCOMP2 
A_CPU0_ABC_RCOMP1 
A_CPU0_ABC_RCOMP2 
M_A_CPU_VREF 
M_B_CPU_VREF 
M_C_CPU_VREF 
M_D_CPU_VREF 
A_CPU0_ABC_RCOMP0 
PU_CPU0_SOCKET_ID_1 
H_CPU0_FAST_WAKE_N 
PD_CPU0_BIST_ENABLE 
PD_CPU0_TXT_PLTEN 
PU_CPU0_TXT_AGENT 
H_CPU0_PROCHOT_G_N 
TP_CPU0_PROCDIS_G_N 
M_ABC_RST_N 
PWRGD_CPU0_G 
RST_CPU0_G_N 
PD_CPU0_EAR_N 
H_PM_SYNC_GTL 
H_CPU0_ERR0_G_N 
H_CPU0_MSMI_G_N 
PU_CPU0_SOCKET_ID_0 
H_PMSYNC_CLK_24M_CPU0 
H_PM_SYNC_GTL_R1 
FM_CPU0_PKGID0 
H_CPU0_ERR1_G_N 
PD_PIROM_CPU0_ADDR1 
PD_PIROM_CPU0_ADDR2 
XDP_CPU_PREQ_N 
PD_CPU0_TEST14 
PD_CPU0_TEST12 
PD_CPU0_TEST13 
XDP_CPU_PRDY_N 
PD_PIROM_CPU0_ADDR0 
PD_CPU0_KSFC_DIS 
PU_CPU0_SAFE_MODE_BOOT 
CLK_100M_CPU0_BCLK1_DN 
CLK_100M_CPU0_BCLK0_DP 
CLK_100M_CPU0_BCLK0_DN 
CLK_100M_CPU0_BCLK1_DP 
CLK_100M_CPU0_BCLK2_DN 
CLK_100M_CPU0_BCLK2_DP 
SMB_DDR_DEF_SCL_G_R 
SMB_DDR_ABC_SCL_G_R 
SMB_DDR_DEF_SDA_G_R 
SMB_DDR_ABC_SDA_G_R 
A_CPU0_MCP01_RBIAS 
TP_XDP_CPU0_OBSDATA_A1_MBP3_N 
TP_XDP_CPU0_OBSDATA_A0_MBP2_N 
XDP_CPU_MBP0_N 
XDP_CPU_TCK0 
XDP_CPU_TRST_N 
PWRGD_CPU0_DRAMPWROK_DEF_G 
M_DEF_RST_N 
H_CPU0_MEMABC_MEMHOT_G_N 
M_F_CPU_VREF 
M_E_CPU_VREF 
TP_XDP_CPU0_OBSDATA_A2_MBP4_N 
TP_XDP_CPU0_OBSDATA_A3_MBP5_N 
XDP_CPU_OBSFN_B1_MBP7_N 
SMB_CPU0_PE_HP_GTL_SDA 
SMB_CPU0_PE_HP_GTL_SCL 
SMB_PIROM_CPU0_SDA 
SMB_PIROM_CPU0_SCL 
AB43 
CU32 
AE12 
AJ10 
CL28 
W14 
AC14 
AA14 
CT31 
AC12 
Y11 
AA12 
AF11 
AG10 
AH11 
Y13 
TBD 
CP29 
CL30 
AJ18 
AE18 
CV61 
CK29 
AP29 
AT29 
CW58 
CT59 
AL18 
CN30 
CR30 
AF13 
AH13 
DV63 
DD49 
DD47 
DC48 
CR28 
AF17 
U64 
AC42 
Y43 
AN30 
CT61 
CP61 
AH63 
AK63 
AJ64 
AM19 
AU24 
AW24 
CU26 
CT25 
CP27 
CR26 
IC 
U5D1 
CU58 
DC50 
AW14 
AB13 
CW56 
DB51 
AE14 
AR12 
AG16 
AP11 
AE20 
CV57 
DB71 
CY71 
DA72 
AV15 
AW18 
AM11 
AB15 
DJ44 
DB45 
DG44 
DC44 
DE44 
AU16 
CV59 
AR18 
AC16 
AB17 
AF15 
CW72 
DC72 
AN20 
AV17 
AL12 
AK11 
AJ12 
AL14 
BD23 
BA20 
AP21 
AT19 
AR14 
AU12 
AJ14 
BC24 
AU20 
AU22 
4.75K 
2
1
1/16W 
0402 
G21796-072 
CHIP 
R4R5 
1% 
G21796-047 R4P18 49.9 1% 
1
1/16W 
2
CHIP 0402 
1
2
0402 
CHIP 
1
1% 
10.0K 
0402 
2
1/16W 
CHIP 2
1
0402 
10.0K 
R5N1 
1/16W 
1% 
2
1
1/16W 
CHIP 
R5N2 
0402 
G21796-047 R4P19 1% 
1
1/16W 
H37604-201 
LEFT 
XRU1 
H37604-101 
PLASTIC 
RIGHT 
CHIP 
G21796-047 
0402 
1/16W 
2
1% 
R6D2 
49.9 1
1/16W 
R4P4 
G21796-047 
CHIP 
0402 
2
1% 
49.9 1
0402 
G21796-047 
1/16W 
R4P2 
49.9 
CHIP 
1% 
2
1
G21796-047 
0402 
2CHIP 
1/16W 
49.9 
R4P3 
1% 
1
1% 
49.9 
R6D11 
G21796-047 
0402 
CHIP 
1/16W 
2
1
1/16W 
0402 
G21796-017 
CHIP 
1% 
2
1100.0 
R4P11 
1/16W 
G21796-365 
0402 
CHIP 2
1% 
190.9 
R4P10 
G21796-365 
CHIP 
1/16W 
90.9 
0402 
1% 
2
1
R4P8 
100.0 
1% 
R6D1 
1/16W 
0402 
G21796-017 
CHIP 2
1
0402 
1/16W 
90.9 
CHIP 
1% 
G21796-365 
1
2
R5D2 
90.9 
R5D1 
0402 
CHIP 
1/16W 
1% 
G21796-365 
2
1
1
2
R6N2 
CHIP 
G21796-017 
2 CHIP 
R6B1 
1
G21796-047 
49.9 
R6B2 
100.0 1
CHIP 
G21796-017 
2
0.0 G21497-005 R6B4 21 5% 
0.0 2 5% R6B5 G21497-005 0402 1
221 1.0% 2G21796-271 R6B3 0402 1
0.0 1 2 0402 5% R6N11 G21497-005 
0.0 2G21497-005 5% 0402 1R6N12 
1.0% 221 0402 21G21796-271 R6N10 
RESERVED 
RESERVED 
MCP SUPPORT 
3'B000 
3'B001 
3'B010 
3'B111-3'B011 
RESERVED 
SKYLAKE PROCESSOR 
2'B11 
2'B01 
2'B00 
2'B10 
RESERVED 
RESERVED FOR FUTURE PROCESSOR HOST FABRIC INTERFACE 
NON-MCP SUPPORT 
113 190 
194 201 211 
194 201 211 
194 201 211 
194 215 218 
96 
190 
190 
190 
97 
156 
90 
92 
90 
90 156 
92 
92 
194 215 218 
194 215 218 
114 55 
55 166 
118 144 
190 
112 
112 55 
112 
55 112 
55 112 
98 
98 
98 
98 
90 
97 157 
90 
90 
90 
95 93 
43 44 45 46 47 48 
96 113 
96 
90 
118 55 
93 
92 
90 
190 
93 
156 
156 
112 55 
90 
90 
90 
55 112 
156 
90 
90 
103 
103 
103 
103 
103 
103 
99 
99 
99 
99 
111 254 55 112 
112 55 
96 
49 50 51 52 53 54 
94 95 152 
98 
94 95 152 
98 
55 112 
248 
248 
156 
156 
0402 
1/16W 
1% 1% 
1/16W 
0402 
1% 
1/16W 
0402 
1% 
1/16W 
0402 
G21796-016 
G21796-336 
G21796-336 
G21796-016 
G21796-016 
CAD NOTE: 
DESIGN NOTE: 
CAD NOTE: 
DESIGN NOTE: 
BOM NOTE: 
DEFINITION DEFINITION PROC_ID [1:0] 
BOM_COST=PROC_SOCKET 
ROOM=CPU0 
PKG_ID[2:0] 
PIROM_ADDR[2:0] 3B000 
ALTERNATE: H63715-002 
CPU0 PIROM ADDRESS: 0XA0 
P0 
P0 
DO NOT SCALE DRAWING 
ASSEMBLY IPN PRIMARY :H63715-002, 
SHEET 
B
AA
B
B
SIZE 
SCALE: 
234
1234
DEPARTMENT CODE 
1
DOCUMENT NUMBER REV 
OUT 
BI 
IN 
IN 
IN 
IN 
IN 
IN 
IN 
OUT 
BI 
IN 
OUT 
OUT 
OUT 
BI 
IN 
IN 
IN 
IN 
IN 
IN 
BI 
BI 
IN 
OUT 
BI 
IN 
IN 
IN 
IN 
BI 
IN 
OUT 
IN 
BI 
PVCCIO_CPU0 
IN 
IN 
IN 
IN 
P3V3_STBY 
OUT 
OUT 
OUT 
OUT 
OUT 
P3V3_STBY 
OUT 
OUT 
OUT 
OUT 
IN 
IN 
OUT 
OUT 
OUT 
IN 
OUT 
IN 
OUT 
IN 
BI 
IN 
IN 
PVCCIO_CPU0 
IN 
OUT 
BI 
OUT 
IN 
OUT 
BI 
BI 
OUT 
OUT 
OUT 
OUT 
IN 
BI 
IN 
IN 
IN 
OUT 
OUT 
21 OF 270 
Wed Feb 08 16:34:32 2017 
WITHIN 1.1 IN OF CPU PINS 
PLACE RBIAS RESISTORS 
PLACE RCOMP RESISTORS 
WITHIN 1 IN OF CPU PINS UPI2_RBIAS<0> UPI2_RBIAS<1> UPI01_RBIAS<0> UPI01_RBIAS<1> 
TXT_PLTEN TXT_AGENT 
TSC_SYNC 
TRST_N TMS 
THERMTRIP_N 
TEST_15 
TEST_14 
TEST_13 
TEST_12 
TDO 
TDI 
TCK 
SVIDDATA<0> 
SVIDDATA<1> 
SVIDCLK<0> 
SVIDCLK<1> 
SVIDALERT_N<0> 
SVIDALERT_N<1> 
SOCKET_ID<0> SOCKET_ID<1> 
SOCKET_ID<2> 
SM_WP 
SMBDAT SMBCLK 
SKTOCC_N 
SAFE_MODE_BOOT 
RESET_N PWRGOOD 
PROC_ID<0> PROC_ID<1> 
PROCHOT_N PROCDIS_N 
PREQ_N PRDY_N 
PM_FAST_WAKE_N 
PMSYNC_CLK PMSYNC 
PKGID<0> PKGID<1> PKGID<2> 
PIROM_ADDR<0> PIROM_ADDR<1> PIROM_ADDR<2> 
PE_HP_SDA PE_HP_SCL 
PECI 
PE3_RBIAS<0> PE3_RBIAS<1> 
PE012_RBIAS<0> PE012_RBIAS<1> 
NMI 
MSMI_N 
MEM_HOT_C345_N MEM_HOT_C012_N 
MCP01_RBIAS<0> MCP01_RBIAS<1> LEGACY_SKT 
FRMAGENT 
ERROR_N<0> ERROR_N<1> ERROR_N<2> 
EAR_N 
DDR5_CAVREF 
DDR4_CAVREF 
DDR3_CAVREF 
DDR345_SPDSDA 
DDR345_SPDSCL 
DDR345_RESET_N 
DDR345_RCOMP<0> DDR345_RCOMP<1> DDR345_RCOMP<2> 
DDR345_DRAM_PWR_OK 
DDR2_CAVREF 
DDR1_CAVREF 
DDR0_CAVREF 
DDR012_SPDSDA 
DDR012_SPDSCL 
DDR012_RESET_N 
DDR012_RCOMP<0> DDR012_RCOMP<1> DDR012_RCOMP<2> 
DDR012_DRAM_PWR_OK 
CATERR_N 
BPM_N<0> BPM_N<1> BPM_N<2> BPM_N<3> BPM_N<4> BPM_N<5> BPM_N<6> BPM_N<7> 
BMCINIT 
BIST_ENABLE 
BCLK2_DP 
BCLK2_DN 
BCLK1_DP 
BCLK1_DN 
BCLK0_DP 
BCLK0_DN 
.
SKYLAKE - SKT0 - 1 OF 21 
CPU SYMBOLS 1-30 ARE PRELIMINARY AND SUBJECT TO CHANGE 
SKYLAKE - SKT0 - 1 OF 21 
SKX_EXT_B 
INA
ILER
R
Y
P
M
WIWYNN CORPORATION 
1/30 



TP_CPU0_RSVD_291 
TP_CPU0_RSVD_299 
AG46 
CPU_XDP_PRESENT_N 
TP_CPU0_RSVD_217 
TP_CPU0_RSVD_218 
TP_CPU0_RSVD_TEST_5 
H_CPU0_FIVR_FAULT_G 
CLK_322M_OSC_CPU0_RC_DP 
TP_CPU0_RSVD_219 
TP_CPU0_RSVD_216 
TP_CPU0_RSVD_214 
CLK_322M_OSC_CPU0_RC_DN 
AK57 
AK59 
CLK_100M_CPU0_RC_REFCLK0_DP 
TP_CPU0_RSVD_300 
TP_CPU0_RSVD_248 
TP_CPU0_RSVD_252 
TP_CPU0_RSVD_265 
TP_CPU0_RSVD_258 
TP_CPU0_RSVD_251 
TP_CPU0_RSVD_250 
TP_CPU0_RSVD_249 
TP_CPU0_RSVD_247 
TP_CPU0_RSVD_246 
TP_CPU0_RSVD_245 
TP_CPU0_RSVD_244 
TP_CPU0_RSVD_243 
TP_CPU0_RSVD_242 
TP_CPU0_RSVD_281 
TP_CPU0_RSVD_279 
TP_CPU0_RSVD_277 
TP_CPU0_RSVD_262 
TP_CPU0_RSVD_264 
TP_CPU0_RSVD_280 
TP_CPU0_RSVD_278 
TP_CPU0_RSVD_276 
TP_CPU0_RSVD_272 
TP_CPU0_RSVD_274 
TP_CPU0_RSVD_293 
TP_CPU0_RSVD_292 
TP_CPU0_RSVD_290 
TP_CPU0_RSVD_268 
TP_CPU0_RSVD_273 
TP_CPU0_RSVD_271 
TP_CPU0_RSVD_269 
TP_CPU0_RSVD_270 
TP_CPU0_RSVD_260 
TP_CPU0_RSVD_298 
TP_CPU0_RSVD_288 
TP_CPU0_RSVD_289 
TP_CPU0_RSVD_224 
TP_CPU0_RSVD_225 
TP_CPU0_RSVD_226 
TP_CPU0_RSVD_227 
TP_CPU0_RSVD_229 
TP_CPU0_RSVD_230 
TP_CPU0_RSVD_234 
TP_CPU0_RSVD_235 
TP_CPU0_RSVD_237 
TP_CPU0_RSVD_238 
TP_CPU0_RSVD_239 
TP_CPU0_RSVD_240 
TP_CPU0_RSVD_241 
TP_CPU0_RSVD_223 
TP_CPU0_RSVD_222 
PD_CPU0_RSVD_TEST_1 
PD_CPU0_RSVD_TEST_2 
TP_CPU0_RSVD_TEST_3 
TP_CPU0_RSVD_TEST_4 
XDP_CPU_PWR_DEBUG_N 
TP_CPU0_RSVD_212 
TP_CPU0_RSVD_211 
TP_CPU0_RSVD_210 
TP_CPU0_RSVD_208 
TP_CPU0_RSVD_204 
TP_CPU0_RSVD_205 
TP_CPU0_RSVD_199 
TP_CPU0_RSVD_198 
CLK_100M_CPU0_RC_REFCLK0_DN 
TP_CPU0_RSVD_194 
TP_CPU0_RSVD_259 
TP_CPU0_RSVD_261 
TP_CPU0_RSVD_263 
TP_CPU0_RSVD_266 
TP_CPU0_RSVD_267 
TP_CPU0_RSVD_275 
TP_CPU0_RSVD_282 
TP_CPU0_RSVD_284 
TP_CPU0_RSVD_283 
TP_CPU0_RSVD_285 
TP_CPU0_RSVD_286 
TP_CPU0_RSVD_287 
TP_CPU0_RSVD_304 
TP_CPU0_RSVD_303 
TP_CPU0_RSVD_254 
TP_CPU0_RSVD_253 
TP_CPU0_RSVD_TEST_11 
TP_CPU0_RSVD_256 
FM_CPU0_RC_ERROR_N 
TP_CPU0_RSVD_231 
TP_CPU0_RSVD_232 
TP_CPU0_RSVD_233 
TP_CPU0_RSVD_236 
TP_CPU0_RSVD_228 
U5D1 
TBD 
IC 
AY13 
AN14 
AN12 
AM13 
AF45 
A4 
A6 
A14 
A16 
A24 
B3 
B7 
B13 
B15 
B17 
B77 
B81 
C6 
C18 
C82 
D5 
D17 
D65 
D83 
E2 
E4 
E84 
F3 
F23 
F65 
F83 
G2 
G64 
G84 
H1 
H83 
H85 
J46 
J62 
K61 
M63 
P65 
R62 
R66 
T67 
U66 
V65 
Y23 
Y65 
AD47 
AD51 
AE46 
AE48 
AE50 
AE52 
AE72 
AF19 
AF47 
AF49 
AF51 
AF53 
AF71 
AG20 
AG48 
AG50 
AG52 
AG56 
AG72 
AH15 
AH19 
AH55 
AH57 
AH71 
AH73 
AJ56 
AJ58 
AJ60 
AJ62 
AJ70 
AK21 
AK61 
AK69 
AL20 
AL22 
AL26 
AL58 
AL60 
AL62 
AM21 
AM23 
AM25 
AM27 
AM59 
AM61 
AN18 
AN22 
AN24 
AN26 
AN60 
AN62 
AP23 
AP25 
AP27 
AP61 
AP17 
AW12 
AV21 
AJ20 
E24 
C24 
AK27 
AU14 
W66 
V67 
AD49 
AG54 
P1V8_MCP_CPU0 
PVCCMCP_CPU0 
R5P4 
G21796-047 
49.9 
1% 
0402 
CHIP 
1/16W 
2
1
R5R1 
G21796-047
49.9 
1% 
0402 
CHIP 
1/16W 
2
1
TP FAB3 RECONNECT 0921 111 255 56 
92 
104 
194 
90 
104 
103 
194 
111 118 254 56 
103 
133 118 120 145 
VSENSE_P1V8MCP_CPU0_SKT_VRTN 
PD_CPU0_DMIMODE_OVERRIDE 
VSENSE_P1V8MCP_CPU0_SKT_VSEN 
DESIGN NOTE: 
DESIGN NOTE: 
CLKS USED FOR DEBUG ONLY 
DO NOT SCALE DRAWING SHEET 
B
AA
B
B
SIZE 
SCALE: 
234
1234
DEPARTMENT CODE 
1
DOCUMENT NUMBER REV 
IN 
IN 
OUT 
IN 
IN 
IN 
IN 
OUT 
IN 
IN 
IN 
22 OF 270 
Wed Feb 08 16:34:32 2017 
TEST_5 
TEST_4 TEST_3 TEST_2 
TEST_11 
TEST_1 
RSVD<194> RSVD<195> RSVD<196> RSVD<197> RSVD<198> RSVD<199> RSVD<200> RSVD<201> RSVD<202> 
RSVD<203> 
RSVD<204> RSVD<205> RSVD<206> RSVD<207> RSVD<208> 
RSVD<209> RSVD<210> RSVD<211> RSVD<212> RSVD<213> 
RSVD<214> 
RSVD<215> RSVD<216> 
RSVD<217> RSVD<218> RSVD<219> 
RSVD<220> 
RSVD<221> 
RSVD<222> RSVD<223> RSVD<224> RSVD<225> RSVD<226> RSVD<227> 
RSVD<228> RSVD<229> RSVD<230> RSVD<231> RSVD<232> 
RSVD<233> RSVD<234> 
RSVD<235> RSVD<236> RSVD<237> RSVD<238> RSVD<239> RSVD<240> RSVD<241> 
RSVD<242> 
RSVD<243> RSVD<244> RSVD<245> RSVD<246> RSVD<247> RSVD<248> 
RSVD<249> RSVD<250> 
RSVD<251> RSVD<252> RSVD<253> RSVD<254> 
RSVD<256> RSVD<257> RSVD<258> RSVD<259> 
RSVD<260> 
RSVD<261> RSVD<262> RSVD<263> RSVD<264> RSVD<265> RSVD<266> RSVD<267> RSVD<268> RSVD<269> RSVD<270> RSVD<271> RSVD<272> RSVD<273> 
RSVD<274> RSVD<275> 
RSVD<276> RSVD<277> 
RSVD<278> RSVD<279> RSVD<280> RSVD<281> 
RSVD<282> RSVD<283> 
RSVD<284> RSVD<285> RSVD<286> RSVD<287> RSVD<288> RSVD<289> 
RSVD<290> RSVD<291> RSVD<292> RSVD<293> RSVD<294> 
RSVD<295> RSVD<296> 
RSVD<298> RSVD<299> RSVD<300> RSVD<301> RSVD<302> RSVD<303> RSVD<304> 
PWR_DEBUG_N 
FIVR_FAULT 
DMIMODE_OVERRIDE 
DEBUG_EN_N 
SKYLAKE - SKT0 - 2 OF 21 
CPU SYMBOLS 1-30 ARE PRELIMINARY AND SUBJECT TO CHANGE 
SKYLAKE - SKT0 - 2 OF 21 
SKX_EXT_B 
INA
ILER
RY
P
M
BOM_COST=PROC_SOCKET 
ROOM=CPU0 
WIWYNN CORPORATION 
2/30 



P73 
47 
M_A_C<2> M_A_PAR 
M_A_ALERT_N 
M_A_ACT_N 
M_A_DQS_DN<17:0> 
M_A_DQS_DP<17:0> 
M_A_BA<1:0> 
M_A_BG<1:0> 
M_A_CKE<3:0> 
M_A_CS_N<7:0> 
M_A_MA<17:0> 
M_A_ODT<3:0> 
M_A_CLK_DN<3:0> 
M_A_CLK_DP<3:0> 
M_A_ECC<7:0> 
M_A_DQ<63:0> 
0
5
7
6
0
1
2
4
3
0
1 1
0
1
63 
62 
61 
60 
59 
58 
57 
2
56 
55 
54 
53 
52 
51 
50 
49 
48 
3
46 
45 
44 
43 
42 
41 
40 
39 
38 
1
37 
35 
36 
34 
33 
32 
30 
31 
29 
28 
0
27 
25 
26 
24 
23 
22 
21 
20 
19 
18 
17 
16 
15 
14 
13 
12 
11 
10 
9
7
8
6
5
4
3
2
0
1
7
6
5
M77 
J60 
B61 
C52 
G54 
D61 
F63 
G46 
C62 
C64 
B63 
D63 
F55 
C54 
J56 
C56 
D55 
B55 
G56 
B57 G52 
F49 
D47 
F47 
B51 
D49 
F45 
K45 
AN86 
AN84 
AE86 
AE84 
AR86 
AR84 
AG86 
AG84 
W86 
W84 
L86 
L84 
AA86 
AA84 
N86 
N84 
V81 
T79 
N82 
M81 
W80 
V79 
R82 
N80 
L76 
R76 
M73 
P77 
L74 
R74 
C42 
B41 
C38 
E38 
E42 
F41 
B39 
F39 
K37 
P37 
L34 
N34 
L38 
N38 
K35 
P35 
K31 
P31 
L28 
N28 
L32 
N32 
K29 
P29 
K25 
P25 
P23 
T23 
L26 
N26 
H23 
K23 
AJ84 
R84 
P79 
T75 
G40 
R36 
R30 
N24 
AH67 
AL84 
U84 
U82 
K75 
A40 
J36 
J30 
J24 
AB67 
AH85 
P85 
R80 
P75 
E40 
N36 
N30 
R24 
AF67 
AM85 
V85 
T81 
M75 
C40 
L36 
L30 
L24 
AD67 
AC68 
AG68 
AD65 
AF65 
AD69 
AF69 
AC66 
AG66 
F53 
F57 
D57 
C58 
G58 
F59 
D59 
G60 
C60 
F61 
J54 
G62 
J64 
J48 
F51 
K49 
D51 
K47 
C50 
C48 
G50 
G48 
D53 
IC 
TBD 
U5D1 
16 
3
15 
17 
10 
11 
14 
13 
12 
7
8
9
4
6
5
4
2
0
1
3
2
13 
14 
15 
1
17 
16 
8
9
10 
11 
12 
3
4
5
0
7
6
17 
1
2
0
12 
13 
16 
15 
3
14 
7
8
11 
10 
9
4
5
6
3
2
2
1
1
2
0
3
1
2
0
3
0
43 44 43 44 
43 44 
43 44 
43 44 
43 44 
43 44 
43 44 
43 44 
43 44 
43 44 
43 44 
43 44 
43 44 
43 44 
43 44 
DESIGN NOTE: 
DO NOT SCALE DRAWING SHEET 
B
AA
B
B
SIZE 
SCALE: 
234
1234
DEPARTMENT CODE 
1
DOCUMENT NUMBER REV 
BI 
OUT 
OUT 
OUT 
BI 
BI 
OUT 
OUT 
OUT 
OUT 
OUT 
OUT 
OUT 
IN 
OUT 
BI 
23 OF 270 
Wed Feb 08 16:34:32 2017 
DDR0_PAR 
DDR0_ODT<0> DDR0_ODT<1> DDR0_ODT<2> DDR0_ODT<3> 
DDR0_MA<0> 
DDR0_MA<1> DDR0_MA<2> DDR0_MA<3> DDR0_MA<4> DDR0_MA<5> DDR0_MA<6> DDR0_MA<7> DDR0_MA<8> DDR0_MA<9> DDR0_MA<10> DDR0_MA<11> DDR0_MA<12> DDR0_MA<13> 
DDR0_MA<14> DDR0_MA<15> DDR0_MA<16> DDR0_MA<17> 
DDR0_ECC<0> DDR0_ECC<1> DDR0_ECC<2> DDR0_ECC<3> DDR0_ECC<4> 
DDR0_ECC<5> DDR0_ECC<6> DDR0_ECC<7> 
DDR0_DQS_DP<0> 
DDR0_DQS_DP<1> DDR0_DQS_DP<2> DDR0_DQS_DP<3> DDR0_DQS_DP<4> DDR0_DQS_DP<5> DDR0_DQS_DP<6> DDR0_DQS_DP<7> DDR0_DQS_DP<8> DDR0_DQS_DP<9> DDR0_DQS_DP<10> DDR0_DQS_DP<11> DDR0_DQS_DP<12> DDR0_DQS_DP<13> 
DDR0_DQS_DP<14> DDR0_DQS_DP<15> DDR0_DQS_DP<16> DDR0_DQS_DP<17> 
DDR0_DQS_DN<0> DDR0_DQS_DN<1> DDR0_DQS_DN<2> DDR0_DQS_DN<3> DDR0_DQS_DN<4> DDR0_DQS_DN<5> DDR0_DQS_DN<6> DDR0_DQS_DN<7> 
DDR0_DQS_DN<8> DDR0_DQS_DN<9> DDR0_DQS_DN<10> DDR0_DQS_DN<11> DDR0_DQS_DN<12> DDR0_DQS_DN<13> DDR0_DQS_DN<14> DDR0_DQS_DN<15> DDR0_DQS_DN<16> DDR0_DQS_DN<17> 
DDR0_DQ<0> DDR0_DQ<1> DDR0_DQ<2> DDR0_DQ<3> DDR0_DQ<4> DDR0_DQ<5> DDR0_DQ<6> DDR0_DQ<7> DDR0_DQ<8> 
DDR0_DQ<9> DDR0_DQ<10> DDR0_DQ<11> DDR0_DQ<12> DDR0_DQ<13> DDR0_DQ<14> DDR0_DQ<15> DDR0_DQ<16> DDR0_DQ<17> DDR0_DQ<18> DDR0_DQ<19> DDR0_DQ<20> DDR0_DQ<21> 
DDR0_DQ<22> DDR0_DQ<23> DDR0_DQ<24> DDR0_DQ<25> DDR0_DQ<26> DDR0_DQ<27> DDR0_DQ<28> DDR0_DQ<29> DDR0_DQ<30> DDR0_DQ<31> DDR0_DQ<32> DDR0_DQ<33> DDR0_DQ<34> 
DDR0_DQ<35> DDR0_DQ<36> DDR0_DQ<37> DDR0_DQ<38> DDR0_DQ<39> DDR0_DQ<40> DDR0_DQ<41> DDR0_DQ<42> DDR0_DQ<43> DDR0_DQ<44> DDR0_DQ<45> DDR0_DQ<46> 
DDR0_DQ<47> DDR0_DQ<48> DDR0_DQ<49> DDR0_DQ<50> DDR0_DQ<51> DDR0_DQ<52> DDR0_DQ<53> DDR0_DQ<54> DDR0_DQ<55> DDR0_DQ<56> DDR0_DQ<57> DDR0_DQ<58> DDR0_DQ<59> 
DDR0_DQ<60> DDR0_DQ<61> DDR0_DQ<62> DDR0_DQ<63> 
DDR0_CS_N<0> DDR0_CS_N<1> DDR0_CS_N<2> DDR0_CS_N<3> DDR0_CS_N<4> DDR0_CS_N<5> DDR0_CS_N<6> 
DDR0_CS_N<7> 
DDR0_CLK_DP<0> DDR0_CLK_DP<1> DDR0_CLK_DP<2> DDR0_CLK_DP<3> 
DDR0_CLK_DN<0> 
DDR0_CLK_DN<1> DDR0_CLK_DN<2> DDR0_CLK_DN<3> 
DDR0_CKE<0> DDR0_CKE<1> DDR0_CKE<2> DDR0_CKE<3> 
DDR0_CID<2> 
DDR0_BG<0> DDR0_BG<1> 
DDR0_BA<0> DDR0_BA<1> 
DDR0_ALERT_N DDR0_ACT_N 
SKYLAKE - SKT0 - 3 OF 21 
CPU SYMBOLS 1-30 ARE PRELIMINARY AND SUBJECT TO CHANGE 
SKYLAKE - SKT0 - 3 OF 21 
ROOM=CPU0 
BOM_COST=PROC_SOCKET 
SKX_EXT_B 
INA
ILER
RY
P
M
WIWYNN CORPORATION 
3/30 



M_B_DQ<63:0> 
H69 
C72 
M_B_ACT_N 
M_B_ALERT_N 
M_B_PAR M_B_C<2> 
M_B_CLK_DN<3:0> 
M_B_CLK_DP<3:0> 
M_B_ECC<7:0> 
M_B_BA<1:0> 
M_B_BG<1:0> 
M_B_CKE<3:0> 
M_B_CS_N<7:0> 
M_B_ODT<3:0> 
M_B_DQS_DN<17:0> 
M_B_MA<17:0> 
M_B_DQS_DP<17:0> 
7
5
6
0
1
2
3
4
0
0
1
1
1
0
62 
63 
61 
60 
59 
58 
57 
0
56 
55 
52 
54 
53 
50 
51 
49 
48 
2
47 
46 
45 
44 
43 
42 
40 
41 
39 
38 
1
37 
35 
36 
34 
33 
32 
31 
29 
30 
28 
0
27 
26 
25 
24 
23 
22 
21 
19 
20 
18 
17 
16 
15 
14 
11 
13 
12 
9
10 
8
7
6
5
4
3
2
1
0
7
6
5
K43 
T63 
W62 
T53 
K55 
M61 
N60 
M47 
N62 
R64 
K63 
L64 
M53 
R54 
N56 
R56 
N54 
T55 
M57 
T57 K51 
R50 
N46 
V47 
J50 
T49 
M45 
R46 
AV81 
AT79 
AN82 
AM81 
AW80 
AV79 
AR82 
AN80 
AH81 
AF79 
AC82 
AB81 
AJ80 
AH79 
AE82 
AC80 
E80 
J80 
F77 
H77 
F81 
H81 
E78 
J78 
D75 
C74 
D71 
F71 
F75 
G74 
G72 
H43 
L40 
N40 
P43 
T43 
K41 
P41 
C36 
B35 
C32 
E32 
E36 
F35 
B33 
F33 
C30 
B29 
C26 
E26 
E30 
F29 
B27 
F27 
U28 
AA28 
V25 
Y25 
V29 
Y29 
U26 
AA26 
AP79 
AD79 
K79 
H73 
N42 
G34 
G28 
AB27 
N68 
AU82 
AG82 
D79 
B73 
J42 
A34 
A28 
T27 
G68 
AR80 
AE80 
H79 
F73 
R42 
E34 
E28 
Y27 
L68 
AT81 
AF81 
F79 
D73 
L42 
C34 
C28 
V27 
J68 
J70 
J66 
L66 
L70 
M69 
H67 
M67 
J52 
J58 
K57 
N58 
M59 
R58 
T59 
V61 
W60 
K59 
M55 
R60 
T61 
M51 
T51 
N52 
R52 
N48 
N50 
R48 
M49 
T47 
K53 
IC 
TBD 
U5D1 
14 
3
15 
17 
16 
9
10 
11 
12 
13 
4
6
4
5
8
7
2
1
3
2
0
14 
15 
16 
1
17 
13 
10 
9
11 
12 
8
5
7
6
0
4
3
2
16 
17 
1
0
11 
12 
13 
3
14 
15 
6
7
8
9
10 
1
3
2
2
5
4
3
0
1
2
2
0
1
3
3
45 46 
45 46 
45 46 
45 46 45 46 
45 46 
45 46 
45 46 
45 46 
45 46 
45 46 
45 46 
45 46 
45 46 
45 46 
45 46 
DESIGN NOTE: 
DO NOT SCALE DRAWING SHEET 
B
AA
B
B
SIZE 
SCALE: 
234
1234
DEPARTMENT CODE 
1
DOCUMENT NUMBER REV 
BI 
BI 
OUT 
OUT 
BI 
BI 
OUT 
OUT 
OUT 
OUT 
OUT 
OUT 
OUT 
IN 
OUT OUT 
24 OF 270 
Wed Feb 08 16:34:33 2017 
DDR1_PAR 
DDR1_ODT<0> DDR1_ODT<1> DDR1_ODT<2> DDR1_ODT<3> 
DDR1_MA<0> DDR1_MA<1> 
DDR1_MA<2> DDR1_MA<3> DDR1_MA<4> DDR1_MA<5> DDR1_MA<6> DDR1_MA<7> DDR1_MA<8> DDR1_MA<9> DDR1_MA<10> DDR1_MA<11> DDR1_MA<12> DDR1_MA<13> DDR1_MA<14> 
DDR1_MA<15> DDR1_MA<16> DDR1_MA<17> 
DDR1_ECC<0> DDR1_ECC<1> DDR1_ECC<2> DDR1_ECC<3> DDR1_ECC<4> DDR1_ECC<5> 
DDR1_ECC<6> DDR1_ECC<7> 
DDR1_DQS_DP<0> DDR1_DQS_DP<1> 
DDR1_DQS_DP<2> DDR1_DQS_DP<3> DDR1_DQS_DP<4> DDR1_DQS_DP<5> DDR1_DQS_DP<6> DDR1_DQS_DP<7> DDR1_DQS_DP<8> DDR1_DQS_DP<9> DDR1_DQS_DP<10> DDR1_DQS_DP<11> DDR1_DQS_DP<12> DDR1_DQS_DP<13> DDR1_DQS_DP<14> 
DDR1_DQS_DP<15> DDR1_DQS_DP<16> DDR1_DQS_DP<17> 
DDR1_DQS_DN<0> DDR1_DQS_DN<1> DDR1_DQS_DN<2> DDR1_DQS_DN<3> DDR1_DQS_DN<4> DDR1_DQS_DN<5> DDR1_DQS_DN<6> DDR1_DQS_DN<7> DDR1_DQS_DN<8> 
DDR1_DQS_DN<9> DDR1_DQS_DN<10> DDR1_DQS_DN<11> DDR1_DQS_DN<12> DDR1_DQS_DN<13> DDR1_DQS_DN<14> DDR1_DQS_DN<15> DDR1_DQS_DN<16> DDR1_DQS_DN<17> 
DDR1_DQ<0> DDR1_DQ<1> DDR1_DQ<2> DDR1_DQ<3> DDR1_DQ<4> DDR1_DQ<5> DDR1_DQ<6> DDR1_DQ<7> DDR1_DQ<8> DDR1_DQ<9> 
DDR1_DQ<10> DDR1_DQ<11> DDR1_DQ<12> DDR1_DQ<13> DDR1_DQ<14> DDR1_DQ<15> DDR1_DQ<16> DDR1_DQ<17> DDR1_DQ<18> DDR1_DQ<19> DDR1_DQ<20> DDR1_DQ<21> DDR1_DQ<22> 
DDR1_DQ<23> DDR1_DQ<24> DDR1_DQ<25> DDR1_DQ<26> DDR1_DQ<27> DDR1_DQ<28> DDR1_DQ<29> DDR1_DQ<30> DDR1_DQ<31> DDR1_DQ<32> DDR1_DQ<33> DDR1_DQ<34> DDR1_DQ<35> 
DDR1_DQ<36> DDR1_DQ<37> DDR1_DQ<38> DDR1_DQ<39> DDR1_DQ<40> DDR1_DQ<41> DDR1_DQ<42> DDR1_DQ<43> DDR1_DQ<44> DDR1_DQ<45> DDR1_DQ<46> DDR1_DQ<47> 
DDR1_DQ<48> DDR1_DQ<49> DDR1_DQ<50> DDR1_DQ<51> DDR1_DQ<52> DDR1_DQ<53> DDR1_DQ<54> DDR1_DQ<55> DDR1_DQ<56> DDR1_DQ<57> DDR1_DQ<58> DDR1_DQ<59> DDR1_DQ<60> 
DDR1_DQ<61> DDR1_DQ<62> DDR1_DQ<63> 
DDR1_CS_N<0> DDR1_CS_N<1> DDR1_CS_N<2> DDR1_CS_N<3> DDR1_CS_N<4> DDR1_CS_N<5> DDR1_CS_N<6> DDR1_CS_N<7> 
DDR1_CLK_DP<0> DDR1_CLK_DP<1> DDR1_CLK_DP<2> DDR1_CLK_DP<3> 
DDR1_CLK_DN<0> DDR1_CLK_DN<1> 
DDR1_CLK_DN<2> DDR1_CLK_DN<3> 
DDR1_CKE<0> DDR1_CKE<1> DDR1_CKE<2> DDR1_CKE<3> 
DDR1_CID<2> 
DDR1_BG<0> DDR1_BG<1> 
DDR1_BA<0> DDR1_BA<1> 
DDR1_ALERT_N DDR1_ACT_N 
SKYLAKE - SKT0 - 4 OF 21 
CPU SYMBOLS 1-30 ARE PRELIMINARY AND SUBJECT TO CHANGE 
SKYLAKE - SKT0 - 4 OF 21 
ROOM=CPU0 
BOM_COST=PROC_SOCKET 
SKX_EXT_B 
INA
ILER
RY
P
M
WIWYNN CORPORATION 
4/30 



AU72 
AR64 
M_C_ALERT_N 
M_C_ACT_N 
M_C_PAR M_C_C<2> 
M_C_CLK_DN<3:0> 
M_C_CLK_DP<3:0> 
M_C_ECC<7:0> 
M_C_DQ<63:0> 
M_C_BA<1:0> 
M_C_BG<1:0> 
M_C_CKE<3:0> 
M_C_CS_N<7:0> 
M_C_ODT<3:0> 
M_C_DQS_DN<17:0> 
M_C_MA<17:0> 
M_C_DQS_DP<17:0> 
0
7
6
5
3
4
1
2
0
1
0 0
1
0
62 
63 
61 
60 
59 
58 
57 
3
56 
55 
54 
53 
52 
50 
51 
49 
48 
2
47 
46 
45 
44 
43 
42 
40 
41 
39 
38 
1
37 
35 
36 
32 
34 
33 
31 
30 
29 
28 
0
27 
25 
26 
24 
23 
22 
20 
21 
19 
18 
17 
16 
15 
14 
13 
12 
9
10 
11 
8
7
6
5
4
3
2
0
1
7
6
5
AN68 
AB61 
AD61 
W52 
AE56 
AA60 
AE62 
AB45 
AA62 
AD63 
V63 
AB63 
AA54 
W54 
AA56 
W56 
AB55 
V55 
AB57 
V57 V51 
AB49 
W46 
AA46 
AB51 
W48 
T45 
V45 
AR76 
AN74 
AK77 
AJ76 
AT75 
AR74 
AM77 
AK75 
AE76 
AC74 
Y77 
W76 
AF75 
AE74 
AB77 
Y75 
W72 
AA70 
R70 
T69 
AA72 
AB71 
T71 
V69 
AM67 
AT67 
AN64 
AR68 
AM65 
AT65 
U40 
AA40 
V37 
Y37 
V41 
Y41 
U38 
AA38 
U34 
AA34 
V31 
Y31 
V35 
Y35 
U32 
AA32 
AD31 
AH31 
AE28 
AG28 
AE32 
AG32 
AD29 
AH29 
AD25 
AH25 
AE22 
AG22 
AE26 
AG26 
AD23 
AH23 
AL74 
AA74 
Y69 
AU66 
AB39 
AB33 
AJ30 
AJ24 
BB71 
AP77 
AD77 
U72 
AL66 
T39 
T33 
AC30 
AC24 
AT71 
AM75 
AB75 
W70 
AR66 
Y39 
Y33 
AG30 
AG24 
AY71 
AN76 
AC76 
V71 
AN66 
V39 
V33 
AE30 
AE24 
AV71 
BA72 
AV69 
AY69 
AV73 
AY73 
AU70 
BA70 
AB53 
AE58 
AD57 
W58 
AA58 
V59 
AB59 
AE60 
AD59 
AG58 
AD55 
AG60 
AG62 
AD53 
W50 
AE54 
AA52 
AC46 
AA50 
AA48 
V49 
AB47 
V53 
IC 
TBD 
U5D1 
17 
3
16 
15 
13 
14 
12 
11 
10 
9
8
7
4
6
4
5
2
3
2
0
1
16 
17 
14 
1
15 
13 
11 
12 
10 
9
8
6
7
5
0
4
3
2
0
1
17 
16 
15 
14 
13 
3
12 
11 
10 
9
8
7
6
5
4
3
2
1
2
0
3
2
1
0
3
2
1
1
47 48 
47 48 
47 48 47 48 
47 48 
47 48 
47 48 
47 48 
47 48 
47 48 
47 48 
47 48 
47 48 
47 48 
47 48 
47 48 
DESIGN NOTE: 
DO NOT SCALE DRAWING SHEET 
B
AA
B
B
SIZE 
SCALE: 
234
1234
DEPARTMENT CODE 
1
DOCUMENT NUMBER REV 
BI 
BI 
OUT 
OUT 
BI 
BI 
OUT 
OUT 
OUT 
OUT 
OUT 
OUT 
IN 
OUT 
OUT OUT 
25 OF 270 
Wed Feb 08 16:34:33 2017 
DDR2_PAR 
DDR2_ODT<0> DDR2_ODT<1> DDR2_ODT<2> DDR2_ODT<3> 
DDR2_MA<0> 
DDR2_MA<1> DDR2_MA<2> DDR2_MA<3> DDR2_MA<4> DDR2_MA<5> DDR2_MA<6> DDR2_MA<7> DDR2_MA<8> DDR2_MA<9> DDR2_MA<10> DDR2_MA<11> DDR2_MA<12> DDR2_MA<13> 
DDR2_MA<14> DDR2_MA<15> DDR2_MA<16> DDR2_MA<17> 
DDR2_ECC<0> DDR2_ECC<1> DDR2_ECC<2> DDR2_ECC<3> DDR2_ECC<4> 
DDR2_ECC<5> DDR2_ECC<6> DDR2_ECC<7> 
DDR2_DQS_DP<0> 
DDR2_DQS_DP<1> DDR2_DQS_DP<2> DDR2_DQS_DP<3> DDR2_DQS_DP<4> DDR2_DQS_DP<5> DDR2_DQS_DP<6> DDR2_DQS_DP<7> DDR2_DQS_DP<8> DDR2_DQS_DP<9> DDR2_DQS_DP<10> DDR2_DQS_DP<11> DDR2_DQS_DP<12> DDR2_DQS_DP<13> 
DDR2_DQS_DP<14> DDR2_DQS_DP<15> DDR2_DQS_DP<16> DDR2_DQS_DP<17> 
DDR2_DQS_DN<0> DDR2_DQS_DN<1> DDR2_DQS_DN<2> DDR2_DQS_DN<3> DDR2_DQS_DN<4> DDR2_DQS_DN<5> DDR2_DQS_DN<6> DDR2_DQS_DN<7> 
DDR2_DQS_DN<8> DDR2_DQS_DN<9> DDR2_DQS_DN<10> DDR2_DQS_DN<11> DDR2_DQS_DN<12> DDR2_DQS_DN<13> DDR2_DQS_DN<14> DDR2_DQS_DN<15> DDR2_DQS_DN<16> DDR2_DQS_DN<17> 
DDR2_DQ<0> DDR2_DQ<1> DDR2_DQ<2> DDR2_DQ<3> DDR2_DQ<4> DDR2_DQ<5> DDR2_DQ<6> DDR2_DQ<7> DDR2_DQ<8> 
DDR2_DQ<9> DDR2_DQ<10> DDR2_DQ<11> DDR2_DQ<12> DDR2_DQ<13> DDR2_DQ<14> DDR2_DQ<15> DDR2_DQ<16> DDR2_DQ<17> DDR2_DQ<18> DDR2_DQ<19> DDR2_DQ<20> DDR2_DQ<21> 
DDR2_DQ<22> DDR2_DQ<23> DDR2_DQ<24> DDR2_DQ<25> DDR2_DQ<26> DDR2_DQ<27> DDR2_DQ<28> DDR2_DQ<29> DDR2_DQ<30> DDR2_DQ<31> DDR2_DQ<32> DDR2_DQ<33> DDR2_DQ<34> 
DDR2_DQ<35> DDR2_DQ<36> DDR2_DQ<37> DDR2_DQ<38> DDR2_DQ<39> DDR2_DQ<40> DDR2_DQ<41> DDR2_DQ<42> DDR2_DQ<43> DDR2_DQ<44> DDR2_DQ<45> DDR2_DQ<46> 
DDR2_DQ<47> DDR2_DQ<48> DDR2_DQ<49> DDR2_DQ<50> DDR2_DQ<51> DDR2_DQ<52> DDR2_DQ<53> DDR2_DQ<54> DDR2_DQ<55> DDR2_DQ<56> DDR2_DQ<57> DDR2_DQ<58> DDR2_DQ<59> 
DDR2_DQ<60> DDR2_DQ<61> DDR2_DQ<62> DDR2_DQ<63> 
DDR2_CS_N<0> DDR2_CS_N<1> DDR2_CS_N<2> DDR2_CS_N<3> DDR2_CS_N<4> DDR2_CS_N<5> DDR2_CS_N<6> 
DDR2_CS_N<7> 
DDR2_CLK_DP<0> DDR2_CLK_DP<1> DDR2_CLK_DP<2> DDR2_CLK_DP<3> 
DDR2_CLK_DN<0> 
DDR2_CLK_DN<1> DDR2_CLK_DN<2> DDR2_CLK_DN<3> 
DDR2_CKE<0> DDR2_CKE<1> DDR2_CKE<2> DDR2_CKE<3> 
DDR2_CID<2> 
DDR2_BG<0> DDR2_BG<1> 
DDR2_BA<0> DDR2_BA<1> 
DDR2_ALERT_N DDR2_ACT_N 
SKYLAKE - SKT0 - 5 OF 21 
CPU SYMBOLS 1-30 ARE PRELIMINARY AND SUBJECT TO CHANGE 
SKYLAKE - SKT0 - 5 OF 21 
ROOM=CPU0 
BOM_COST=PROC_SOCKET 
SKX_EXT_B 
INA
ILER
RY
P
M
WIWYNN CORPORATION 
5/30 



M_D_DQ<63:0> 
M_D_ACT_N 
M_D_ALERT_N 
M_D_C<2> M_D_PAR 
M_D_ECC<7:0> 
M_D_CLK_DP<3:0> 
M_D_CLK_DN<3:0> 
M_D_ODT<3:0> 
M_D_CS_N<7:0> 
M_D_CKE<3:0> 
M_D_BG<1:0> 
M_D_BA<1:0> 
M_D_MA<17:0> 
M_D_DQS_DN<17:0> 
M_D_DQS_DP<17:0> 
0
6
5
7
3
4
2
0
1
00
1
1
0
63 
62 
61 
60 
59 
58 
57 
2
56 
55 
54 
53 
52 
51 
50 
49 
48 
3
47 
46 
45 
44 
43 
42 
41 
40 
39 
38 
1
37 
35 
36 
34 
33 
32 
30 
31 
29 
28 
0
27 
25 
26 
24 
23 
22 
21 
20 
19 
18 
17 
16 
15 
14 
13 
12 
11 
10 
9
7
8
6
5
4
3
2
1
0
7
6
5
DU74 
DW60 
ED63 
EE52 
EA54 
ED61 
DW62 
DV47 
EE62 
EF63 
EA62 
EB63 
ED55 
EF55 
DW56 
EF57 
EB55 
EE54 
EA56 
EE56 EF51 
ED49 
ED47 
EB47 
EB51 
EB49 
DV45 
EB45 
CN84 
CN86 
DA86 
DA84 
CL84 
CL86 
CW86 
CW84 
DG84 
DH85 
DV83 
DY83 
DD85 
DE84 
DR84 
DV85 
DM79 
DK81 
DT81 
DR82 
DK79 
DJ80 
DR80 
DN82 
DN76 
DU76 
DP73 
DT73 
DP77 
DT77 
DN74 
EC40 
ED39 
EA36 
EC36 
DY39 
EA40 
DY37 
ED37 
DN36 
DU36 
DP33 
DT33 
DP37 
DT37 
DN34 
DU34 
DN30 
DU30 
DP27 
DT27 
DP31 
DT31 
DN28 
DU28 
DN24 
DU24 
DY21 
EB21 
DP25 
DT25 
EC22 
DW22 
CU84 
DN84 
DL82 
DV75 
EE38 
DV35 
DV29 
DV23 
DF67 
CR84 
DM85 
DN80 
DP75 
EA38 
DP35 
DM29 
DM23 
DB67 
CV85 
DP85 
DM81 
DT75 
EC38 
DT35 
DT29 
DT23 
DD67 
CP85 
DL84 
DP79 
DM75 
DW38 
DM35 
DP29 
DP23 
CY67 
DA68 
DE68 
DB65 
DD65 
DB69 
DD69 
DA66 
DE66 
EB53 
ED57 
EE58 
EB57 
ED59 
EA58 
EE60 
EA60 
EB59 
EF61 
DW54 
EB61 
DT63 
DW48 
ED51 
DV49 
EA52 
EA46 
EE50 
EE48 
EA50 
EA48 
ED53 
IC 
TBD 
U5D1 
17 
3
15 
16 
13 
14 
12 
11 
10 
8
9
7
4
5
6
4
2
3
2
0
1
16 
17 
13 
1
15 
14 
11 
12 
10 
9
8
7
6
5
0
4
3
0
2
1
17 
14 
16 
15 
12 
3
13 
11 
10 
9
8
7
5
6
4
2
2
3
1
0
3
2
1
0
1
3
2
1
49 50 
49 50 
49 50 
49 50 49 50 
49 50 
49 50 
49 50 
49 50 
49 50 
49 50 
49 50 
49 50 
49 50 
49 50 
49 50 
DESIGN NOTE: 
DO NOT SCALE DRAWING SHEET 
B
AA
B
B
SIZE 
SCALE: 
234
1234
DEPARTMENT CODE 
1
DOCUMENT NUMBER REV 
BI 
BI 
OUT 
OUT 
BI 
BI 
OUT 
OUT 
OUT 
OUT 
OUT 
OUT 
OUT 
IN 
OUT OUT 
26 OF 270 
Wed Feb 08 16:34:34 2017 
DDR3_PAR 
DDR3_ODT<0> DDR3_ODT<1> DDR3_ODT<2> DDR3_ODT<3> 
DDR3_MA<0> 
DDR3_MA<1> DDR3_MA<2> DDR3_MA<3> DDR3_MA<4> DDR3_MA<5> DDR3_MA<6> DDR3_MA<7> DDR3_MA<8> DDR3_MA<9> DDR3_MA<10> DDR3_MA<11> DDR3_MA<12> DDR3_MA<13> 
DDR3_MA<14> DDR3_MA<15> DDR3_MA<16> DDR3_MA<17> 
DDR3_ECC<0> DDR3_ECC<1> DDR3_ECC<2> DDR3_ECC<3> DDR3_ECC<4> 
DDR3_ECC<5> DDR3_ECC<6> DDR3_ECC<7> 
DDR3_DQS_DP<0> DDR3_DQS_DP<1> 
DDR3_DQS_DP<2> DDR3_DQS_DP<3> DDR3_DQS_DP<4> DDR3_DQS_DP<5> DDR3_DQS_DP<6> DDR3_DQS_DP<7> DDR3_DQS_DP<8> DDR3_DQS_DP<9> DDR3_DQS_DP<10> DDR3_DQS_DP<11> DDR3_DQS_DP<12> DDR3_DQS_DP<13> DDR3_DQS_DP<14> 
DDR3_DQS_DP<15> DDR3_DQS_DP<16> DDR3_DQS_DP<17> 
DDR3_DQS_DN<0> DDR3_DQS_DN<1> DDR3_DQS_DN<2> DDR3_DQS_DN<3> DDR3_DQS_DN<4> DDR3_DQS_DN<5> DDR3_DQS_DN<6> DDR3_DQS_DN<7> 
DDR3_DQS_DN<8> DDR3_DQS_DN<9> DDR3_DQS_DN<10> DDR3_DQS_DN<11> DDR3_DQS_DN<12> DDR3_DQS_DN<13> DDR3_DQS_DN<14> DDR3_DQS_DN<15> DDR3_DQS_DN<16> DDR3_DQS_DN<17> 
DDR3_DQ<0> DDR3_DQ<1> DDR3_DQ<2> DDR3_DQ<3> DDR3_DQ<4> DDR3_DQ<5> DDR3_DQ<6> DDR3_DQ<7> DDR3_DQ<8> 
DDR3_DQ<9> DDR3_DQ<10> DDR3_DQ<11> DDR3_DQ<12> DDR3_DQ<13> DDR3_DQ<14> DDR3_DQ<15> DDR3_DQ<16> DDR3_DQ<17> DDR3_DQ<18> DDR3_DQ<19> DDR3_DQ<20> DDR3_DQ<21> 
DDR3_DQ<22> DDR3_DQ<23> DDR3_DQ<24> DDR3_DQ<25> DDR3_DQ<26> DDR3_DQ<27> DDR3_DQ<28> DDR3_DQ<29> DDR3_DQ<30> DDR3_DQ<31> DDR3_DQ<32> DDR3_DQ<33> DDR3_DQ<34> 
DDR3_DQ<35> DDR3_DQ<36> DDR3_DQ<37> DDR3_DQ<38> DDR3_DQ<39> DDR3_DQ<40> DDR3_DQ<41> DDR3_DQ<42> DDR3_DQ<43> DDR3_DQ<44> DDR3_DQ<45> DDR3_DQ<46> DDR3_DQ<47> 
DDR3_DQ<48> DDR3_DQ<49> DDR3_DQ<50> DDR3_DQ<51> DDR3_DQ<52> DDR3_DQ<53> DDR3_DQ<54> DDR3_DQ<55> DDR3_DQ<56> DDR3_DQ<57> DDR3_DQ<58> DDR3_DQ<59> DDR3_DQ<60> 
DDR3_DQ<61> DDR3_DQ<62> DDR3_DQ<63> 
DDR3_CS_N<0> DDR3_CS_N<1> DDR3_CS_N<2> DDR3_CS_N<3> DDR3_CS_N<4> DDR3_CS_N<5> DDR3_CS_N<6> 
DDR3_CS_N<7> 
DDR3_CLK_DP<0> DDR3_CLK_DP<1> DDR3_CLK_DP<2> DDR3_CLK_DP<3> 
DDR3_CLK_DN<0> DDR3_CLK_DN<1> 
DDR3_CLK_DN<2> DDR3_CLK_DN<3> 
DDR3_CKE<0> DDR3_CKE<1> DDR3_CKE<2> DDR3_CKE<3> 
DDR3_CID<2> 
DDR3_BG<0> DDR3_BG<1> 
DDR3_BA<0> DDR3_BA<1> 
DDR3_ALERT_N DDR3_ACT_N 
SKYLAKE - SKT0 - 6 OF 21 
CPU SYMBOLS 1-30 ARE PRELIMINARY AND SUBJECT TO CHANGE 
SKYLAKE - SKT0 - 6 OF 21 
ROOM=CPU0 
BOM_COST=PROC_SOCKET 
SKX_EXT_B 
INA
ILER
RY
P
M
WIWYNN CORPORATION 
6/30 



M_E_DQ<63:0> 
EA68 
EA74 
M_E_ACT_N 
M_E_PAR 
M_E_ALERT_N 
M_E_C<2> 
M_E_ECC<7:0> 
M_E_CLK_DP<3:0> 
M_E_CLK_DN<3:0> 
M_E_ODT<3:0> 
M_E_CS_N<7:0> 
M_E_CKE<3:0> 
M_E_BG<1:0> 
M_E_BA<1:0> 
M_E_MA<17:0> 
M_E_DQS_DN<17:0> 
M_E_DQS_DP<17:0> 
1
7
6
4
3
5
2
0
1
1
0
0
1
0
63 
62 
61 
60 
59 
58 
57 
2
56 
55 
54 
53 
52 
51 
50 
49 
48 
3
47 
46 
45 
44 
43 
42 
41 
40 
39 
38 
1
37 
36 
35 
34 
33 
32 
30 
31 
29 
28 
0
27 
25 
26 
24 
23 
22 
21 
20 
19 
18 
17 
16 
15 
14 
13 
12 
11 
10 
9
7
8
6
5
4
3
2
0
1
7
6
5
EB75 
DR62 
DT61 
DM53 
DV55 
DJ62 
DM61 
DT47 
DM63 
DN64 
DL64 
DR64 
DM55 
DR54 
DM57 
DT57 
DN54 
DT53 
DN56 
DR56 DV51 
DN50 
DR46 
DK47 
DW50 
DM49 
DT45 
DN46 
CM79 
CK81 
CT81 
CR82 
CK79 
CJ80 
CR80 
CN82 
DB79 
CY81 
DE80 
DF81 
CY79 
CW80 
DC82 
DE82 
DW80 
EC80 
DY77 
EB77 
DY81 
EB81 
DW78 
EC78 
ED75 
EE74 
EB71 
ED71 
EA72 
EE72 
DU42 
DW42 
DP39 
DT39 
DL42 
DN42 
DN40 
DU40 
EC34 
ED33 
EA30 
EC30 
DY33 
EA34 
DY31 
ED31 
EC28 
ED27 
EA24 
EC24 
DY27 
EA28 
DY25 
ED25 
DF27 
DK27 
DD25 
DJ24 
DG28 
DJ28 
DF25 
DK25 
CL82 
DA82 
ED79 
EF73 
DV41 
EE32 
EE26 
DL26 
EB67 
CN80 
DC80 
DY79 
EB73 
DP41 
EA32 
EA26 
DG26 
DV67 
CM81 
DB81 
EB79 
ED73 
DT41 
EC32 
EC26 
DJ26 
DY67 
CP79 
DD79 
DV79 
DY73 
DM41 
DW32 
DW26 
DE26 
DT67 
DY69 
DV65 
DY65 
DU68 
DV69 
DU66 
EA66 
DW52 
DW58 
DV57 
DR58 
DT59 
DN58 
DM59 
DK61 
DJ60 
DV59 
DT55 
DR60 
DN60 
DT51 
DM51 
DR52 
DN52 
DR48 
DR50 
DN48 
DT49 
DM47 
DV53 
IC 
TBD 
U5D1 
17 
4
16 
15 
14 
13 
10 
11 
12 
8
9
7
3
5
6
2
2
3
4
0
1
16 
17 
14 
1
15 
12 
11 
13 
9
10 
8
6
7
5
0
4
3
1
2
0
17 
15 
16 
14 
13 
3
12 
10 
11 
7
8
9
6
5
4
2
2
3
1
0
2
3
1
0
2
3
0
1
51 52 
51 52 
51 52 
51 52 
51 52 
51 52 
51 52 
51 52 
51 52 
51 52 
51 52 
51 52 
51 52 
51 52 
51 52 
51 52 
DESIGN NOTE: 
DO NOT SCALE DRAWING SHEET 
B
AA
B
B
SIZE 
SCALE: 
234
1234
DEPARTMENT CODE 
1
DOCUMENT NUMBER REV 
BI 
BI 
OUT 
OUT 
BI 
BI 
OUT 
OUT 
OUT 
OUT 
OUT 
OUT 
OUT 
OUT 
IN 
OUT 
27 OF 270 
Wed Feb 08 16:34:34 2017 
DDR4_PAR 
DDR4_ODT<0> DDR4_ODT<1> DDR4_ODT<2> DDR4_ODT<3> 
DDR4_MA<0> DDR4_MA<1> DDR4_MA<2> DDR4_MA<3> DDR4_MA<4> DDR4_MA<5> DDR4_MA<6> DDR4_MA<7> DDR4_MA<8> DDR4_MA<9> DDR4_MA<10> DDR4_MA<11> DDR4_MA<12> DDR4_MA<13> DDR4_MA<14> DDR4_MA<15> DDR4_MA<16> DDR4_MA<17> 
DDR4_ECC<0> DDR4_ECC<1> DDR4_ECC<2> DDR4_ECC<3> DDR4_ECC<4> DDR4_ECC<5> DDR4_ECC<6> DDR4_ECC<7> 
DDR4_DQS_DP<0> DDR4_DQS_DP<1> DDR4_DQS_DP<2> DDR4_DQS_DP<3> DDR4_DQS_DP<4> DDR4_DQS_DP<5> DDR4_DQS_DP<6> DDR4_DQS_DP<7> DDR4_DQS_DP<8> DDR4_DQS_DP<9> DDR4_DQS_DP<10> DDR4_DQS_DP<11> DDR4_DQS_DP<12> DDR4_DQS_DP<13> DDR4_DQS_DP<14> DDR4_DQS_DP<15> DDR4_DQS_DP<16> DDR4_DQS_DP<17> 
DDR4_DQS_DN<0> DDR4_DQS_DN<1> DDR4_DQS_DN<2> DDR4_DQS_DN<3> DDR4_DQS_DN<4> DDR4_DQS_DN<5> DDR4_DQS_DN<6> DDR4_DQS_DN<7> DDR4_DQS_DN<8> DDR4_DQS_DN<9> DDR4_DQS_DN<10> DDR4_DQS_DN<11> DDR4_DQS_DN<12> DDR4_DQS_DN<13> DDR4_DQS_DN<14> DDR4_DQS_DN<15> DDR4_DQS_DN<16> DDR4_DQS_DN<17> 
DDR4_DQ<0> DDR4_DQ<1> DDR4_DQ<2> DDR4_DQ<3> DDR4_DQ<4> DDR4_DQ<5> DDR4_DQ<6> DDR4_DQ<7> DDR4_DQ<8> DDR4_DQ<9> DDR4_DQ<10> DDR4_DQ<11> DDR4_DQ<12> DDR4_DQ<13> DDR4_DQ<14> DDR4_DQ<15> DDR4_DQ<16> DDR4_DQ<17> DDR4_DQ<18> DDR4_DQ<19> DDR4_DQ<20> DDR4_DQ<21> DDR4_DQ<22> DDR4_DQ<23> DDR4_DQ<24> DDR4_DQ<25> DDR4_DQ<26> DDR4_DQ<27> DDR4_DQ<28> DDR4_DQ<29> DDR4_DQ<30> DDR4_DQ<31> DDR4_DQ<32> DDR4_DQ<33> DDR4_DQ<34> DDR4_DQ<35> DDR4_DQ<36> DDR4_DQ<37> DDR4_DQ<38> DDR4_DQ<39> DDR4_DQ<40> DDR4_DQ<41> DDR4_DQ<42> DDR4_DQ<43> DDR4_DQ<44> DDR4_DQ<45> DDR4_DQ<46> DDR4_DQ<47> DDR4_DQ<48> DDR4_DQ<49> DDR4_DQ<50> DDR4_DQ<51> DDR4_DQ<52> DDR4_DQ<53> DDR4_DQ<54> DDR4_DQ<55> DDR4_DQ<56> DDR4_DQ<57> DDR4_DQ<58> DDR4_DQ<59> DDR4_DQ<60> DDR4_DQ<61> DDR4_DQ<62> DDR4_DQ<63> 
DDR4_CS_N<0> DDR4_CS_N<1> DDR4_CS_N<2> DDR4_CS_N<3> DDR4_CS_N<4> DDR4_CS_N<5> DDR4_CS_N<6> DDR4_CS_N<7> 
DDR4_CLK_DP<0> DDR4_CLK_DP<1> DDR4_CLK_DP<2> DDR4_CLK_DP<3> 
DDR4_CLK_DN<0> DDR4_CLK_DN<1> DDR4_CLK_DN<2> DDR4_CLK_DN<3> 
DDR4_CKE<0> DDR4_CKE<1> DDR4_CKE<2> DDR4_CKE<3> 
DDR4_CID<2> 
DDR4_BG<0> DDR4_BG<1> 
DDR4_BA<0> DDR4_BA<1> 
DDR4_ALERT_N DDR4_ACT_N 
SKYLAKE - SKT0 - 7 OF 21 
.
CPU SYMBOLS 1-30 ARE PRELIMINARY AND SUBJECT TO CHANGE 
SKYLAKE - SKT0 - 7 OF 21 
ROOM=CPU0 
BOM_COST=PROC_SOCKET 
SKX_EXT_B 
INA
ILER
RY
P
M
WIWYNN CORPORATION 
7/30 



CY35 
DC36 
1
0
3
2
0
1
3
2
0
1
3
2
2
4
5
6
9
8
7
11 
10 
12 
3
13 
14 
16 
15 
17 
0
2
1
3
4
0
5
7
6
8
10 
9
13 
11 
12 
15 
1
14 
17 
16 
1
0
4
3
2
2
6
5
3
7
9
8
12 
11 
10 
13 
14 
15 
16 
4
17 
U5D1 
TBD 
IC 
DK53 
DF47 
DK49 
DG48 
DG50 
DE46 
DG52 
DC54 
DJ50 
DD53 
DG60 
DA60 
DD55 
DA58 
DD59 
DC60 
DK59 
DF59 
DJ58 
DG58 
DD57 
DC58 
DF53 
CM69 
CH69 
CL72 
CJ72 
CL68 
CJ68 
CM71 
CH71 
CG70 
CV29 
CV35 
DE32 
DC40 
CM65 
DH69 
DG74 
CU74 
CL70 
DB35 
DJ32 
DJ40 
CT65 
DK71 
DE76 
CR76 
CJ70 
CY29 
DG32 
DE40 
CP65 
DJ70 
DF75 
CT75 
CN70 
DD29 
DD35 
DL32 
DG40 
CV65 
DL72 
DD77 
CP77 
DC28 
CW28 
DB31 
CY31 
DB27 
CY27 
DC30 
CW30 
DC34 
CW34 
DB37 
CY37 
DB33 
CY33 
CW36 
DK31 
DF31 
DJ34 
DG34 
DJ30 
DG30 
DK33 
DF33 
DH39 
DD39 
DE42 
DA42 
DG38 
DE38 
DG42 
DD41 
CU64 
CN64 
CT67 
CP63 
CU66 
CN66 
DM71 
DK69 
DG72 
DF71 
DN70 
DM69 
DJ72 
DG70 
DH77 
DF77 
DB75 
DC74 
DJ76 
DH75 
DC76 
DE74 
CT77 
CV75 
CM75 
CN74 
CV77 
CW76 
CN76 
CR74 
DK45 
DM45 
DJ48 
DF51 
DG46 
DJ46 
DF49 
DK51 DG56 
DJ56 
DG54 
DJ54 
DF57 
DK57 
DF55 
DK55 
DF63 
DK63 
DD63 
DG62 
DF45 
DF61 
DA62 
DC56 
DJ52 
DD61 
DC62 
CP67 
5
6
7
1
0
2
3
4
5
6
8
7
9
10 
11 
12 
13 
14 
15 
16 
17 
18 
19 
20 
21 
22 
23 
24 
26 
25 
27 
0
28 
29 
31 
30 
32 
33 
34 
35 
36 
1
38 
39 
40 
41 
42 
43 
44 
45 
46 
47 
3
48 
49 
50 
51 
52 
53 
54 
55 
56 
2
57 
58 
59 
60 
61 
62 
63 
0
1
0
0
1
1
0
2
5
3
4
6
7
1
M_F_DQS_DP<17:0> 
M_F_DQS_DN<17:0> 
M_F_MA<17:0> 
M_F_BA<1:0> 
M_F_BG<1:0> 
M_F_CKE<3:0> 
M_F_CS_N<7:0> 
M_F_ODT<3:0> 
M_F_CLK_DN<3:0> 
M_F_CLK_DP<3:0> 
M_F_ECC<7:0> 
M_F_C<2> 
M_F_ALERT_N 
M_F_PAR 
M_F_ACT_N 
37 
CT63 
M_F_DQ<63:0> 
DB29 
53 54 
53 54 
53 54 
53 54 
53 54 
53 54 
53 54 
53 54 
53 54 
53 54 
53 54 
53 54 
53 54 
53 54 
53 54 
53 54 
DESIGN NOTE: 
DO NOT SCALE DRAWING SHEET 
B
AA
B
B
SIZE 
SCALE: 
234
1234
DEPARTMENT CODE 
1
DOCUMENT NUMBER REV 
BI 
BI 
OUT 
OUT 
BI 
BI 
OUT 
OUT 
OUT 
OUT 
OUT 
OUT 
OUT 
OUT 
IN 
OUT 
28 OF 270 
Wed Feb 08 16:34:34 2017 
DDR5_PAR 
DDR5_ODT<0> DDR5_ODT<1> DDR5_ODT<2> DDR5_ODT<3> 
DDR5_MA<0> 
DDR5_MA<1> DDR5_MA<2> DDR5_MA<3> DDR5_MA<4> DDR5_MA<5> DDR5_MA<6> DDR5_MA<7> DDR5_MA<8> DDR5_MA<9> DDR5_MA<10> DDR5_MA<11> DDR5_MA<12> DDR5_MA<13> 
DDR5_MA<14> DDR5_MA<15> DDR5_MA<16> DDR5_MA<17> 
DDR5_ECC<0> DDR5_ECC<1> DDR5_ECC<2> DDR5_ECC<3> DDR5_ECC<4> 
DDR5_ECC<5> DDR5_ECC<6> DDR5_ECC<7> 
DDR5_DQS_DP<0> DDR5_DQS_DP<1> 
DDR5_DQS_DP<2> DDR5_DQS_DP<3> DDR5_DQS_DP<4> DDR5_DQS_DP<5> DDR5_DQS_DP<6> DDR5_DQS_DP<7> DDR5_DQS_DP<8> DDR5_DQS_DP<9> DDR5_DQS_DP<10> DDR5_DQS_DP<11> DDR5_DQS_DP<12> DDR5_DQS_DP<13> DDR5_DQS_DP<14> 
DDR5_DQS_DP<15> DDR5_DQS_DP<16> DDR5_DQS_DP<17> 
DDR5_DQS_DN<0> DDR5_DQS_DN<1> DDR5_DQS_DN<2> DDR5_DQS_DN<3> DDR5_DQS_DN<4> DDR5_DQS_DN<5> DDR5_DQS_DN<6> DDR5_DQS_DN<7> 
DDR5_DQS_DN<8> DDR5_DQS_DN<9> DDR5_DQS_DN<10> DDR5_DQS_DN<11> DDR5_DQS_DN<12> DDR5_DQS_DN<13> DDR5_DQS_DN<14> DDR5_DQS_DN<15> DDR5_DQS_DN<16> DDR5_DQS_DN<17> 
DDR5_DQ<0> DDR5_DQ<1> DDR5_DQ<2> DDR5_DQ<3> DDR5_DQ<4> DDR5_DQ<5> DDR5_DQ<6> DDR5_DQ<7> DDR5_DQ<8> 
DDR5_DQ<9> DDR5_DQ<10> DDR5_DQ<11> DDR5_DQ<12> DDR5_DQ<13> DDR5_DQ<14> DDR5_DQ<15> DDR5_DQ<16> DDR5_DQ<17> DDR5_DQ<18> DDR5_DQ<19> DDR5_DQ<20> DDR5_DQ<21> 
DDR5_DQ<22> DDR5_DQ<23> DDR5_DQ<24> DDR5_DQ<25> DDR5_DQ<26> DDR5_DQ<27> DDR5_DQ<28> DDR5_DQ<29> DDR5_DQ<30> DDR5_DQ<31> DDR5_DQ<32> DDR5_DQ<33> DDR5_DQ<34> 
DDR5_DQ<35> DDR5_DQ<36> DDR5_DQ<37> DDR5_DQ<38> DDR5_DQ<39> DDR5_DQ<40> DDR5_DQ<41> DDR5_DQ<42> DDR5_DQ<43> DDR5_DQ<44> DDR5_DQ<45> DDR5_DQ<46> DDR5_DQ<47> 
DDR5_DQ<48> DDR5_DQ<49> DDR5_DQ<50> DDR5_DQ<51> DDR5_DQ<52> DDR5_DQ<53> DDR5_DQ<54> DDR5_DQ<55> DDR5_DQ<56> DDR5_DQ<57> DDR5_DQ<58> DDR5_DQ<59> DDR5_DQ<60> 
DDR5_DQ<61> DDR5_DQ<62> DDR5_DQ<63> 
DDR5_CS_N<0> DDR5_CS_N<1> DDR5_CS_N<2> DDR5_CS_N<3> DDR5_CS_N<4> DDR5_CS_N<5> DDR5_CS_N<6> 
DDR5_CS_N<7> 
DDR5_CLK_DP<0> DDR5_CLK_DP<1> DDR5_CLK_DP<2> DDR5_CLK_DP<3> 
DDR5_CLK_DN<0> DDR5_CLK_DN<1> 
DDR5_CLK_DN<2> DDR5_CLK_DN<3> 
DDR5_CKE<0> DDR5_CKE<1> DDR5_CKE<2> DDR5_CKE<3> 
DDR5_CID<2> 
DDR5_BG<0> DDR5_BG<1> 
DDR5_BA<0> DDR5_BA<1> 
DDR5_ALERT_N DDR5_ACT_N 
SKYLAKE - SKT0 - 8 OF 21 
CPU SYMBOLS 1-30 ARE PRELIMINARY AND SUBJECT TO CHANGE 
SKYLAKE - SKT0 - 8 OF 21 
BOM_COST=PROC_SOCKET 
ROOM=CPU0 
SKX_EXT_B 
INA
ILER
RY
P
M
WIWYNN CORPORATION 
8/30 



DMI_CPU0_PCH_RX_C_DN<3:0> 
TP_CPU0_RSVD_172 
TP_CPU0_RSVD_173 
TP_CPU0_RSVD_184 
TP_CPU0_RSVD_186 
TP_CPU0_RSVD_189 
TP_CPU0_RSVD_190 
JTAG_MCP_TRST_N 
JTAG_MCP_TMS 
JTAG_MCP_CPU0_TDI 
JTAG_MCP_TCK 
CLK_100M_CPU0_PE_REFCLK_DP 
CLK_100M_CPU0_PE_REFCLK_DN CLK_156M_OSC_CPU0_HFI_DN 
RST_HFI1_CPU0_LVT2_N 
IRQ_HFI1_CPU0_LVT2_N 
RST_HFI0_CPU0_LVT2_N 
FM_MODPRST_HFI0_CPU0_LVT2_N 
LED_HFI0_CPU0_N 
IRQ_HFI0_CPU0_LVT2_N 
SMB_HFI0_CPU0_LVC2_SDA 
SMB_HFI0_CPU0_LVC2_SCL 
TP_CPU0_RSVD_181 
TP_CPU0_RSVD_180 
TP_CPU0_RSVD_179 
TP_CPU0_RSVD_178 
TP_CPU0_RSVD_177 
TP_CPU0_RSVD_176 
TP_CPU0_RSVD_175 
TP_CPU0_RSVD_174 
TP_CPU0_RSVD_183 
TP_CPU0_RSVD_182 
CLK_156M_OSC_CPU0_HFI_DP 
LED_HFI1_CPU0_N 
FM_MODPRST_HFI1_CPU0_LVT2_N 
JTAG_MCP_CPU0_TDO 
RST_CD_CPU0_POR_N 
SMB_HFI1_CPU0_LVC2_SDA 
SMB_HFI1_CPU0_LVC2_SCL 
DMI_CPU0_PCH_RX_C_DP<3:0> 
DMI_CPU0_PCH_TX_DN<3:0> 
DMI_CPU0_PCH_TX_DP<3:0> 
3
1
0
IC 
BN22 
BP23 
BP19 
BK21 
BR20 
BN24 
BJ22 
BH23 
BM21 
BM23 
BT19 
BK23 
BE16 
BG16 
BU24 
BW24 
CF25 
CB23 
BY21 
CC22 
CE24 
CD23 
CK9 
CM11 
CR12 
CT11 
CL10 
CN10 
CP11 
CV11 
CG4 
CJ4 
CN4 
CP5 
CH5 
CL4 
CM3 
CR4 
BA76 
BA66 BA64 
BA22 
BA18 
BA16 
BA14 
AY77 
AY75 
AY67 
AY65 
AW76 
AW64 
AV77 
AT25 
AT23 
AT13 
AR62 
AR26 
AR22 
AR20 
TBD 
U5D1 
PVCCMCP_CPU0 
3
1
2
0
2
3
0
1
3
2
1
0
2
129 
113 63 
113 63 
113 
113 63 
103 
103 104 
91 
91 
91 
91 
91 
91 
91 
91 
104 
91 
91 
113 
190 192 
91 
91 
129 
129 
129 
DESIGN NOTE: 
DO NOT SCALE DRAWING SHEET 
B
AA
B
B
SIZE 
SCALE: 
234
1234
DEPARTMENT CODE 
1
DOCUMENT NUMBER REV 
IN 
IN 
BI 
OUT 
OUT 
OUT 
IN 
IN 
IN 
BI 
OUT 
OUT 
IN 
IN 
OUT 
IN 
IN 
IN 
IN 
IN 
OUT 
IN 
IN 
IN 
OUT 
OUT 
29 OF 270 
Wed Feb 08 16:34:35 2017 
RSVD<172> RSVD<173> RSVD<174> RSVD<175> RSVD<176> RSVD<177> RSVD<178> RSVD<179> RSVD<180> 
RSVD<181> 
RSVD<182> RSVD<183> 
RSVD<184> RSVD<186> RSVD<187> RSVD<188> RSVD<189> RSVD<190> 
RSVD<191> 
RSVD<192> RSVD<193> 
DMI_TX_DP<0> DMI_TX_DP<1> DMI_TX_DP<2> DMI_TX_DP<3> 
DMI_TX_DN<0> DMI_TX_DN<1> DMI_TX_DN<2> DMI_TX_DN<3> 
DMI_RX_DP<0> DMI_RX_DP<1> DMI_RX_DP<2> DMI_RX_DP<3> 
DMI_RX_DN<0> DMI_RX_DN<1> DMI_RX_DN<2> DMI_RX_DN<3> 
CD_TRST_N CD_TMS CD_TDO 
CD_TDI CD_TCLK CD_POR_N 
CD_PE_REFCLK_DP CD_PE_REFCLK_DN CD_HFI_REFCLK_DP 
CD_HFI_REFCLK_DN 
CD_HFI1_RESET_N CD_HFI1_MODPRST_N CD_HFI1_LED_N CD_HFI1_INT_N 
CD_HFI1_I2CDAT CD_HFI1_I2CCLK 
CD_HFI0_RESET_N 
CD_HFI0_MODPRST_N 
CD_HFI0_LED_N 
CD_HFI0_INT_N 
CD_HFI0_I2CDAT CD_HFI0_I2CCLK 
SKYLAKE - SKT0 - 9 OF 21 
CPU SYMBOLS 1-30 ARE PRELIMINARY AND SUBJECT TO CHANGE 
SKYLAKE - SKT0 - 9 OF 21 
ROOM=CPU0 
BOM_COST=PROC_SOCKET 
SKX_EXT_B 
INA
ILER
RY
P
M
WIWYNN CORPORATION 
9/30 



P3E_CPU0_PE1_SS_TXP<7:0> 
P3E_CPU0_PE1_SS_TXN<7:0> 
DW4 
DL10 
P3E_CPU0_PE1_SS_RXN<7:0> 
P3E_CPU0_PE1_SS_RXP<7:0> 
1
7
8
9
10 
11 
12 
13 
15 
14 
1
0
0
3
2
5
6
4
7
8
9
2
10 
11 
13 
12 
15 
0
1
2
3
0
1
2
5
6
7
8
9
10 
3
4
5
6
7
8
10 
9
12 
3
13 
15 
14 
12 
13 
15 
14 
4
11 
11 
5
U5D1 
TBD 
IC 
EC8 
EB7 
DW6 
DT7 
DV5 
DU4 
DU2 
DR4 
DP3 
DL2 
DH3 
DF3 
DC4 
DD3 
CW2 
ED9 
EA8 
DY7 
DV7 
DU6 
DV3 
DT5 
DN4 
DM3 
DK3 
DG4 
DE4 
DE2 
DC2 
DA2 
DT15 
DV15 
DY13 
DU12 
DP13 
DR12 
DN10 
DK11 
DJ8 
DF9 
DD9 
DA10 
DB9 
CU8 
DU16 
DY15 
DV13 
DT13 
DT11 
DP11 
DM11 
DM9 
DK9 
DH9 
DE10 
DC10 
DC8 
DA8 
CW8 
6
P3E_CPU0_PE1_PCH_TXN<15:8> 
P3E_CPU0_PE1_PCH_TXP<15:8> 
DW14 
14 
DB1 
4
CY7 
P3E_CPU0_PE1_PCH_RXP<15:8> 
P3E_CPU0_PE1_PCH_RXN<15:8> 
107 
107 107 
107 
105 244 
105 244 
105 244 
105 244 
DESIGN NOTE: 
DO NOT SCALE DRAWING SHEET 
B
AA
B
B
SIZE 
SCALE: 
234
1234
DEPARTMENT CODE 
1
DOCUMENT NUMBER REV 
IN 
IN OUT 
OUT 
OUT 
OUT 
IN 
IN 
30 OF 270 
Wed Feb 08 16:34:35 2017 
PE1_TX_DP<0> PE1_TX_DP<1> PE1_TX_DP<2> 
PE1_TX_DP<3> 
PE1_TX_DP<4> PE1_TX_DP<5> PE1_TX_DP<6> PE1_TX_DP<7> 
PE1_TX_DP<8> PE1_TX_DP<9> PE1_TX_DP<10> PE1_TX_DP<11> 
PE1_TX_DP<12> PE1_TX_DP<13> PE1_TX_DP<14> PE1_TX_DP<15> 
PE1_TX_DN<0> PE1_TX_DN<1> PE1_TX_DN<2> PE1_TX_DN<3> 
PE1_TX_DN<4> PE1_TX_DN<5> PE1_TX_DN<6> PE1_TX_DN<7> 
PE1_TX_DN<8> 
PE1_TX_DN<9> PE1_TX_DN<10> PE1_TX_DN<11> 
PE1_TX_DN<12> PE1_TX_DN<13> PE1_TX_DN<14> PE1_TX_DN<15> 
PE1_RX_DP<0> PE1_RX_DP<1> PE1_RX_DP<2> 
PE1_RX_DP<3> 
PE1_RX_DP<4> PE1_RX_DP<5> PE1_RX_DP<6> PE1_RX_DP<7> 
PE1_RX_DP<8> PE1_RX_DP<9> PE1_RX_DP<10> PE1_RX_DP<11> 
PE1_RX_DP<12> PE1_RX_DP<13> PE1_RX_DP<14> PE1_RX_DP<15> 
PE1_RX_DN<0> PE1_RX_DN<1> PE1_RX_DN<2> PE1_RX_DN<3> 
PE1_RX_DN<4> PE1_RX_DN<5> PE1_RX_DN<6> PE1_RX_DN<7> 
PE1_RX_DN<8> 
PE1_RX_DN<9> PE1_RX_DN<10> PE1_RX_DN<11> 
PE1_RX_DN<12> PE1_RX_DN<13> PE1_RX_DN<14> PE1_RX_DN<15> 
PCH PCIEUP/SS STEERING OPTION 
TO: 
PCH PCIEUP/SS STEERING OPTION TO: 
PCH PCIEUP/SS STEERING OPTION 
PCH PCIEUP/SS STEERING OPTION 
TO: 
TO: 
SKYLAKE - SKT0 - 10 OF 21 
CPU SYMBOLS 1-30 ARE PRELIMINARY AND SUBJECT TO CHANGE 
SKYLAKE - SKT0 - 10 OF 21 
SKX_EXT_B 
INA
ILER
RY
P
M
ROOM=CPU0 
BOM_COST=PROC_SOCKET 
WIWYNN CORPORATION 
10/30 



P3E_CPU0_PE2_SS_RXP<15:0> 
P3E_CPU0_PE2_SS_RXN<15:0> P3E_CPU0_PE2_SS_TXP<15:0> 
P3E_CPU0_PE2_SS_TXN<15:0> 
10 
9
11 
11 
12 
13 
14 
15 
12 
13 
3
14 
15 
8
9
10 
8
9
10 
11 
11 
12 
13 
15 
14 
12 
14 
15 
13 
0
3
6
5
2
7
6
7
5
4
4
3
2
1
3
1
2
1
0
00
6
5
7
5
7
6
4
4
2
CT9 
CP9 
CP7 
CM7 
CK7 
CG8 
CE6 
CE8 
BY9 
BY7 
BV7 
BT7 
BR8 
BN8 
BL8 
BK9 
CR8 
CM9 
CN8 
CL6 
CH7 
CF7 
CD7 
CC8 
BV9 
BW8 
BU6 
BP7 
BP9 
BM7 
BJ8 
BJ10 
CY3 
CV3 
CT1 
CT3 
CM1 
CL2 
CG2 
CF3 
CC2 
CB3 
CA4 
BW4 
BU4 
BP5 
BL4 
BM5 
CW4 
CU2 
CR2 
CP3 
CK1 
CK3 
CE2 
CE4 
CD3 
BY3 
BY5 
BV3 
BR4 
BN4 
BM3 
BK5 
IC 
TBD 
U5D1 
8
9
10 
8
1
109 245 
109 245 105 
105 
DESIGN NOTE: 
DO NOT SCALE DRAWING SHEET 
B
AA
B
B
SIZE 
SCALE: 
234
1234
DEPARTMENT CODE 
1
DOCUMENT NUMBER REV 
OUT 
OUT IN 
IN 
31 OF 270 
Wed Feb 08 16:34:35 2017 
PE2_TX_DP<0> PE2_TX_DP<1> 
PE2_TX_DP<2> PE2_TX_DP<3> 
PE2_TX_DP<4> PE2_TX_DP<5> PE2_TX_DP<6> PE2_TX_DP<7> 
PE2_TX_DP<8> PE2_TX_DP<9> PE2_TX_DP<10> PE2_TX_DP<11> 
PE2_TX_DP<12> PE2_TX_DP<13> PE2_TX_DP<14> PE2_TX_DP<15> 
PE2_TX_DN<0> PE2_TX_DN<1> PE2_TX_DN<2> PE2_TX_DN<3> 
PE2_TX_DN<4> PE2_TX_DN<5> PE2_TX_DN<6> PE2_TX_DN<7> 
PE2_TX_DN<8> PE2_TX_DN<9> PE2_TX_DN<10> PE2_TX_DN<11> 
PE2_TX_DN<12> PE2_TX_DN<13> PE2_TX_DN<14> 
PE2_TX_DN<15> 
PE2_RX_DP<0> PE2_RX_DP<1> 
PE2_RX_DP<2> PE2_RX_DP<3> 
PE2_RX_DP<4> PE2_RX_DP<5> PE2_RX_DP<6> PE2_RX_DP<7> 
PE2_RX_DP<8> PE2_RX_DP<9> PE2_RX_DP<10> PE2_RX_DP<11> 
PE2_RX_DP<12> PE2_RX_DP<13> PE2_RX_DP<14> PE2_RX_DP<15> 
PE2_RX_DN<0> PE2_RX_DN<1> PE2_RX_DN<2> PE2_RX_DN<3> 
PE2_RX_DN<4> PE2_RX_DN<5> PE2_RX_DN<6> PE2_RX_DN<7> 
PE2_RX_DN<8> PE2_RX_DN<9> PE2_RX_DN<10> PE2_RX_DN<11> 
PE2_RX_DN<12> PE2_RX_DN<13> PE2_RX_DN<14> 
PE2_RX_DN<15> 
TO X24 SUPER SLOT 
SKYLAKE - SKT0 - 11 OF 21 
FROM X24 SUPER SLOT 
CPU SYMBOLS 1-30 ARE PRELIMINARY AND SUBJECT TO CHANGE 
SKYLAKE - SKT0 - 11 OF 21 
SKX_EXT_B 
INA
ILER
RY
P
M
ROOM=CPU0 
BOM_COST=PROC_SOCKET 
WIWYNN CORPORATION 
11/30 



DH5 
DL14 
15 
DL6 
13 
11 
DT9 
DP7 
P3E_CPU0_PE3_OCP_RXP<15:0> 
P3E_CPU0_PE3_OCP_RXN<15:0> 
P3E_CPU0_PE3_OCP_TXP<15:0> 
P3E_CPU0_PE3_OCP_TXN<15:0> 
2
EA18 
DW18 
DW16 
DT19 
DR16 
DR14 
DN14 
DL12 
DJ12 
DG12 
DG10 
DD13 
DB11 
CY11 
CV9 
DY17 
DU18 
DV17 
DR18 
DN16 
DP15 
DM13 
DJ14 
DK13 
DH11 
DE12 
DF11 
DC12 
DA12 
CW10 
CU10 
EE14 
EE12 
EC12 
DY11 
EB9 
DW10 
DU8 
DR8 
DM7 
DP5 
DJ4 
DJ6 
DD5 
DB5 
CY5 
EC14 
ED13 
EB11 
EA10 
DY9 
DV9 
DN6 
DM5 
DK5 
DG6 
DC6 
DA4 
CV5 
IC 
TBD 
U5D1 
4
5
6
7
4
5
6
7
1
0
14 
13 
12 
14 
12 
15 
13 
3
11 
9
10 
8
8
9
11 
10 
7
6
2
5
4
3
4
5
7
6
3
2
11
0
1
2
0
15 
14 
13 
12 
14 
15 
0
12 
11 
9
10 
8
10 
9
8
3
186 187 
186 187 
106 
106 
DESIGN NOTE: 
DO NOT SCALE DRAWING SHEET 
B
AA
B
B
SIZE 
SCALE: 
234
1234
DEPARTMENT CODE 
1
DOCUMENT NUMBER REV 
OUT 
OUT 
IN 
IN 
32 OF 270 
Wed Feb 08 16:34:35 2017 
PE3_TX_DP<0> PE3_TX_DP<1> 
PE3_TX_DP<2> PE3_TX_DP<3> 
PE3_TX_DP<4> PE3_TX_DP<5> PE3_TX_DP<6> PE3_TX_DP<7> 
PE3_TX_DP<8> PE3_TX_DP<9> PE3_TX_DP<10> PE3_TX_DP<11> 
PE3_TX_DP<12> PE3_TX_DP<13> PE3_TX_DP<14> PE3_TX_DP<15> 
PE3_TX_DN<0> PE3_TX_DN<1> PE3_TX_DN<2> PE3_TX_DN<3> 
PE3_TX_DN<4> PE3_TX_DN<5> PE3_TX_DN<6> PE3_TX_DN<7> 
PE3_TX_DN<8> PE3_TX_DN<9> PE3_TX_DN<10> PE3_TX_DN<11> 
PE3_TX_DN<12> PE3_TX_DN<13> PE3_TX_DN<14> 
PE3_TX_DN<15> 
PE3_RX_DP<0> PE3_RX_DP<1> 
PE3_RX_DP<2> PE3_RX_DP<3> 
PE3_RX_DP<4> PE3_RX_DP<5> PE3_RX_DP<6> PE3_RX_DP<7> 
PE3_RX_DP<8> PE3_RX_DP<9> PE3_RX_DP<10> PE3_RX_DP<11> 
PE3_RX_DP<12> PE3_RX_DP<13> PE3_RX_DP<14> PE3_RX_DP<15> 
PE3_RX_DN<0> PE3_RX_DN<1> PE3_RX_DN<2> PE3_RX_DN<3> 
PE3_RX_DN<4> PE3_RX_DN<5> PE3_RX_DN<6> PE3_RX_DN<7> 
PE3_RX_DN<8> PE3_RX_DN<9> PE3_RX_DN<10> PE3_RX_DN<11> 
PE3_RX_DN<12> PE3_RX_DN<13> PE3_RX_DN<14> 
PE3_RX_DN<15> 
FROM OCP TO OCP 
SKYLAKE - SKT0 - 12 OF 21 
CPU SYMBOLS 1-30 ARE PRELIMINARY AND SUBJECT TO CHANGE 
SKYLAKE - SKT0 - 12 OF 21 
SKX_EXT_B 
INA
ILER
RY
P
M
ROOM=CPU0 
BOM_COST=PROC_SOCKET 
WIWYNN CORPORATION 
12/30 



UPI_CPU1_CPU0_P0P0_DP<19..0> 
UPI_CPU1_CPU0_P0P0_DN<19..0> 
UPI_CPU0_CPU1_P0P0_DP<19..0> 
UPI_CPU0_CPU1_P0P0_DN<19..0> 
12 
U5D1 
AC10 
AA8 
AB7 
AD5 
AE6 
AG8 
AJ6 
AL6 
AK7 
AM9 
AP7 
AR8 
AU10 
BA8 
BC6 
BD7 
AW8 
AY9 
BD9 
BB11 
AB9 
AC8 
AA6 
AC6 
AG6 
AF7 
AH7 
AK5 
AM7 
AL8 
AN8 
AU8 
AT9 
AY7 
BB7 
BF7 
AV9 
BB9 
BC10 
BA10 
N2 
P1 
V3 
Y1 
AB3 
AC2 
AG4 
AE2 
AH3 
AL2 
AM3 
AN4 
AT1 
AT3 
AU4 
AV5 
BA4 
BB3 
BF3 
BG4 
M1 
T1 
Y3 
W2 
AA2 
AD1 
AF3 
AG2 
AJ2 
AK1 
AK3 
AP3 
AP1 
AR2 
AR4 
AW4 
AY3 
BC2 
BD3 
BH3 
IC 
TBD 
0
3
2
1
14 
4
5
8
6
7
9
10 
11 
13 
12 
15 
14 
15 
16 
18 
17 
19 
0
1
2
4
16 
3
5
7
6
10 
9
8
12 
11 
13 
18 
15 
14 
18 
17 
16 
19 
0
1
3
2
17 
5
4
6
8
7
9
10 
11 
14 
12 
19 
13 
16 
15 
0
18 
19 
17 
3
2
1
5
4
8
7
6
10 
9
11 
13 
67 
67 
67 
67 
DESIGN NOTE: 
DO NOT SCALE DRAWING SHEET 
B
AA
B
B
SIZE 
SCALE: 
234
1234
DEPARTMENT CODE 
1
DOCUMENT NUMBER REV 
OUT 
OUT 
IN 
IN 
33 OF 270 
Wed Feb 08 16:34:35 2017 
UPI0_TX_DP<0> UPI0_TX_DP<1> UPI0_TX_DP<2> UPI0_TX_DP<3> UPI0_TX_DP<4> UPI0_TX_DP<5> UPI0_TX_DP<6> UPI0_TX_DP<7> UPI0_TX_DP<8> UPI0_TX_DP<9> UPI0_TX_DP<10> UPI0_TX_DP<11> UPI0_TX_DP<12> 
UPI0_TX_DP<13> UPI0_TX_DP<14> UPI0_TX_DP<15> UPI0_TX_DP<16> UPI0_TX_DP<17> UPI0_TX_DP<18> UPI0_TX_DP<19> 
UPI0_TX_DN<0> UPI0_TX_DN<1> UPI0_TX_DN<2> UPI0_TX_DN<3> UPI0_TX_DN<4> UPI0_TX_DN<5> UPI0_TX_DN<6> UPI0_TX_DN<7> 
UPI0_TX_DN<8> UPI0_TX_DN<9> UPI0_TX_DN<10> UPI0_TX_DN<11> UPI0_TX_DN<12> UPI0_TX_DN<13> UPI0_TX_DN<14> UPI0_TX_DN<15> UPI0_TX_DN<16> UPI0_TX_DN<17> UPI0_TX_DN<18> UPI0_TX_DN<19> 
UPI0_RX_DP<0> UPI0_RX_DP<1> UPI0_RX_DP<2> UPI0_RX_DP<3> UPI0_RX_DP<4> UPI0_RX_DP<5> UPI0_RX_DP<6> UPI0_RX_DP<7> UPI0_RX_DP<8> UPI0_RX_DP<9> UPI0_RX_DP<10> UPI0_RX_DP<11> UPI0_RX_DP<12> 
UPI0_RX_DP<13> UPI0_RX_DP<14> UPI0_RX_DP<15> UPI0_RX_DP<16> UPI0_RX_DP<17> UPI0_RX_DP<18> UPI0_RX_DP<19> 
UPI0_RX_DN<0> UPI0_RX_DN<1> UPI0_RX_DN<2> UPI0_RX_DN<3> UPI0_RX_DN<4> UPI0_RX_DN<5> UPI0_RX_DN<6> UPI0_RX_DN<7> 
UPI0_RX_DN<8> UPI0_RX_DN<9> UPI0_RX_DN<10> UPI0_RX_DN<11> UPI0_RX_DN<12> UPI0_RX_DN<13> UPI0_RX_DN<14> UPI0_RX_DN<15> UPI0_RX_DN<16> UPI0_RX_DN<17> UPI0_RX_DN<18> UPI0_RX_DN<19> 
SKYLAKE - SKT0 - 13 OF 21 
CPU SYMBOLS 1-30 ARE PRELIMINARY AND SUBJECT TO CHANGE 
SKYLAKE - SKT0 - 13 OF 21 
SKX_EXT_B 
INA
ILER
RY
P
M
BOM_COST=PROC_SOCKET 
ROOM=CPU0 
WIWYNN CORPORATION 
13/30 



UPI_CPU1_CPU0_P1P1_DP<19..0> 
UPI_CPU1_CPU0_P1P1_DN<19..0> 
UPI_CPU0_CPU1_P1P1_DP<19..0> 
UPI_CPU0_CPU1_P1P1_DN<19..0> 
13 
P13 
T5 
P7 
V7 
T9 
P9 
R10 
U12 
L12 
N14 
R12 
R16 
P17 
U16 
W18 
R20 
U18 
P21 
V19 
Y21 
AB19 
R6 
T7 
U8 
R8 
N10 
U10 
T11 
N12 
M13 
T15 
N16 
W16 
V17 
P19 
T19 
T21 
Y19 
W20 
AA20 
M3 
L4 
K5 
J6 
G6 
H7 
K9 
D9 
F11 
G10 
E12 
G14 
D15 
F15 
H17 
K19 
G18 
J20 
F21 
P3 
K3 
M5 
H5 
F7 
K7 
J8 
F9 
E10 
H9 
F13 
E14 
H15 
G16 
L18 
J18 
H19 
G20 
K21 
IC 
TBD 
U5D1 
H21 
G12 
0
1
3
2
4
5
6
8
7
9
10 
11 
12 
13 
15 
14 
15 
16 
17 
18 
19 
0
1
2
3
16 
4
5
6
7
8
9
10 
11 
12 
13 
17 
14 
15 
16 
17 
18 
19 
1
0
2
3
19 
4
6
5
7
8
9
11 
10 
12 
13 
18 
14 
15 
18 
17 
16 
19 
0
1
2
3
4
5
6
7
8
9
10 
11 
14 
12 
68 
68 
68 
68 
DESIGN NOTE: 
DO NOT SCALE DRAWING SHEET 
B
AA
B
B
SIZE 
SCALE: 
234
1234
DEPARTMENT CODE 
1
DOCUMENT NUMBER REV 
OUT 
OUT 
IN 
IN 
34 OF 270 
Wed Feb 08 16:34:36 2017 
UPI1_TX_DP<0> UPI1_TX_DP<1> UPI1_TX_DP<2> UPI1_TX_DP<3> UPI1_TX_DP<4> UPI1_TX_DP<5> UPI1_TX_DP<6> UPI1_TX_DP<7> UPI1_TX_DP<8> UPI1_TX_DP<9> UPI1_TX_DP<10> UPI1_TX_DP<11> UPI1_TX_DP<12> 
UPI1_TX_DP<13> UPI1_TX_DP<14> UPI1_TX_DP<15> UPI1_TX_DP<16> UPI1_TX_DP<17> UPI1_TX_DP<18> UPI1_TX_DP<19> 
UPI1_TX_DN<0> UPI1_TX_DN<1> UPI1_TX_DN<2> UPI1_TX_DN<3> UPI1_TX_DN<4> UPI1_TX_DN<5> UPI1_TX_DN<6> UPI1_TX_DN<7> 
UPI1_TX_DN<8> UPI1_TX_DN<9> UPI1_TX_DN<10> UPI1_TX_DN<11> UPI1_TX_DN<12> UPI1_TX_DN<13> UPI1_TX_DN<14> UPI1_TX_DN<15> UPI1_TX_DN<16> UPI1_TX_DN<17> UPI1_TX_DN<18> UPI1_TX_DN<19> 
UPI1_RX_DP<0> UPI1_RX_DP<1> UPI1_RX_DP<2> UPI1_RX_DP<3> UPI1_RX_DP<4> UPI1_RX_DP<5> UPI1_RX_DP<6> UPI1_RX_DP<7> UPI1_RX_DP<8> UPI1_RX_DP<9> UPI1_RX_DP<10> UPI1_RX_DP<11> UPI1_RX_DP<12> 
UPI1_RX_DP<13> UPI1_RX_DP<14> UPI1_RX_DP<15> UPI1_RX_DP<16> UPI1_RX_DP<17> UPI1_RX_DP<18> UPI1_RX_DP<19> 
UPI1_RX_DN<0> UPI1_RX_DN<1> UPI1_RX_DN<2> UPI1_RX_DN<3> UPI1_RX_DN<4> UPI1_RX_DN<5> UPI1_RX_DN<6> UPI1_RX_DN<7> 
UPI1_RX_DN<8> UPI1_RX_DN<9> UPI1_RX_DN<10> UPI1_RX_DN<11> UPI1_RX_DN<12> UPI1_RX_DN<13> UPI1_RX_DN<14> UPI1_RX_DN<15> UPI1_RX_DN<16> UPI1_RX_DN<17> UPI1_RX_DN<18> UPI1_RX_DN<19> 
SKYLAKE - SKT0 - 14 OF 21 
CPU SYMBOLS 1-30 ARE PRELIMINARY AND SUBJECT TO CHANGE 
SKYLAKE - SKT0 - 14 OF 21 
SKX_EXT_B 
INA
ILER
RY
P
M
BOM_COST=PROC_SOCKET 
ROOM=CPU0 
WIWYNN CORPORATION 
14/30 



DE16 
TP_CPU0_UPI2_RSVD_DF17 
DB19 
TP_CPU0_UPI2_RSVD_CV13 
TP_CPU0_UPI2_RSVD_CF11 
TP_CPU0_UPI2_RSVD_CC12 
TP_CPU0_UPI2_RSVD_CC10 
TP_CPU0_UPI2_RSVD_CE12 
TP_CPU0_UPI2_RSVD_CH11 
TP_CPU0_UPI2_RSVD_CF13 
TP_CPU0_UPI2_RSVD_CJ14 
TP_CPU0_UPI2_RSVD_CM13 
TP_CPU0_UPI2_RSVD_CU14 
TP_CPU0_UPI2_RSVD_CW14 
TP_CPU0_UPI2_RSVD_CA12 
TP_CPU0_UPI2_RSVD_CB11 
TP_CPU0_UPI2_RSVD_CD11 
TP_CPU0_UPI2_RSVD_CG12 
TP_CPU0_UPI2_RSVD_CH13 
TP_CPU0_UPI2_RSVD_CK13 
TP_CPU0_UPI2_RSVD_CR14 
TP_CPU0_UPI2_RSVD_CW16 
TP_CPU0_UPI2_RSVD_DB15 
TP_CPU0_UPI2_RSVD_DD15 
TP_CPU0_UPI2_RSVD_DE16 
TP_CPU0_UPI2_RSVD_DH17 
TP_CPU0_UPI2_RSVD_DJ18 
TP_CPU0_UPI2_RSVD_DJ20 
TP_CPU0_UPI2_RSVD_DK19 
TP_CPU0_UPI2_RSVD_DN20 
TP_CPU0_UPI2_RSVD_DP21 
TP_CPU0_UPI2_RSVD_DA16 
TP_CPU0_UPI2_RSVD_DC16 
TP_CPU0_UPI2_RSVD_DF15 
TP_CPU0_UPI2_RSVD_DD17 
TP_CPU0_UPI2_RSVD_DG18 
TP_CPU0_UPI2_RSVD_DK17 
TP_CPU0_UPI2_RSVD_DH19 
TP_CPU0_UPI2_RSVD_DG20 
TP_CPU0_UPI2_RSVD_DL20 
TP_CPU0_UPI2_RSVD_DM21 
TP_CPU0_UPI2_RSVD_DT21 
CY19 
DF23 
DE22 
DC22 
DB21 
DD19 
DA20 
CW20 
CV19 
CT21 
CR18 
CN20 
CP21 
CL16 
CJ18 
CH17 
CE16 
CD15 
CF17 
CB15 
BY17 
DG22 
DD21 
DA22 
DC20 
CU20 
CW18 
CR20 
CN18 
CP19 
CM21 
CJ16 
CK17 
CG16 
CF15 
CC14 
CD17 
BY15 
CA16 
DT21 
DM21 
DL20 
DG20 
DH19 
DK17 
DG18 
DD17 
DF15 
DC16 
DA16 
CW14 
CU14 
CM13 
CJ14 
CF13 
CH11 
CE12 
CC10 
CC12 
DP21 
DN20 
DK19 
DJ20 
DJ18 
DH17 
DF17 
DD15 
DB15 
CW16 
CV13 
CR14 
CK13 
CH13 
CG12 
CF11 
CD11 
CB11 
CA12 
IC 
TBD 
U5D1 
DESIGN NOTE: 
DO NOT SCALE DRAWING SHEET 
B
AA
B
B
SIZE 
SCALE: 
234
1234
DEPARTMENT CODE 
1
DOCUMENT NUMBER REV 
35 OF 270 
Wed Feb 08 16:34:36 2017 
UPI2_TX_DP<0> UPI2_TX_DP<1> UPI2_TX_DP<2> UPI2_TX_DP<3> UPI2_TX_DP<4> UPI2_TX_DP<5> UPI2_TX_DP<6> UPI2_TX_DP<7> UPI2_TX_DP<8> UPI2_TX_DP<9> UPI2_TX_DP<10> UPI2_TX_DP<11> 
UPI2_TX_DP<12> UPI2_TX_DP<13> UPI2_TX_DP<14> UPI2_TX_DP<15> UPI2_TX_DP<16> UPI2_TX_DP<17> UPI2_TX_DP<18> UPI2_TX_DP<19> 
UPI2_TX_DN<0> UPI2_TX_DN<1> UPI2_TX_DN<2> UPI2_TX_DN<3> UPI2_TX_DN<4> UPI2_TX_DN<5> UPI2_TX_DN<6> 
UPI2_TX_DN<7> UPI2_TX_DN<8> UPI2_TX_DN<9> UPI2_TX_DN<10> UPI2_TX_DN<11> UPI2_TX_DN<12> UPI2_TX_DN<13> UPI2_TX_DN<14> UPI2_TX_DN<15> UPI2_TX_DN<16> UPI2_TX_DN<17> UPI2_TX_DN<18> UPI2_TX_DN<19> 
UPI2_RX_DP<0> UPI2_RX_DP<1> UPI2_RX_DP<2> UPI2_RX_DP<3> UPI2_RX_DP<4> UPI2_RX_DP<5> UPI2_RX_DP<6> UPI2_RX_DP<7> UPI2_RX_DP<8> UPI2_RX_DP<9> UPI2_RX_DP<10> UPI2_RX_DP<11> 
UPI2_RX_DP<12> UPI2_RX_DP<13> UPI2_RX_DP<14> UPI2_RX_DP<15> UPI2_RX_DP<16> UPI2_RX_DP<17> UPI2_RX_DP<18> UPI2_RX_DP<19> 
UPI2_RX_DN<0> UPI2_RX_DN<1> UPI2_RX_DN<2> UPI2_RX_DN<3> UPI2_RX_DN<4> UPI2_RX_DN<5> UPI2_RX_DN<6> 
UPI2_RX_DN<7> UPI2_RX_DN<8> UPI2_RX_DN<9> UPI2_RX_DN<10> UPI2_RX_DN<11> UPI2_RX_DN<12> UPI2_RX_DN<13> UPI2_RX_DN<14> UPI2_RX_DN<15> UPI2_RX_DN<16> UPI2_RX_DN<17> UPI2_RX_DN<18> UPI2_RX_DN<19> 
SKYLAKE - SKT0 - 15 OF 21 
CPU SYMBOLS 1-30 ARE PRELIMINARY AND SUBJECT TO CHANGE 
SKYLAKE - SKT0 - 15 OF 21 
SKX_EXT_B 
BOM_COST=PROC_SOCKET 
ROOM=CPU0 
WIWYNN CORPORATION 
15/30 



PVCCMCP_CPU0 
CC20 
TP_CPU0_RSVD_91 
TP_CPU0_RSVD_90 
TP_CPU0_RSVD_85 
TP_CPU0_TEST_10 
TP_CPU0_TEST_6 
TP_CPU0_TEST_7 
TP_CPU0_TEST_8 
TP_CPU0_TEST_9 
TP_CPU0_RSVD_123 
TP_CPU0_RSVD_121 
TP_CPU0_RSVD_119 
TP_CPU0_RSVD_117 
TP_CPU0_RSVD_114 
TP_CPU0_RSVD_111 
TP_CPU0_RSVD_108 
TP_CPU0_RSVD_106 
TP_CPU0_RSVD_105 
TP_CPU0_RSVD_101 
TP_CPU0_RSVD_100 
TP_CPU0_RSVD_99 
TP_CPU0_RSVD_97 
TP_CPU0_RSVD_95 
TP_CPU0_RSVD_94 
TP_CPU0_RSVD_255 
CLK_100M_CPU0_RC_REFCLK1_DN 
TP_CPU0_RSVD_171 
TP_CPU0_RSVD_170 
TP_CPU0_RSVD_169 
TP_CPU0_RSVD_168 
TP_CPU0_RSVD_167 
TP_CPU0_RSVD_166 
TP_CPU0_RSVD_164 
TP_CPU0_RSVD_163 
TP_CPU0_RSVD_162 
TP_CPU0_RSVD_161 
TP_CPU0_RSVD_160 
TP_CPU0_RSVD_159 
TP_CPU0_RSVD_158 
TP_CPU0_RSVD_157 
TP_CPU0_RSVD_156 
TP_CPU0_RSVD_155 
TP_CPU0_RSVD_113 
TP_CPU0_RSVD_82 
TP_CPU0_RSVD_124 
TP_CPU0_RSVD_151 
TP_CPU0_RSVD_152 
TP_CPU0_RSVD_145 
TP_CPU0_RSVD_146 
TP_CPU0_RSVD_147 
TP_CPU0_RSVD_148 
TP_CPU0_RSVD_149 
TP_CPU0_RSVD_154 
CLK_100M_CPU0_RC_REFCLK1_DP 
TP_CPU0_RSVD_150 
TP_CPU0_RSVD_144 
PVCCIOMCP_CPU0 
CL24 
CK77 
CK25 
CK23 
CK19 
CJ26 
CJ24 
CJ22 
CJ20 
CH77 
CH25 
AR16 
AU18 
AW16 
AW20 
AW22 
IC 
TBD 
U5D1 
CB25 
CH23 
CH21 
CG82 
CG78 
CG26 
CG24 
CG20 
CG10 
CF81 
CF79 
CF23 
CF21 
CF19 
CE80 
CE78 
CE22 
CD25 
CD21 
CD19 
CC6 
CB5 
CB21 
CB19 
CA24 
CA22 
BY25 
BY19 
BW22 
BW20 
BW10 
BV23 
BV21 
BV19 
BU22 
BJ20 
BG18 
BF21 
BE20 
BD19 
BD17 
BC68 
BC66 
BC64 
BC22 
BC20 
BC18 
BC14 
BB67 
BB65 
BB25 
BB21 
BB17 
BB15 
BB13 
BA82 
BA78 
AY83 
IC 
TBD 
U5D1 
BE22 
BP21 
BJ18 
BJ16 
BH19 
BG20 
BK17 
BL18 
BL20 
BE18 
BD69 
BD67 
BD65 
BD25 
BM17 
BM19 
BN18 
BP17 
BR22 
BR24 
BU20 
BU18 
PVCCMCP_CPU0 
PVCCMCP_CPU0 
103 
103 
DESIGN NOTE: 
DESIGN NOTE: 
DESIGN NOTE: 
DO NOT SCALE DRAWING SHEET 
B
AA
B
B
SIZE 
SCALE: 
234
1234
DEPARTMENT CODE 
1
DOCUMENT NUMBER REV 
IN 
IN 
36 OF 270 
Wed Feb 08 16:34:36 2017 
TEST_9 TEST_8 TEST_7 TEST_6 
TEST_10 
RSVD<81> RSVD<82> RSVD<83> RSVD<84> RSVD<85> RSVD<86> RSVD<87> RSVD<88> 
RSVD<89> 
RSVD<90> RSVD<91> 
RSVD<92> RSVD<93> RSVD<94> RSVD<95> RSVD<96> RSVD<97> RSVD<98> RSVD<99> RSVD<100> RSVD<101> RSVD<102> RSVD<103> RSVD<104> 
RSVD<105> RSVD<106> RSVD<107> RSVD<108> RSVD<109> RSVD<110> RSVD<111> RSVD<112> RSVD<113> RSVD<114> RSVD<115> RSVD<116> RSVD<117> 
RSVD<118> RSVD<119> RSVD<120> RSVD<121> RSVD<122> RSVD<123> RSVD<124> RSVD<125> RSVD<126> 
RSVD<127> RSVD<128> RSVD<129> RSVD<130> RSVD<131> RSVD<132> RSVD<133> RSVD<134> RSVD<135> RSVD<136> 
RSVD<137> RSVD<138> RSVD<139> RSVD<140> RSVD<141> RSVD<142> RSVD<143> RSVD<144> RSVD<145> RSVD<146> RSVD<147> RSVD<148> RSVD<149> 
RSVD<150> RSVD<151> RSVD<152> RSVD<153> RSVD<154> RSVD<155> RSVD<156> RSVD<157> RSVD<158> RSVD<159> RSVD<160> RSVD<161> RSVD<162> 
RSVD<163> RSVD<164> RSVD<165> RSVD<166> RSVD<167> RSVD<168> RSVD<169> RSVD<170> RSVD<171> 
RSVD<255> 
SKYLAKE - SKT0 - 16 OF 21 
CPU SYMBOLS 1-30 ARE PRELIMINARY AND SUBJECT TO CHANGE 
MCP CLK IS USED FOR DEBUG ONLY 
CPU SYMBOLS 1-30 ARE PRELIMINARY AND SUBJECT TO CHANGE 
SKYLAKE - SKT0 - 16 OF 21 
SKX_EXT_B 
SKX_EXT_B 
BOM_COST=PROC_SOCKET 
ROOM=CPU0 
WIWYNN CORPORATION 
17/30 
16/30 



BG60 
1% 
AF43 
BJ62 
CA76 
VSENSE_PMAX_CPU0 
VSENSE_VCCINR2PMAX_CPU0 
VSENSE_PVCCIN_CPU0_SKT_VRTN 
VSENSE_PVCCIN_CPU0_SKT_VSEN 
EMPTY 
1/16W 
1
1% 
2
0402 
G21796-066 
10.0 
R5D6 
CA60 
CA62 
U5D1 
IC 
BN80 
BN82 
BN84 CA72 
CA80 
CA78 
CA74 
CA82 
CB77 
CB75 
CB73 
CB61 
CA84 
CC62 
CC60 
CB83 
CB81 
CB79 
CE60 
CD85 
CD83 
CD61 
CC84 
CG84 
CG60 
CF85 
CF61 
CE84 
CK61 
CK59 
CJ60 
CH85 
CH61 
CL58 
CN56 
CM59 
CM57 
CL60 
CN58 
CR34 
CP57 
CP55 
CP33 
CR54 
CT41 
CT39 
CT37 
CR56 
CT53 
CU42 
CU40 
CU38 
CT55 
CW50 
CW46 
CV51 
CU54 
AV85 
CY47 
CY49 
BA86 
AW86 
AD41 
AY85 
BP67 
BP65 
BP63 
BP61 
BP69 
BP79 
BP77 
BP75 
BP73 
BP71 
BR84 
BR62 
BR60 
BP83 
BP81 
BT69 
BT67 
BT65 
BT63 
BT61 
BT79 
BT77 
BT75 
BT73 
BT71 
BU64 
BU62 
BU60 
BT83 
BT81 
BU66 
BU74 
BU72 
BU70 
BU68 
BU76 
BU84 
BU82 
BU80 
BU78 
BV61 
TBD 
BV69 
BV67 
BV65 
BV63 
BV71 
BV79 
BV77 
BV75 
BV73 
BV81 
BW66 
BW64 
BW62 
BW60 
BV83 
BY73 
BY61 
BW84 
BW70 
BW68 
BY75 
BY77 
BY79 
BY81 
BY83 
CW48 
CU52 
BG62 
U5D1 
IC 
AG38 
AG40 BG64 
BG66 
BG68 
BG70 
BG84 
BH61 
BH63 
BH65 
BH67 
BH69 
BH71 
BH73 
BH75 
BH77 
BH79 
BH81 
BH83 
BJ60 
BJ64 
BJ66 
BJ68 
BJ70 
BJ72 
BJ74 
BJ76 
BJ78 
BJ80 
BJ82 
BJ84 
BK61 
BK63 
BK65 
BK67 
BK69 
BK71 
BK73 
BK75 
BK77 
BK79 
BK81 
BK83 
BL60 
BL62 
BL84 
BM61 
BM63 
BM65 
BM67 
BM69 
BM71 
BM73 
BM75 
BM77 
BM79 
BM81 
BM83 
BN60 
BN62 
BN64 
BN66 
BN68 
BN70 
BN72 
BN74 
BN76 
BN78 
AG42 
AH37 
AH39 
AH41 
AJ36 
AK35 
AK45 
AK47 
AK49 
AK51 
AK53 
AL34 
AL46 
AL48 
AL50 
AL52 
AL54 
AM33 
AM53 
AM55 
AN32 
AN54 
AN56 
AP55 
AP57 
AR56 
AR58 
AT57 
AT59 
AU58 
AU60 
AV59 
AV61 
AW60 
AY61 
BA60 
BB61 
BB85 
BC60 
BC62 
BC84 
BD61 
BD73 
BD75 
BD77 
BD79 
BD81 
BD83 
BD85 
BE60 
BE62 
BE72 
BE74 
BE76 
BE78 
BE80 
BE82 
BE84 
BF61 
BF73 
BF75 
TBD 
BF77 
BF79 
BF81 
BF83 
BF85 
0603 
100.0K 
R5P1 
1
2
G22026-050 
CHIP 
1/10W 
R5D5 
G85996-031 
249 
0.1% 
0402 
CHIP 
1/16W 
1
2
204 
204 
DESIGN NOTE: 
DO NOT SCALE DRAWING SHEET 
B
AA
B
B
SIZE 
SCALE: 
234
1234
DEPARTMENT CODE 
1
DOCUMENT NUMBER REV 
PVCCIO_CPU0 
PVCCIN_CPU0 
PVCCIN_CPU0 PVCCIN_CPU0 
OUT 
OUT 
PVCCIN_CPU0 
PVCCIN_CPU0 
37 OF 270 
Wed Feb 08 16:34:36 2017 
VSS_VCCIN_SENSE 
VSENSEPMAX 
VCCIN_SENSE 
VCCINPMAX<0> 
VCCINPMAX<1> 
VCCIN<0> VCCIN<1> VCCIN<2> 
VCCIN<3> VCCIN<4> VCCIN<5> VCCIN<6> VCCIN<7> VCCIN<8> VCCIN<9> VCCIN<10> VCCIN<11> VCCIN<12> VCCIN<13> VCCIN<14> VCCIN<15> 
VCCIN<16> VCCIN<17> VCCIN<18> VCCIN<19> VCCIN<20> VCCIN<21> VCCIN<22> VCCIN<23> VCCIN<24> VCCIN<25> VCCIN<26> VCCIN<27> VCCIN<28> 
VCCIN<29> VCCIN<30> VCCIN<31> VCCIN<32> VCCIN<33> VCCIN<34> VCCIN<35> VCCIN<36> VCCIN<37> VCCIN<38> VCCIN<39> VCCIN<40> VCCIN<41> 
VCCIN<42> VCCIN<43> VCCIN<44> VCCIN<45> VCCIN<46> VCCIN<47> VCCIN<48> VCCIN<49> VCCIN<50> VCCIN<51> VCCIN<52> VCCIN<53> 
VCCIN<54> VCCIN<55> VCCIN<56> VCCIN<57> VCCIN<58> VCCIN<59> VCCIN<60> 
VCCIN<61> VCCIN<62> VCCIN<63> VCCIN<64> VCCIN<65> VCCIN<66> VCCIN<67> VCCIN<68> VCCIN<69> VCCIN<70> VCCIN<71> 
VCCIN<72> VCCIN<73> VCCIN<74> VCCIN<75> VCCIN<76> VCCIN<77> VCCIN<78> VCCIN<79> VCCIN<80> VCCIN<81> VCCIN<82> VCCIN<83> VCCIN<84> 
VCCIN<85> VCCIN<86> VCCIN<87> VCCIN<88> VCCIN<89> VCCIN<90> VCCIN<91> VCCIN<92> VCCIN<93> VCCIN<94> VCCIN<95> VCCIN<96> VCCIN<97> 
VCCIN<98> VCCIN<99> VCCIN<100> VCCIN<101> VCCIN<102> VCCIN<103> VCCIN<104> VCCIN<105> VCCIN<106> VCCIN<107> VCCIN<108> VCCIN<109> VCCIN<110> 
VCCIN<111> VCCIN<112> VCCIN<113> VCCIN<114> VCCIN<115> VCCIN<116> VCCIN<117> VCCIN<118> VCCIN<119> VCCIN<120> VCCIN<121> VCCIN<122> 
VCCIN<123> VCCIN<124> VCCIN<125> VCCIN<126> VCCIN<127> VCCIN<128> VCCIN<129> 
VCCIN<130> VCCIN<131> VCCIN<132> VCCIN<133> VCCIN<134> VCCIN<135> VCCIN<136> VCCIN<137> VCCIN<138> VCCIN<139> VCCIN<140> 
VCCIN<141> VCCIN<142> VCCIN<143> VCCIN<144> VCCIN<145> VCCIN<146> VCCIN<147> VCCIN<148> VCCIN<149> VCCIN<150> VCCIN<151> VCCIN<152> VCCIN<153> 
VCCIN<154> VCCIN<155> VCCIN<156> VCCIN<157> VCCIN<158> VCCIN<159> VCCIN<160> VCCIN<161> VCCIN<162> VCCIN<163> VCCIN<164> VCCIN<165> VCCIN<166> 
VCCIN<167> VCCIN<168> VCCIN<169> VCCIN<170> VCCIN<171> VCCIN<172> VCCIN<173> VCCIN<174> VCCIN<175> VCCIN<176> VCCIN<177> VCCIN<178> VCCIN<179> 
VCCIN<180> VCCIN<181> VCCIN<182> VCCIN<183> VCCIN<184> VCCIN<185> VCCIN<186> VCCIN<187> VCCIN<188> VCCIN<189> VCCIN<190> VCCIN<191> 
VCCIN<192> VCCIN<193> VCCIN<194> VCCIN<195> VCCIN<196> VCCIN<197> VCCIN<198> 
VCCIN<199> VCCIN<200> VCCIN<201> VCCIN<202> VCCIN<203> VCCIN<204> VCCIN<205> VCCIN<206> VCCIN<207> VCCIN<208> VCCIN<209> 
VCCIN<210> VCCIN<211> VCCIN<212> VCCIN<213> VCCIN<214> VCCIN<215> VCCIN<216> VCCIN<217> VCCIN<218> VCCIN<219> VCCIN<220> VCCIN<221> VCCIN<222> 
VCCIN<223> VCCIN<224> VCCIN<225> VCCIN<226> VCCIN<227> VCCIN<228> VCCIN<229> VCCIN<230> VCCIN<231> VCCIN<232> VCCIN<233> VCCIN<234> VCCIN<235> 
VCCIN<236> VCCIN<237> VCCIN<238> VCCIN<239> VCCIN<240> VCCIN<241> VCCIN<242> VCCIN<243> VCCIN<244> VCCIN<245> VCCIN<246> VCCIN<247> VCCIN<248> 
VCCIN<249> VCCIN<250> VCCIN<251> VCCIN<252> VCCIN<253> VCCIN<254> VCCIN<255> VCCIN<256> VCCIN<257> VCCIN<258> VCCIN<259> VCCIN<260> 
VCCIN<261> VCCIN<262> VCCIN<263> VCCIN<264> VCCIN<265> VCCIN<266> VCCIN<267> 
SKYLAKE - SKT0 - 17 OF 21 
CPU SYMBOLS 1-30 ARE PRELIMINARY AND SUBJECT TO CHANGE 
SKYLAKE - SKT0 - 17 OF 21 
ROOM=CPU0 
BOM_COST=PROC_SOCKET 
SKX_EXT_B SKX_EXT_B 
INA
ILER
RY
P
M
WIWYNN CORPORATION 
19/30 18/30 



CC26 
DH63 
1
M21 
EF53 
A12 
AC36 
P1V8_MCP_CPU0 
BA24 
BL14 
BK15 
BK13 
BJ14 
BJ12 
BH13 
BG14 
BG12 
BF13 
BF11 
BE14 
BE12 
BD13 
BT27 
BU26 
BV27 
BY27 
BV15 
BV13 
BV11 
BU14 
BU12 
BT15 
BT13 
BT11 
BR14 
BR12 
BP13 
BP11 
BN14 
BN12 
BM11 
B11 
A10 
A8 
CY55 
CM15 
CL12 
CK5 
CV7 
CH9 
D7 
CE18 
CD9 
CB17 
CB13 
BP25 
BJ24 
BF23 
DA14 
BB5 
AY11 
AW6 
AT11 
DD7 
AN10 
DF13 
AH9 
AC4 
AC20 
AA10 
W6 
W4 
DF21 
U14 
T3 
P5 
M11 
DG8 
DH7 
L16 
L14 
J10 
H13 
DJ16 
DM17 
DN8 
DP19 
DR10 
DR2 
DU20 
EA12 
EB15 
J2 
K15 
M7 
M9 
N18 
W10 
BC26 
BB27 
BA26 
AY27 
AW26 
AV27 
CF27 
CD27 
CJ28 
CH27 
BM27 
BL26 
BK27 
BK25 
BJ26 
BH27 
BH25 
BG26 
BF27 
AE36 
AD37 
AF35 
AD35 
AE34 
AG34 
AM29 
AL28 
AR28 
CJ66 
CJ64 
CH75 
CH65 
CG74 
CG66 
CG64 
CF75 
CF73 
CF67 
CF65 
CE74 
CE72 
CE68 
CE66 
CE64 
CD71 
CD69 
CD67 
CD65 
CC70 
CC68 
CC66 
CB69 
CB67 
CB65 
IC 
TBD 
U5D1 
BP15 
U5D1 
DH61 
B49 
B53 
B59 
E46 
E48 
E50 
E52 
E54 
E56 
E58 
E60 
E62 
E64 
L46 
L48 
L50 
L52 
L54 
L56 
L58 
L60 
L62 
N64 
U46 
U48 
U50 
U52 
U54 
U56 
U58 
U60 
U62 
W64 
Y45 
Y47 
Y49 
Y51 
Y53 
Y55 
Y57 
Y59 
Y61 
Y63 
AD45 
AF55 
AF57 
AF59 
AF61 
AF63 
D45 
C46 
B47 
EF59 
EF49 
EC62 
EC60 
EC58 
EC56 
EC54 
EC52 
EC50 
EC48 
EC46 
DU64 
DU62 
DU60 
DU58 
DU56 
DU54 
DU52 
DU50 
DU48 
DU46 
DL62 
DL60 
DL58 
DL56 
DL54 
DL52 
DL50 
DL48 
DL46 
DJ64 
DH59 
DH57 
DH55 
DH53 
DH51 
DH49 
DH47 
DH45 
DD45 
DB63 
DB61 
DB59 
DB57 
DB55 
DB53 
EF45 
EE44 
IC 
TBD 
PVCCMCP_CPU0 
PVCCIOMCP_CPU0 
2 X6S 
4V 
0603LF 
20% 
10UF 
E15431-001 
C6D1 
DESIGN NOTE: 
DO NOT SCALE DRAWING SHEET 
B
AA
B
B
SIZE 
SCALE: 
234
1234
DEPARTMENT CODE 
1
DOCUMENT NUMBER REV 
P3V3_STBY 
PVPP_ABC 
PVSA_CPU0 
PVCCIO_CPU0 
PVCCIO_CPU0 
PVDDQ_DEF PVDDQ_ABC 
38 OF 270 
Wed Feb 08 16:34:37 2017 
VCCSA<0> VCCSA<1> VCCSA<2> VCCSA<3> VCCSA<4> VCCSA<5> VCCSA<6> VCCSA<7> VCCSA<8> VCCSA<9> VCCSA<10> VCCSA<11> 
VCCSA<12> VCCSA<13> VCCSA<14> VCCSA<15> VCCSA<16> VCCSA<17> VCCSA<18> VCCSA<19> VCCSA<20> VCCSA<21> VCCSA<22> VCCSA<23> VCCSA<24> 
VCCSA<25> 
VCCIO<20> VCCIO<21> VCCIO<22> VCCIO<23> 
VCCIO<24> VCCIO<25> VCCIO<26> VCCIO<27> VCCIO<28> VCCIO<29> 
VCCIO<30> VCCIO<31> VCCIO<32> VCCIO<33> VCCIO<34> VCCIO<35> VCCIO<36> VCCIO<37> VCCIO<38> 
VCCIO<39> VCCIO<40> VCCIO<41> VCCIO<42> VCCIO<43> VCCIO<44> VCCIO<45> VCCIO<46> VCCIO<47> VCCIO<48> VCCIO<49> VCCIO<50> VCCIO<51> 
VCCIO<52> VCCIO<53> VCCIO<54> VCCIO<55> VCCIO<56> VCCIO<57> VCCIO<58> VCCIO<59> VCCIO<60> VCCIO<61> VCCIO<62> VCCIO<63> VCCIO<64> 
VCCIO<65> VCCIO<66> VCCIO<67> VCCIO<68> VCCIO<69> VCCIO<70> VCCIO<71> VCCIO<72> VCCIO<73> VCCIO<74> VCCIO<75> VCCIO<76> VCCIO<77> 
VCCIO<78> VCCIO<79> VCCIO<80> VCCIO<81> VCCIO<82> VCCIO<83> VCCIO<84> VCCIO<85> VCCIO<86> VCCIO<87> VCCIO<88> VCCIO<89> VCCIO<90> 
VCCIO<91> VCCIO<92> VCCIO<93> VCCIO<94> VCCIO<95> VCCIO<96> VCCIO<97> VCCIO<98> VCCIO<99> VCCIO<100> VCCIO<101> VCCIO<102> VCCIO<103> 
VCCIO<104> 
VCC33 
CD_VPP<0> CD_VPP<1> CD_VPP<2> CD_VPP<3> 
CD_VCC_CORE<0> CD_VCC_CORE<1> CD_VCC_CORE<2> CD_VCC_CORE<3> CD_VCC_CORE<4> CD_VCC_CORE<5> CD_VCC_CORE<6> CD_VCC_CORE<7> CD_VCC_CORE<8> CD_VCC_CORE<9> CD_VCC_CORE<10> CD_VCC_CORE<11> CD_VCC_CORE<12> 
CD_VCCP<0> CD_VCCP<1> CD_VCCP<2> CD_VCCP<3> CD_VCCP<4> 
CD_VCCP<5> CD_VCCP<6> CD_VCCP<7> CD_VCCP<8> CD_VCCP<9> 
CD_VCCP<10> CD_VCCP<11> CD_VCCP<12> CD_VCCP<13> CD_VCCP<14> CD_VCCP<15> 
CD_VCCIN<0> CD_VCCIN<1> 
CD_VCCIN<2> CD_VCCIN<3> 
VCCD345<0> VCCD345<1> 
VCCD345<2> VCCD345<3> VCCD345<4> VCCD345<5> VCCD345<6> VCCD345<7> VCCD345<8> VCCD345<9> VCCD345<10> VCCD345<11> VCCD345<12> VCCD345<13> 
VCCD345<14> VCCD345<15> VCCD345<16> VCCD345<17> VCCD345<18> VCCD345<19> VCCD345<20> VCCD345<21> VCCD345<22> VCCD345<23> VCCD345<24> VCCD345<25> VCCD345<26> 
VCCD345<27> VCCD345<28> VCCD345<29> VCCD345<30> VCCD345<31> VCCD345<32> VCCD345<33> VCCD345<34> VCCD345<35> VCCD345<36> VCCD345<37> VCCD345<38> VCCD345<39> 
VCCD345<40> VCCD345<41> VCCD345<42> VCCD345<43> VCCD345<44> VCCD345<45> VCCD345<46> VCCD345<47> VCCD345<48> VCCD345<49> VCCD345<50> 
VCCD012<0> VCCD012<1> VCCD012<2> 
VCCD012<3> VCCD012<4> VCCD012<5> VCCD012<6> VCCD012<7> VCCD012<8> VCCD012<9> VCCD012<10> VCCD012<11> VCCD012<12> VCCD012<13> VCCD012<14> 
VCCD012<15> VCCD012<16> VCCD012<17> VCCD012<18> VCCD012<19> VCCD012<20> VCCD012<21> VCCD012<22> VCCD012<23> VCCD012<24> VCCD012<25> VCCD012<26> VCCD012<27> 
VCCD012<28> VCCD012<29> VCCD012<30> VCCD012<31> VCCD012<32> VCCD012<33> VCCD012<34> VCCD012<35> VCCD012<36> VCCD012<37> VCCD012<38> VCCD012<39> VCCD012<40> 
VCCD012<41> VCCD012<42> VCCD012<43> VCCD012<44> VCCD012<45> VCCD012<46> VCCD012<47> VCCD012<48> VCCD012<49> VCCD012<50> VCCD012<51> 
SKYLAKE - SKT0 - 18 OF 21 
CPU SYMBOLS 1-30 ARE PRELIMINARY AND SUBJECT TO CHANGE 
SKYLAKE - SKT0 - 18 OF 21 
SKX_EXT_B 
SKX_EXT_B 
BOM_COST=PROC_SOCKET 
ROOM=CPU0 
WIWYNN CORPORATION 
21/30 
20/30 



TP_CPU0_RSVD_48 
CP13 
AT7 
CW62 TP_CPU0_RSVD_60 
TP_CPU0_RSVD_59 
VSENSE_PVCCMCP_CPU0_SKT_VRTN BL16 
DU44 
VSENSE_PVCCIO_CPU0_SKT_VRTN 
EE16 
TP_CPU0_RSVD_57 
TP_CPU0_RSVD_56 
TP_CPU0_RSVD_55 
TP_CPU0_RSVD_54 
TP_CPU0_RSVD_53 
TP_CPU0_RSVD_51 
TP_CPU0_RSVD_50 
TP_CPU0_RSVD_49 
TP_CPU0_RSVD_47 
TP_CPU0_RSVD_46 
TP_CPU0_RSVD_45 
TP_CPU0_RSVD_44 
TP_CPU0_RSVD_42 
TP_CPU0_RSVD_41 
TP_CPU0_RSVD_40 
TP_CPU0_RSVD_39 
TP_CPU0_RSVD_38 
TP_CPU0_RSVD_37 
TP_CPU0_RSVD_36 
TP_CPU0_RSVD_35 
TP_CPU0_RSVD_31 
TP_CPU0_RSVD_30 
TP_CPU0_RSVD_29 
TP_CPU0_RSVD_28 
TP_CPU0_RSVD_27 
TP_CPU0_RSVD_26 
TP_CPU0_RSVD_25 
TP_CPU0_RSVD_24 
TP_CPU0_RSVD_23 
TP_CPU0_RSVD_22 
TP_CPU0_RSVD_21 
TP_CPU0_RSVD_20 
TP_CPU0_RSVD_19 
TP_CPU0_RSVD_18 
TP_CPU0_RSVD_17 
TP_CPU0_RSVD_16 
TP_CPU0_RSVD_15 
TP_CPU0_RSVD_14 
TP_CPU0_RSVD_12 
TP_CPU0_RSVD_11 
TP_CPU0_RSVD_10 
TP_CPU0_RSVD_9 
TP_CPU0_RSVD_8 
TP_CPU0_RSVD_7 
TP_CPU0_RSVD_6 
TP_CPU0_RSVD_5 
TP_CPU0_RSVD_4 
TP_CPU0_RSVD_3 
TP_CPU0_RSVD_2 
TP_CPU0_RSVD_1 
TP_CPU0_RSVD_0 
TP_CPU0_RSVD_43 
TP_CPU0_RSVD_13 
VSENSE_PVCCMCP_CPU0_SKT_VSEN 
TP_CPU0_KTI2_AMONV 
VSENSE_PVSA_CPU0_SKT_VSEN 
VSENSE_PVSA_CPU0_SKT_VRTN 
VSENSE_PVCCIOMCP_CPU0_SKT_VSEN 
VSENSE_PVCCIOMCP_CPU0_SKT_VRTN 
VSENSE_PVCCIO_CPU0_SKT_VSEN 
PD_CPU0_MCP01_DMON 
TP_CPU0_RSVD_73 
TP_CPU0_RSVD_72 
TP_CPU0_RSVD_70 
TP_CPU0_RSVD_69 
TP_CPU0_RSVD_67 
TP_CPU0_RSVD_66 
TP_CPU0_RSVD_64 
TP_CPU0_KTI2_DFX_DN 
TP_CPU0_RSVD_61 
TP_CPU0_RSVD_34 
TP_CPU0_RSVD_33 
TP_CPU0_RSVD_32 
BN16 
BU16 
BT17 
EF83 
EF81 
EF77 
EF47 
EE84 
EE82 
EE6 
EE46 
ED83 
ED5 
ED45 
EC84 
EC44 
EC4 
EC16 
EB85 
EB5 
EB3 
EA44 
EA4 
DY3 
DW46 
DW44 
DV71 
DV61 
DT71 
DR44 
DP65 
DP17 
DN66 
DN62 
DM67 
DL66 
DL38 
DK67 
DK65 
DK37 
DK15 
DJ66 
DJ36 
DH65 
DG64 
DG36 
DD51 
DC52 
DC46 
DA56 
DA54 
DA52 
DA40 
DA24 
CY73 
CY63 
CY57 
CY53 
CY39 
CY25 
CY23 
CW60 
CW24 
CW22 
CV69 
CV23 
CU60 
CU6 
CU24 
CT69 
CT5 
CT23 
CR60 
CP31 
CP23 
CN28 
CN24 
CM25 
CM23 
CL26 
EE10 
AE10 
AF5 
DV11 
AM5 
AT5 
BE24 
DK21 
CF5 
CG14 
CL20 
DE14 
DC18 
CY17 
CU18 
CV21 
CU12 
CN6 
BH5 
CE76 
BF5 
CG76 
IC 
TBD 
U5D1 
CN22 
PVCCMCP_CPU0 
PVCCMCP_CPU0 
PVCCMCP_CPU0 
194 
212 
194 
205 
205 
194 
194 
212 
97 
DESIGN NOTE: 
DO NOT SCALE DRAWING SHEET 
B
AA
B
B
SIZE 
SCALE: 
234
1234
DEPARTMENT CODE 
1
DOCUMENT NUMBER REV 
OUT 
OUT 
OUT 
OUT 
OUT 
OUT 
OUT 
OUT 
PVCCIO_CPU0 
IN 
39 OF 270 
Wed Feb 08 16:34:37 2017 
VSS_VCCSA_SENSE 
VSS_VCCIO_SENSE 
VCCSA_SENSE 
VCCIO_SENSE 
VCCIO<0> VCCIO<1> VCCIO<2> VCCIO<3> VCCIO<4> VCCIO<5> VCCIO<6> VCCIO<7> 
VCCIO<8> VCCIO<9> 
VCCIO<10> VCCIO<11> VCCIO<12> VCCIO<13> VCCIO<14> VCCIO<15> VCCIO<16> VCCIO<17> 
VCCIO<18> VCCIO<19> 
RSVD<0> RSVD<1> RSVD<2> RSVD<3> RSVD<4> RSVD<5> RSVD<6> RSVD<7> 
RSVD<8> RSVD<9> RSVD<10> RSVD<11> RSVD<12> RSVD<13> RSVD<14> RSVD<15> RSVD<16> RSVD<17> RSVD<18> RSVD<19> RSVD<20> 
RSVD<21> RSVD<22> RSVD<23> RSVD<24> RSVD<25> RSVD<26> RSVD<27> RSVD<28> RSVD<29> RSVD<30> RSVD<31> RSVD<32> RSVD<33> 
RSVD<34> RSVD<35> RSVD<36> RSVD<37> RSVD<38> RSVD<39> RSVD<40> RSVD<41> RSVD<42> RSVD<43> RSVD<44> RSVD<45> RSVD<46> 
RSVD<47> RSVD<48> RSVD<49> RSVD<50> RSVD<51> RSVD<52> RSVD<53> RSVD<54> RSVD<55> RSVD<56> RSVD<57> RSVD<58> 
RSVD<59> RSVD<60> 
RSVD<61> RSVD<62> RSVD<63> 
RSVD<64> RSVD<65> RSVD<66> RSVD<67> RSVD<68> RSVD<69> RSVD<70> RSVD<71> RSVD<72> RSVD<73> RSVD<74> RSVD<75> 
RSVD<76> 
RSVD<77> RSVD<78> RSVD<79> RSVD<80> 
CD_VSS_VCC_CORE_SENSE CD_VCC_CORE_SENSE 
CD_VCCP_SENSE<0> CD_VCCP_SENSE<1> 
SKYLAKE - SKT0 - 19 OF 21 
CPU SYMBOLS 1-30 ARE PRELIMINARY AND SUBJECT TO CHANGE 
SKYLAKE - SKT0 - 19 OF 21 
SKX_EXT_B 
INA
ILER
RY
P
M
ROOM=CPU0 
BOM_COST=PROC_SOCKET 
WIWYNN CORPORATION 
22/30 



AC48 
T37 
AF29 
K69 
C80 
B9 
AT63 
BG72 
BG24 
BG22 
BG10 
BG6 
BF71 
BF67 
BF65 
BF63 
BF25 
BF19 
BF17 
BF15 
BF9 
BE70 
BE68 
BE66 
BE64 
BE26 
BE10 
BE8 
BE6 
BE4 
BD71 
BD63 
BD27 
BD21 
BD15 
BD11 
BD5 
BC82 
BC80 
BC78 
BC76 
BC74 
BC72 
BC70 
BC16 
BC12 
BC8 
BC4 
BB83 
BB81 
BB79 
BB77 
BB75 
BB73 
BB69 
BB63 
BB23 
BB19 
BA84 
BA80 
BA74 
BA68 
BA62 
BA12 
BA6 
BA2 
AY81 
AY79 
AY63 
AY25 
AY23 
AY21 
AY17 
AY15 
AY5 
AW84 
AW82 
AW78 
AW74 
AW72 
AW70 
AW68 
AW66 
AW62 
AW10 
AW2 
AV83 
AV75 
AV67 
AV65 
AV63 
AV25 
AV23 
AV19 
AV13 
AV11 
AV7 
AV3 
AV1 
AU86 
AU84 
AU80 
AU78 
AU76 
AU74 
AU68 
AU64 
AU62 
AU28 
AU26 
AU6 
AU2 
AT85 
AT83 
AT77 
AT73 
AT69 
AT61 
AT27 
AT21 
AT17 
AT15 
P63 
AR78 
AR72 
AR60 
AR30 
AR24 
AR10 
AP85 
AP83 
AP81 
AP75 
AP73 
AP69 
AP67 
AP65 
AP63 
AP59 
AP31 
AP19 
AP13 
AP9 
AP5 
AN78 
AN58 
AN28 
AN6 
AN2 
AM83 
AM79 
AM73 
AM69 
AM63 
AM57 
AM31 
AC50 
AM1 
AL86 
AL82 
AL80 
AL78 
AL76 
IC 
TBD 
U5D1 
BG8 
BF69 
AG78 
AJ22 
AL68 
AL64 
AL56 
AL32 
AL30 
AL24 
AL10 
AL4 
AK85 
AK83 
AK81 
AK79 
AK73 
AK67 
AK65 
AK55 
AK33 
AK31 
AK29 
AK25 
AK23 
AK19 
AK13 
AK9 
AJ86 
AJ82 
AJ78 
AJ74 
AJ68 
AJ66 
AJ54 
AJ52 
AJ50 
AJ48 
AJ46 
AJ34 
AJ32 
AJ28 
AJ26 
AJ8 
AH83 
AH77 
AH75 
AH69 
AH65 
AH61 
AH59 
AH53 
AH51 
AH49 
AH47 
AH45 
AH35 
AH33 
AH27 
AH21 
AH5 
AH1 
AG80 
AG76 
AG74 
AG70 
AG64 
AG36 
AG18 
AG14 
AG12 
AF85 
AF83 
AF77 
AF73 
AF41 
AF39 
AF37 
AF33 
AF31 
AF27 
AF25 
AF23 
AF21 
AF9 
AC52 
AF1 
AE78 
AE70 
AE68 
AE66 
AE64 
AE42 
AE40 
AE38 
AE16 
AC54 
AE8 
AE4 
AD85 
AD83 
AD81 
AD75 
AD73 
AD71 
AD43 
AD39 
AD33 
AD27 
AD21 
AD19 
AD15 
AD13 
AD11 
AD9 
AD7 
AD3 
AC86 
AC84 
AC78 
AC72 
AC70 
AC64 
AC40 
AC38 
AC34 
AC32 
AC28 
AC26 
AC22 
AC18 
AB85 
AB83 
AB79 
AB73 
AB69 
AB65 
AB41 
AB37 
AB35 
AB31 
AB29 
AB25 
AB23 
AB21 
AB11 
AB5 
AB1 
AA82 
AA80 
AA78 
AA76 
AA68 
AA66 
AA64 
AA42 
AA36 
AA30 
AA24 
AA22 
AA18 
IC 
TBD 
U5D1 
K11 
AA16 
AA4 
Y85 
Y83 
Y81 
Y79 
Y73 
Y71 
Y9 
Y7 
Y67 
Y5 
Y17 
Y15 
W82 
W78 
W74 
W68 
W42 
W40 
W38 
W36 
W34 
W32 
W30 
W28 
W26 
W24 
W22 
W12 
AC56 
W8 
V83 
V77 
V75 
V73 
V43 
V23 
V21 
V15 
V13 
V9 
V5 
V1 
U86 
U80 
U78 
U76 
U74 
U70 
U68 
U42 
U36 
U30 
U24 
U22 
U20 
U6 
U4 
U2 
T85 
T83 
T77 
T73 
T65 
T41 
T35 
T31 
T29 
T25 
T17 
T13 
R86 
R78 
R72 
R68 
R40 
R38 
R34 
R32 
R28 
R26 
R22 
R4 
R2 
R18 
R14 
P83 
P81 
P71 
P69 
P67 
P39 
P33 
P27 
P15 
P11 
N8 
N4 
N78 
N76 
N74 
N72 
N70 
N66 
N6 
N22 
N20 
DM19 
M85 
M83 
M79 
M71 
M65 
M43 
M41 
M39 
M37 
M35 
M33 
M31 
M29 
M27 
M25 
M23 
M19 
M17 
M15 
CT7 
BT9 
L82 
L80 
L78 
L72 
L22 
L20 
L6 
L2 
L10 
K85 
K83 
K81 
K77 
K73 
K71 
K67 
K65 
K39 
K33 
K27 
DB7 
K17 
K13 
K1 
J84 
J82 
J76 
IC 
TBD 
U5D1 
G4 
J74 
J72 
J40 
J38 
J34 
J32 
J28 
J26 
J22 
J14 
J12 
J4 
DN44 
H75 
H71 
H65 
H41 
H39 
H37 
H35 
H31 
H29 
H27 
H25 
H11 
H3 
G82 
G80 
G78 
G76 
G70 
G66 
G42 
G38 
G36 
G32 
G30 
G26 
G24 
G22 
G8 
F69 
F67 
F43 
F37 
F31 
F25 
F19 
F17 
F5 
E76 
E74 
E72 
E22 
E20 
E18 
E16 
E8 
E6 
D77 
D43 
D41 
D39 
D37 
D35 
D33 
D31 
D29 
D27 
D25 
D13 
D11 
CM27 
C78 
C76 
C16 
C14 
C12 
C10 
C8 
B75 
B71 
B37 
B31 
B25 
A38 
A36 
A32 
A30 
A26 
AC58 
AC60 
AC62 
AJ4 
AR6 
CG6 
CW6 
DE48 
DE50 
DE52 
DE54 
DE56 
DE58 
DE60 
DE62 
DL8 
DN18 
DP45 
DP47 
DP49 
DP51 
DP53 
DP55 
DP57 
DP59 
DP61 
DP63 
DP9 
DV19 
DY45 
DY47 
DY49 
DY51 
DY53 
DY55 
DY57 
DY59 
DY61 
DY63 
EA14 
L8 
V11 
E66 
ED69 
EE80 
EE8 
EE40 
ED81 
ED7 
ED41 
EC82 
EC6 
EC42 
DW2 
EB83 
EA84 
DY85 
J86 
E82 
D81 
D3 
C4 
B79 
B5 
B43 
A42 
IC 
TBD 
U5D1 
H33 
DESIGN NOTE: 
DO NOT SCALE DRAWING SHEET 
B
AA
B
B
SIZE 
SCALE: 
234
1234
DEPARTMENT CODE 
1
DOCUMENT NUMBER REV 
40 OF 270 
Wed Feb 08 16:34:37 2017 
VSS<614> VSS<615> 
VSS<616> VSS<617> VSS<618> VSS<619> VSS<620> VSS<621> VSS<622> VSS<623> VSS<624> VSS<625> VSS<626> VSS<627> VSS<628> 
VSS<629> VSS<630> VSS<631> VSS<632> VSS<633> VSS<634> VSS<635> VSS<636> VSS<637> VSS<638> VSS<639> VSS<640> VSS<641> 
VSS<642> VSS<643> VSS<644> VSS<645> VSS<646> VSS<647> VSS<648> VSS<649> VSS<650> VSS<651> VSS<652> VSS<653> VSS<654> 
VSS<655> VSS<656> VSS<657> VSS<658> VSS<659> VSS<660> VSS<661> VSS<662> VSS<663> VSS<664> VSS<665> VSS<666> VSS<667> 
VSS<668> VSS<669> VSS<670> VSS<671> VSS<672> VSS<673> VSS<674> VSS<675> VSS<676> VSS<677> VSS<678> VSS<679> 
VSS<680> VSS<681> VSS<682> VSS<683> VSS<684> VSS<685> VSS<686> VSS<687> VSS<688> VSS<689> VSS<690> VSS<691> VSS<692> 
VSS<693> 
VSS<694> VSS<695> 
VSS<696> VSS<697> VSS<698> VSS<699> VSS<700> VSS<701> VSS<702> VSS<703> VSS<704> VSS<705> VSS<706> VSS<707> VSS<708> 
VSS<709> VSS<710> VSS<711> VSS<712> VSS<713> VSS<714> VSS<715> VSS<716> VSS<717> VSS<718> VSS<719> VSS<720> VSS<721> 
VSS<722> VSS<723> VSS<724> VSS<725> VSS<726> VSS<727> VSS<728> VSS<729> VSS<730> VSS<731> VSS<732> VSS<733> VSS<734> 
VSS<735> VSS<736> VSS<737> VSS<738> VSS<739> VSS<740> VSS<741> VSS<742> VSS<743> VSS<744> VSS<745> VSS<746> VSS<747> 
VSS<748> VSS<749> VSS<750> VSS<751> VSS<752> VSS<753> VSS<754> VSS<755> VSS<756> VSS<757> VSS<758> VSS<759> 
VSS<760> VSS<761> VSS<762> VSS<763> VSS<764> VSS<765> VSS<766> VSS<767> VSS<768> VSS<769> VSS<770> VSS<771> VSS<772> 
VSS<773> 
VSS<774> VSS<775> 
VSS<776> VSS<777> VSS<778> VSS<779> VSS<780> VSS<781> VSS<782> VSS<783> VSS<784> VSS<785> VSS<786> VSS<787> VSS<788> 
VSS<789> VSS<790> VSS<791> VSS<792> VSS<793> VSS<794> VSS<795> VSS<796> VSS<797> VSS<798> VSS<799> VSS<800> VSS<801> 
VSS<802> VSS<803> VSS<804> VSS<805> VSS<806> VSS<807> VSS<808> VSS<809> VSS<810> VSS<811> VSS<812> VSS<813> VSS<814> 
VSS<815> VSS<816> VSS<817> VSS<818> VSS<819> VSS<820> VSS<821> VSS<822> VSS<823> VSS<824> VSS<825> VSS<826> VSS<827> 
VSS<828> VSS<829> VSS<830> VSS<831> VSS<832> VSS<833> VSS<834> VSS<835> VSS<836> VSS<837> VSS<838> VSS<839> 
VSS<840> VSS<841> VSS<842> VSS<843> VSS<844> VSS<845> VSS<846> VSS<847> VSS<848> VSS<849> VSS<850> VSS<851> VSS<852> 
VSS<853> 
VSS<854> VSS<855> 
VSS<856> VSS<857> VSS<858> VSS<859> VSS<860> VSS<861> VSS<862> VSS<863> VSS<864> VSS<865> VSS<866> VSS<867> VSS<868> 
VSS<869> VSS<870> VSS<871> VSS<872> VSS<873> VSS<874> VSS<875> VSS<876> VSS<877> VSS<878> VSS<879> VSS<880> VSS<881> 
VSS<882> VSS<883> VSS<884> VSS<885> VSS<886> VSS<887> VSS<888> VSS<889> VSS<890> VSS<891> VSS<892> VSS<893> VSS<894> 
VSS<895> VSS<896> VSS<897> VSS<898> VSS<899> VSS<900> VSS<901> VSS<902> VSS<903> VSS<904> VSS<905> VSS<906> VSS<907> 
VSS<908> VSS<909> VSS<910> VSS<911> VSS<912> VSS<913> VSS<914> VSS<915> VSS<916> VSS<917> VSS<918> VSS<919> 
VSS<920> VSS<921> VSS<922> VSS<923> VSS<924> VSS<925> VSS<926> VSS<927> VSS<928> VSS<929> VSS<930> VSS<931> VSS<932> 
VSS<933> 
VSS<934> VSS<935> 
VSS<936> VSS<937> VSS<938> VSS<939> VSS<940> VSS<941> VSS<942> VSS<943> VSS<944> VSS<945> VSS<946> VSS<947> VSS<948> 
VSS<949> VSS<950> VSS<951> VSS<952> VSS<953> VSS<954> VSS<955> VSS<956> VSS<957> VSS<958> VSS<959> VSS<960> VSS<961> 
VSS<962> VSS<963> VSS<964> VSS<965> VSS<966> VSS<967> VSS<968> VSS<969> VSS<970> VSS<971> VSS<972> VSS<973> VSS<974> 
VSS<975> VSS<976> VSS<977> VSS<978> VSS<979> VSS<980> VSS<981> VSS<982> VSS<983> VSS<984> VSS<985> VSS<986> VSS<987> 
VSS<988> VSS<989> VSS<990> VSS<991> VSS<992> VSS<993> VSS<994> VSS<995> VSS<996> VSS<997> VSS<998> VSS<999> 
VSS<1000> VSS<1001> VSS<1002> VSS<1003> VSS<1004> VSS<1005> VSS<1006> VSS<1007> VSS<1008> VSS<1009> VSS<1010> VSS<1011> VSS<1012> 
VSS<1013> 
VSS<1014> VSS<1015> 
VSS<1016> VSS<1017> VSS<1018> VSS<1019> VSS<1020> VSS<1021> VSS<1022> VSS<1023> VSS<1024> VSS<1025> VSS<1026> VSS<1027> VSS<1028> 
VSS<1029> VSS<1030> VSS<1031> VSS<1032> VSS<1033> VSS<1034> VSS<1035> VSS<1036> VSS<1037> VSS<1038> VSS<1039> VSS<1040> VSS<1041> 
VSS<1042> VSS<1043> VSS<1044> VSS<1045> VSS<1046> VSS<1047> VSS<1048> VSS<1049> VSS<1050> VSS<1051> VSS<1052> VSS<1053> VSS<1054> 
VSS<1055> VSS<1056> VSS<1057> VSS<1058> VSS<1059> VSS<1060> VSS<1061> VSS<1062> VSS<1063> VSS<1064> VSS<1065> VSS<1066> VSS<1067> 
VSS<1068> VSS<1069> VSS<1070> VSS<1071> VSS<1072> VSS<1073> VSS<1074> VSS<1075> VSS<1076> VSS<1077> VSS<1078> VSS<1079> 
VSS<1080> VSS<1081> VSS<1082> VSS<1083> VSS<1084> VSS<1085> VSS<1086> VSS<1087> VSS<1088> VSS<1089> VSS<1090> VSS<1091> VSS<1092> 
VSS<1093> 
VSS<1094> VSS<1095> 
VSS<1096> VSS<1097> VSS<1098> VSS<1099> VSS<1100> VSS<1101> VSS<1102> VSS<1103> VSS<1104> VSS<1105> VSS<1106> VSS<1107> VSS<1108> 
VSS<1109> VSS<1110> VSS<1111> VSS<1112> VSS<1113> VSS<1114> VSS<1115> VSS<1116> VSS<1117> VSS<1118> VSS<1119> VSS<1120> VSS<1121> 
VSS<1122> VSS<1123> VSS<1124> VSS<1125> VSS<1126> VSS<1127> VSS<1128> VSS<1129> VSS<1130> VSS<1131> VSS<1132> VSS<1133> VSS<1134> 
VSS<1135> VSS<1136> VSS<1137> VSS<1138> VSS<1139> VSS<1140> VSS<1141> VSS<1142> VSS<1143> VSS<1144> VSS<1145> VSS<1146> VSS<1147> 
VSS<1148> VSS<1149> VSS<1150> VSS<1151> VSS<1152> VSS<1153> VSS<1154> VSS<1155> VSS<1156> VSS<1157> VSS<1158> VSS<1159> 
VSS<1160> VSS<1161> VSS<1162> VSS<1163> VSS<1164> VSS<1165> VSS<1166> VSS<1167> VSS<1168> VSS<1169> VSS<1170> VSS<1171> VSS<1172> 
VSS<1173> 
VSS<1174> VSS<1175> 
VSS<1176> VSS<1177> VSS<1178> VSS<1179> VSS<1180> VSS<1181> VSS<1182> VSS<1183> VSS<1184> VSS<1185> VSS<1186> VSS<1187> VSS<1188> 
VSS<1189> VSS<1190> VSS<1191> VSS<1192> VSS<1193> VSS<1194> VSS<1195> VSS<1196> VSS<1197> VSS<1198> VSS<1199> VSS<1200> VSS<1201> 
VSS<1202> VSS<1203> VSS<1204> VSS<1205> VSS<1206> VSS<1207> VSS<1208> VSS<1209> VSS<1210> VSS<1211> VSS<1212> VSS<1213> VSS<1214> 
VSS<1215> VSS<1216> VSS<1217> VSS<1218> VSS<1219> VSS<1220> VSS<1221> VSS<1222> VSS<1223> VSS<1224> VSS<1225> VSS<1226> VSS<1227> 
VSS<1228> VSS<1229> VSS<1230> VSS<1231> VSS<1232> VSS<1233> VSS<1234> VSS<1235> VSS<1236> VSS<1237> VSS<1238> VSS<1239> 
VSS<1240> VSS<1241> VSS<1242> VSS<1243> VSS<1244> VSS<1245> VSS<1246> VSS<1247> VSS<1248> VSS<1249> VSS<1250> VSS<1251> VSS<1252> 
VSS<1253> 
SKYLAKE - SKT0 - 20 OF 21 
CPU SYMBOLS 1-30 ARE PRELIMINARY AND SUBJECT TO CHANGE SKYLAKE - SKT0 - 20 OF 21 
BOM_COST=PROC_SOCKET 
ROOM=CPU0 
SKX_EXT_B SKX_EXT_B SKX_EXT_B SKX_EXT_B 
INA
ILER
RY
P
M INA
ILER
RY
P
MINA
ILER
RY
P
MINA
ILER
RY
P
M
WIWYNN CORPORATION 
26/30 25/30 24/30 23/30 



DB85 
CA10 
DP69 
CU86 
DA78 BH11 
ED77 
CU76 
DR38 
EF79 
EF75 
EF71 
EE78 
EE76 
EE70 
EE36 
EE34 
EE30 
EE28 
EE24 
ED35 
ED29 
ED23 
ED15 
ED11 
EC76 
EC74 
EC72 
EC70 
EC10 
EB69 
EB65 
EB41 
EB39 
EB37 
EB35 
EB33 
EB31 
EB29 
EB27 
EB25 
EB23 
BR18 
EB13 
EA82 
EA80 
EA78 
EA76 
EA70 
EA64 
EA42 
EA22 
EA20 
EA16 
J16 
EA6 
DY75 
DY71 
DY41 
DY35 
DY29 
DY23 
DY19 
DY5 
DW84 
DW82 
DW8 
DW76 
DW74 
DW72 
DW70 
DW68 
DW66 
DW64 
DW40 
DW36 
DW34 
DW30 
DW28 
DW24 
DW20 
DW12 
DV81 
DV77 
DV73 
DV39 
DV37 
DV33 
DV31 
DV27 
DV25 
DV21 
DU84 
DU82 
DU80 
DU78 
DU72 
DU70 
DU38 
DU32 
DU26 
DU22 
CN14 
DU14 
DU10 
DT85 
DT83 
DT79 
DT69 
DT65 
DH21 
DT17 
DT3 
DR78 
DR76 
DR74 
DR72 
DR70 
DR68 
DR66 
DR42 
DR40 
DR36 
DR34 
DR32 
DR30 
DR28 
DR26 
DR24 
DR22 
DR20 
CL22 
CA20 
DR6 
BR26 
DP83 
DP81 
DP71 
DP67 
DN78 
IC 
TBD 
U5D1 
DK77 
DH83 
DF69 
DN72 
DN68 
DN38 
DN32 
DN26 
DN22 
DN12 
BH17 
DN2 
DM83 
DM77 
DM73 
DM65 
DM39 
DM37 
DM33 
DM31 
DM27 
DM25 
H45 
DM15 
DL80 
DL78 
DL76 
DL74 
DL70 
DL68 
DL40 
DL36 
DL34 
DL30 
DL28 
DL24 
DL22 
DL4 
DL18 
DL16 
DK85 
DK83 
DK75 
DK73 
DK41 
DK39 
DK35 
DK29 
DK23 
DK7 
DJ84 
DJ82 
DJ78 
DJ74 
DJ68 
DJ42 
DJ38 
DJ22 
H47 
DJ10 
DJ2 
DH81 
DH79 
DH73 
DH71 
DH67 
DH41 
DH37 
DH35 
DH33 
DH31 
DH29 
DH27 
DH25 
DH23 
DH15 
DH13 
DG80 
DG78 
DG76 
DG68 
DG66 
DG24 
DG16 
DG14 
H49 
DG2 
DF85 
DF83 
DF79 
DF73 
DF65 
DF41 
DF39 
DF37 
DF35 
DF29 
DF19 
H51 
DF7 
DF5 
DE78 
DE72 
DE70 
DE64 
DE36 
DE34 
DE30 
DE28 
DE24 
DE20 
DE18 
DE8 
DE6 
DD83 
DD81 
DD75 
DD73 
DD71 
DD37 
DD33 
DD31 
DD27 
DD23 
DD11 
DC86 
DC84 
DC78 
DC70 
DC68 
DC66 
DC64 
DC42 
DC38 
DC32 
DC26 
DC24 
DC14 
DB83 
DB77 
DB73 
DB49 
DB47 
DB41 
DB39 
DB25 
DB23 
DB17 
DB13 
DB3 
DA80 
DA76 
DA74 
DA70 
DA64 
DA50 
DA48 
IC 
TBD 
U5D1 
DG82 
DA46 
DA44 
DA38 
DA36 
DA34 
DA32 
DA30 
DA28 
DA26 
DA18 
H53 
DA6 
CY85 
CY83 
CY77 
CY75 
CY69 
CY65 
CY61 
CY59 
CY51 
CY45 
CY41 
CY21 
CY15 
CY13 
CY9 
CY1 
CW82 
CW78 
CW74 
CW68 
CW66 
CW64 
CW54 
CW52 
CW42 
CW40 
CW38 
CW32 
CW26 
CW12 
CV83 
CV81 
CV79 
CV73 
CV67 
CV63 
CV55 
CV53 
CV41 
CV39 
CV37 
CV33 
CV31 
CV27 
CV25 
CV17 
H55 
CV1 
CU82 
CU80 
CU78 
CU68 
CU62 
CU56 
CU36 
CU34 
CU30 
CU28 
CU22 
CU4 
CT85 
CT83 
CT79 
CT73 
CT57 
CT35 
CT33 
CT29 
CT27 
CT19 
CT13 
H57 
CR86 
CR78 
CR68 
CR66 
CR64 
CR62 
CR58 
CR32 
CR24 
CR22 
CR10 
CR6 
CP83 
CP81 
CP75 
CP73 
CP69 
CP59 
CP25 
H59 
CP1 
CN78 
CN68 
CN62 
CN60 
CN32 
CN26 
H61 
CN12 
CN2 
CM85 
CM83 
CM77 
CM73 
CM67 
CM63 
CM61 
CM31 
CM5 
CM29 
CM19 
CL80 
CL78 
CL76 
CL74 
CL66 
CL64 
CL62 
H63 
P45 
CL18 
CL14 
CL8 
CK85 
CK83 
CK75 
CK73 
CK71 
CK69 
CK67 
CK65 
CK63 
CK27 
CK21 
CK15 
CK11 
CJ86 
CJ84 
CJ82 
CJ76 
CJ74 
CJ62 
P47 
IC 
TBD 
U5D1 
CJ78 
BY23 
BH7 
CD63 
P49 
CJ12 
CJ10 
CJ8 
CJ6 
CJ2 
CH83 
CH81 
CH79 
CH73 
CH67 
CH63 
CH19 
CH15 
CH3 
CH1 
CG80 
CG72 
CG68 
CG22 
CG18 
P51 
CF83 
CF77 
CF71 
CF69 
CF63 
CF9 
P53 
CE82 
CE70 
CE62 
CE26 
CE20 
CE14 
CE10 
CD81 
CD79 
CD77 
CD75 
CD73 
CD13 
CD5 
CC82 
CC80 
CC78 
CC76 
CC74 
CC72 
CC64 
CC24 
CC18 
CC16 
CC4 
CB71 
CB63 
CB27 
CB9 
CB7 
CA70 
CA68 
CA66 
CA64 
CA26 
CA18 
CA14 
CA8 
CA6 
CA2 
BY71 
BY69 
BY67 
BY65 
BY63 
BY13 
BY11 
BW82 
BW80 
BW78 
BW76 
BW74 
BW72 
BW26 
BW18 
BW16 
BW14 
BW12 
P55 
BW6 
BV25 
BV17 
BU10 
BV5 
BU8 
BT25 
BT23 
BT21 
BT5 
BT3 
BR82 
BR80 
BR78 
BR76 
BR74 
BR72 
BR70 
BR68 
BR66 
BR64 
P57 
BR16 
BR10 
BR6 
BP27 
BP3 
BN26 
BN20 
BN10 
BN6 
BM25 
P59 
BM15 
BM13 
BM9 
BL82 
BL80 
BL78 
BL76 
BL74 
BL72 
BL70 
BL68 
BL66 
BL64 
BL24 
BL22 
P61 
BL12 
BL10 
BL6 
BK19 
BK11 
BK7 
BK3 
BJ6 
BJ4 
BH21 
BH15 
BH9 
BG82 
BG80 
BG78 
BG76 
IC 
TBD 
U5D1 
CG62 
BG74 
DESIGN NOTE: 
DO NOT SCALE DRAWING SHEET 
B
AA
B
B
SIZE 
SCALE: 
234
1234
DEPARTMENT CODE 
1
DOCUMENT NUMBER REV 
41 OF 270 
Wed Feb 08 16:34:38 2017 
VSS<0> 
VSS<1> VSS<2> VSS<3> VSS<4> VSS<5> VSS<6> VSS<7> VSS<8> VSS<9> VSS<10> VSS<11> VSS<12> VSS<13> 
VSS<14> VSS<15> VSS<16> VSS<17> VSS<18> VSS<19> VSS<20> VSS<21> VSS<22> VSS<23> VSS<24> VSS<25> VSS<26> 
VSS<27> VSS<28> VSS<29> VSS<30> VSS<31> VSS<32> VSS<33> VSS<34> VSS<35> VSS<36> VSS<37> VSS<38> VSS<39> 
VSS<40> VSS<41> VSS<42> VSS<43> VSS<44> VSS<45> VSS<46> VSS<47> VSS<48> VSS<49> VSS<50> VSS<51> VSS<52> 
VSS<53> 
VSS<54> VSS<55> 
VSS<56> VSS<57> VSS<58> VSS<59> VSS<60> VSS<61> VSS<62> VSS<63> VSS<64> VSS<65> VSS<66> VSS<67> 
VSS<68> VSS<69> VSS<70> VSS<71> VSS<72> VSS<73> VSS<74> VSS<75> VSS<76> VSS<77> VSS<78> VSS<79> VSS<80> 
VSS<81> VSS<82> VSS<83> VSS<84> VSS<85> VSS<86> VSS<87> VSS<88> VSS<89> VSS<90> VSS<91> VSS<92> VSS<93> 
VSS<94> VSS<95> VSS<96> VSS<97> VSS<98> VSS<99> VSS<100> VSS<101> VSS<102> VSS<103> VSS<104> VSS<105> VSS<106> 
VSS<107> VSS<108> VSS<109> VSS<110> VSS<111> VSS<112> VSS<113> VSS<114> VSS<115> VSS<116> VSS<117> VSS<118> VSS<119> 
VSS<120> VSS<121> VSS<122> VSS<123> VSS<124> VSS<125> VSS<126> VSS<127> VSS<128> VSS<129> VSS<130> VSS<131> VSS<132> 
VSS<133> 
VSS<134> VSS<135> VSS<136> 
VSS<137> VSS<138> VSS<139> VSS<140> VSS<141> VSS<142> VSS<143> VSS<144> VSS<145> VSS<146> VSS<147> VSS<148> 
VSS<149> VSS<150> VSS<151> VSS<152> VSS<153> VSS<154> VSS<155> VSS<156> VSS<157> VSS<158> VSS<159> VSS<160> VSS<161> 
VSS<162> VSS<163> VSS<164> VSS<165> VSS<166> VSS<167> VSS<168> VSS<169> VSS<170> VSS<171> VSS<172> VSS<173> VSS<174> 
VSS<175> VSS<176> VSS<177> VSS<178> VSS<179> VSS<180> VSS<181> VSS<182> VSS<183> VSS<184> VSS<185> VSS<186> VSS<187> 
VSS<188> VSS<189> VSS<190> VSS<191> VSS<192> VSS<193> VSS<194> VSS<195> VSS<196> VSS<197> VSS<198> VSS<199> VSS<200> 
VSS<201> VSS<202> VSS<203> VSS<204> VSS<205> VSS<206> VSS<207> VSS<208> VSS<209> VSS<210> VSS<211> VSS<212> VSS<213> 
VSS<214> VSS<215> VSS<216> 
VSS<217> VSS<218> VSS<219> VSS<220> VSS<221> VSS<222> VSS<223> VSS<224> VSS<225> VSS<226> VSS<227> VSS<228> 
VSS<229> VSS<230> VSS<231> VSS<232> VSS<233> VSS<234> VSS<235> VSS<236> VSS<237> VSS<238> VSS<239> VSS<240> VSS<241> 
VSS<242> VSS<243> VSS<244> VSS<245> VSS<246> VSS<247> VSS<248> VSS<249> VSS<250> VSS<251> VSS<252> VSS<253> VSS<254> 
VSS<255> VSS<256> VSS<257> VSS<258> VSS<259> VSS<260> VSS<261> VSS<262> VSS<263> VSS<264> VSS<265> VSS<266> VSS<267> 
VSS<268> VSS<269> VSS<270> VSS<271> VSS<272> VSS<273> VSS<274> VSS<275> VSS<276> VSS<277> VSS<278> VSS<279> VSS<280> 
VSS<281> VSS<282> VSS<283> VSS<284> VSS<285> VSS<286> VSS<287> VSS<288> VSS<289> VSS<290> VSS<291> VSS<292> VSS<293> 
VSS<294> VSS<295> 
VSS<296> VSS<297> VSS<298> VSS<299> VSS<300> VSS<301> VSS<302> VSS<303> VSS<304> VSS<305> VSS<306> VSS<307> 
VSS<308> VSS<309> VSS<310> VSS<311> VSS<312> VSS<313> VSS<314> VSS<315> VSS<316> VSS<317> VSS<318> VSS<319> VSS<320> 
VSS<321> VSS<322> VSS<323> VSS<324> VSS<325> VSS<326> VSS<327> VSS<328> VSS<329> VSS<330> VSS<331> VSS<332> VSS<333> 
VSS<334> VSS<335> VSS<336> VSS<337> VSS<338> VSS<339> VSS<340> VSS<341> VSS<342> VSS<343> VSS<344> VSS<345> VSS<346> 
VSS<347> VSS<348> VSS<349> VSS<350> VSS<351> VSS<352> VSS<353> VSS<354> VSS<355> VSS<356> VSS<357> VSS<358> VSS<359> 
VSS<360> VSS<361> VSS<362> VSS<363> VSS<364> VSS<365> VSS<366> VSS<367> VSS<368> VSS<369> VSS<370> VSS<371> VSS<372> 
VSS<373> 
VSS<374> VSS<375> 
VSS<376> VSS<377> VSS<378> VSS<379> VSS<380> VSS<381> VSS<382> VSS<383> VSS<384> VSS<385> VSS<386> VSS<387> 
VSS<388> VSS<389> VSS<390> VSS<391> VSS<392> VSS<393> VSS<394> VSS<395> VSS<396> VSS<397> VSS<398> VSS<399> VSS<400> 
VSS<401> VSS<402> VSS<403> VSS<404> VSS<405> VSS<406> VSS<407> VSS<408> VSS<409> VSS<410> VSS<411> VSS<412> VSS<413> 
VSS<414> VSS<415> VSS<416> VSS<417> VSS<418> VSS<419> VSS<420> VSS<421> VSS<422> VSS<423> VSS<424> VSS<425> VSS<426> 
VSS<427> VSS<428> VSS<429> VSS<430> VSS<431> VSS<432> VSS<433> VSS<434> VSS<435> VSS<436> VSS<437> VSS<438> VSS<439> 
VSS<440> VSS<441> VSS<442> VSS<443> VSS<444> VSS<445> VSS<446> VSS<447> VSS<448> VSS<449> VSS<450> VSS<451> VSS<452> 
VSS<453> 
VSS<454> VSS<455> 
VSS<456> VSS<457> VSS<458> VSS<459> VSS<460> VSS<461> VSS<462> VSS<463> VSS<464> VSS<465> VSS<466> VSS<467> 
VSS<468> VSS<469> VSS<470> VSS<471> VSS<472> VSS<473> VSS<474> VSS<475> VSS<476> VSS<477> VSS<478> VSS<479> VSS<480> 
VSS<481> VSS<482> VSS<483> VSS<484> VSS<485> VSS<486> VSS<487> VSS<488> VSS<489> VSS<490> VSS<491> VSS<492> VSS<493> 
VSS<494> VSS<495> VSS<496> VSS<497> VSS<498> VSS<499> VSS<500> VSS<501> VSS<502> VSS<503> VSS<504> VSS<505> VSS<506> 
VSS<507> VSS<508> VSS<509> VSS<510> VSS<511> VSS<512> VSS<513> VSS<514> VSS<515> VSS<516> VSS<517> VSS<518> VSS<519> 
VSS<520> VSS<521> VSS<522> VSS<523> VSS<524> VSS<525> VSS<526> VSS<527> VSS<528> VSS<529> VSS<530> VSS<531> VSS<532> 
VSS<533> 
VSS<534> VSS<535> 
VSS<536> VSS<537> VSS<538> VSS<539> VSS<540> VSS<541> VSS<542> VSS<543> VSS<544> VSS<545> VSS<546> VSS<547> 
VSS<548> VSS<549> VSS<550> VSS<551> VSS<552> VSS<553> VSS<554> VSS<555> VSS<556> VSS<557> VSS<558> VSS<559> VSS<560> 
VSS<561> VSS<562> VSS<563> VSS<564> VSS<565> VSS<566> VSS<567> VSS<568> VSS<569> VSS<570> VSS<571> VSS<572> VSS<573> 
VSS<574> VSS<575> VSS<576> VSS<577> VSS<578> VSS<579> VSS<580> VSS<581> VSS<582> VSS<583> VSS<584> VSS<585> VSS<586> 
VSS<587> VSS<588> VSS<589> VSS<590> VSS<591> VSS<592> VSS<593> VSS<594> VSS<595> VSS<596> VSS<597> VSS<598> VSS<599> 
VSS<600> VSS<601> VSS<602> VSS<603> VSS<604> VSS<605> VSS<606> VSS<607> VSS<608> VSS<609> VSS<610> VSS<611> VSS<612> 
VSS<613> 
SKYLAKE - SKT0 - 21 OF 21 
CPU SYMBOLS 1-30 ARE PRELIMINARY AND SUBJECT TO CHANGE SKYLAKE - SKT0 - 21 OF 21 
SKX_EXT_B SKX_EXT_B SKX_EXT_B SKX_EXT_B 
ROOM=CPU0 
BOM_COST=PROC_SOCKET 
WIWYNN CORPORATION 
30/30 29/30 28/30 27/30 



22.0UF 
E15431-004 
C5P10 
100UF 
4V 
20% 
0805 
20% 
C5P13 
0805 
20% 
4V 
100UF 
C5P18 
C95333-006 
20% 
C95333-006 2
0805 2
C5D38 
100UF 
C5P21 
47UF 
20% 
2
4V 
20% 
0805 
1
2 0805 
20% 
C5P12 
100UF 
4V 
602433-112 
1
20% 
0805 
4V 2
1
0805 
100UF 
C5P20 
4V 
20% 
2
1
2 0805 
100UF 
4V 
20% 
C4P2 
4V 
C5P31 
20% 
0805 
100UF 
2
1
0805 
20% 
4V 
C5P11 
1
2
100UF 
C5P29 
100UF 1
PVCCMCP_CPU0 
1
2 0805 
100UF 
20% 
4V 
100UF 
C4P5 
4V 
0805 
2
11
22
4V 
1
20% 
0805 
C5P28 
100UF 1
2
20% 
100UF 
2
4V 
0805 
1
C4P3 
4V 
100UF 
2
C4P7 
20% 
0805 
1
20% 
100UF 
4V 
1
2
C5P19 
0805 
C4P4 
1
2 0805 
20% 
4V 
100UF 
2
1 100UF 
C5P30 
4V 
20% 
0805 
0603LF 
E15431-001 
X6S 
20% 
4V 
10UF 
1C5D10 
E15431-001 
0603V 
X6S 
47UF 
20% 20% 147UF 47UF 
C5P35 C5P37 
47UF 
20% 
C5D30 
0603V 
0603V 
E15431-004 
20% 
4V 
22.0UF 
C5W2 
E15431-004 
C5P24 1
0603LF 
10UF 
C5D11 
X6S 
22.0UF 
0603V 0603V 
E15431-004 E15431-004 E15431-004 E15431-004 E15431-004 E 15431-004 
22.0UF 
0603V 
X6S 
0603V 
C5D36 
22.0UF 
4V 
20% PVCCMCP_CPU0 
C5D34 
22.0UF 
4V 
22.0UF 22.0UF 22.0UF 22.0UF 
4V 4V 
C5D35 
E15431-004 
4V 4V 
20% 
4V 
22.0UF 
4V 
22.0UF 
4V 4V 
20% 
4V 4V 4V 
22.0UF 
4V 
22.0UF 
4V 
1 C5D50 1 C5D21 1 22.0UF 22.0UF 
C6D2 C6D5 
20% 
X6S 
E15431-004 
0603V 
C5D33 
20% 
X6S 
E15431-004 
0603V 
PVCCMCP_CPU0 
C5D53 
0603V 
22.0UF 
X6S 
C5W1 
4V 
20% 
0603V 
E15431-004 
X6S X6S 
E15431-004 
0603V 
X6S 
20% 
22.0UF 
20% 
4V 
E15431-001 
20% 
1
2 X6S 
10UF 
C5D13 
20% 
4V 
X6S 
1
22
C5D12 
4V 20% 20% 
4V 
22.0UF 1 1
10UF 
C5D52 
E15431-004 E15431-004 
4V 
X6S X6S 
E15431-004 E15431-004 
0603V 0603V 
C95333-002 
20% 
22UF 
C5P9 C4P8 
1
E15431-004 
2 0805 
0603V 
E15431-004 
20% 
C5D43 
22.0UF 
E15431-004 
22.0UF 
C5D15 
C5P14 
47UF 
20% 
0805 
C5P22 
20% 
4V 
0603V 0603V 
E15431-004 
0603V 
22E15431-004 
22.0UF 
0603V 
E15431-004 2E15431-004 
X6S 
20% 
4V 1 22.0UF 
0603V 
E15431-004 
X6S 
20% 
4V 
22.0UF 
0603V 
E15431-004 
22.0UF 
C5D17 
C5D46 
E15431-004 
0603V 
C5D45 
22.0UF 
X6S 
E15431-004 C95333-006 
0603V 0805 20805 0805 
C4P9 
4V 
20% 
47UF 
0603LF 
2
C5P40 
47UF 1
2
20% 
C5P27 
2
20% 
2
20% 
X6S 
0805 
1
2 2 0805 
C5P33 
47UF 1
C5P16 
20% 1
C5P7 
20% 
2
C5P8 
2
1
2
X6S 
20% 
1
2
0603V 
4V 
20% 
X6S 
1
2
C5D18 
20% 
X6S 
0603V 
E15431-004 
22.0UF 
4V 
20% 
X6S 
2
122.0UF 
C5D42 
4V 1
4V 
22.0UF 
C5D19 
2
2
1 22.0UF 
0603V 
20% 
4V 1
1
4V 
20% 
22.0UF 
C5D5 
4V 
1
20% 
X6S 
2
1
22.0UF 
0603V 
X6S 
C5D39 
X6S 2
20% 
1
2
C5D47 C5D40 C5D14 
22.0UF 
4V 
22.0UF 
C5D31 
20% 
4V 
2
X6S 
C5D24 
20% 
4V 
1 22.0UF 
X6S 
E15431-004 
0603V 
2
X6S 
2 0603V 
E15431-004 
X6S 
1
22.0UF 
E15431-004 
X6S 
E15431-004 
X6S 
E15431-004 2
0603V 
4V 4V 
20% 
2 E15431-004 
X6S 
20% 
4V 
22.0UF 
C5D26 
0603V 
2
20% 
4V 
22.0UF 
C5D32 
1
0603V 
20% 
4V 
22.0UF 
X6S 
1
22
1 1
C6D6 
2
11
2 2 2
PVCCMCP_CPU0 
X6S 2
0603V 
1
E15431-004 
0603V 
1
2
C5D49 C5D22 
E15431-004 
22.0UF 
20% 
0603V 
4V 
X6S 
2
1
4V 
C5D20 
20% 
C6D8 
22.0UF 
20% 
1
2
22.0UF 
0603V 
X6S 
1
2
20% 
0603V 
X6S 
1
2
C5D37 
22.0UF 1
2
0603V 
X6S 
1
2
20% 
C5D51 
20% 
X6S 
2
20% 
X6S 
2
20% 
X6S 
2 E15431-004 
C5D48 
20% 
X6S 
1
2 E15431-004 
0603V 
C5D23 
20% 
X6S 
1
0603V 
E15431-004 
X6S 
0603V 
1
22222
1
2
1
0603V 
E15431-004 
X6S 
4V 
C6D3 C6D4 
4V 
E15431-004 
0603V 
E15431-004 
X6S 
4V 
C6D7 C6D10 
4V 
X6S 
E15431-004 
0603V 
C6D9 
4V 
X6S 
0603V 
20% 
4V 
C5D29 
22.0UF 1
4V 
20% 
0603V 
2
1
1
20% 
X6S 
20% 
4V 
E15431-004 
1
2
X6S X6S 
C5D27 
C5D28 
22.0UF 1 1 22.0UF 1 22.0UF 22.0UF 
20% 20% 20% 20% 20% 20% 20% 
X6S 
20% 
4V 
22.0UF 
X6S 
20% 
4V 
C5D25 
22.0UF 
E15431-004 
0603V 
1
X6S 
0603V 
E15431-004 
X6S 
1
2
2E15431-004 E15431-004 
0603V 
E15431-004 
X6S 
20% 
4V 
22.0UF 
C5D44 
E15431-004 
20805LF 
0603V 
E15431-004 
1
2
0805 
1
2
C5P36 
47UF 
20% 
0805 
C5P34 
47UF 
20% 20% 
2 0805 
20% 
2 0805 
1 47UF 
1 47UF 
C5P32 
2
1
C5P23 
0805 
1
1 22UF 22UF 
47UF 1
2 0805 0805 
47UF 
20% 
0805 0805 0805 
C5P25 
1
0805 
47UF 
C5P26 
20% 
47UF 
C5P15 
X6S 
20% 
C4P10 
0805LF 
C95333-002 C95333-002 
1 47UF 47UF 1
20% 
0805LF 
20% 
C4P6 
4V 
22.0UF 22.0UF 1
C4P1 
47UF 
C5P17 
0603V 
20% 
4V 
22.0UF 
C5D41 
0603V 
0603V 
X6S 
20% 
4V 
C5D16 
2E15431-004 
X6S 
0603V 
X6S 
20% 
E15431-001 
0603LF 
0805 
2
1 4V 
20% 
602433-112 
0805 
100UF 
C8W3 
TP FAB1 ADD CAP 0314 
TP FAB3 ADD CAP 0919 
TP FAB1 MOVE TO PAGE 217 0318 
TP FAB1 MOVE TO PAGE 220 0311 
TP FAB1 MOVE TO PAGE 220 0311 
TP FAB1 MOVE TO PAGE 217 0314 
TP FAB1 MOVE TO PAGE 217 0314 
TP FAB1 MOVE TO PAGE 220 0314 
TP FAB1 MOVE TO PAGE 220 0318 
TP FAB1 MOVE TO PAGE 217 0311 
TP FAB1 MOVE TO PAGE 220 0314 
TP FAB1 MOVE TO PAGE 217 0314 
TP FAB3 CHANGE CAP FROM 47UF TO 100UF 1004 
GROUP=PWR_MLCC_CAP 
GROUP=PWR_MLCC_CAP 
GROUP=PWR_MLCC_CAP 
NEW_PN=078.1071T.0811 
NEW_PN=078.1071T.0811 
NEW_PN=078.1071T.0811 NEW_PN=078.1071T.0811 
NEW_PN=078.1071T.0811 
NEW_PN=078.1071T.0811 
NEW_PN=078.1071T.0811 
NEW_PN=078.1071T.0811 
NEW_PN=078.1071T.0811 NEW_PN=078.1071T.0811 
NEW_PN=078.1071T.0811 
NEW_PN=078.1071T.0811 
NEW_PN=078.1071T.0811 NEW_PN=078.1071T.0811 
NEW_PN=078.1071T.0811 
GROUP=PWR_MLCC_CAP 
NEW_MATERIAL=X6S 
NEW_MATERIAL=X6S 
NEW_PN=078.1071T.0811 
NEW_PN=078.1071T.0811 
NEW_PN=078.1071T.0811 
NEW_MATERIAL=X6S 
NEW_MATERIAL=X6S 
GROUP=PWR_MLCC_CAP 
NEW_MATERIAL=X6S 
NEW_MATERIAL=X6S 
NEW_MATERIAL=X6S NEW_MATERIAL=X6S 
GROUP=PWR_MLCC_CAP 
X6S 
GROUP=PWR_MLCC_CAP GROUP=PWR_MLCC_CAP 
GROUP=PWR_MLCC_CAP 
GROUP=PWR_MLCC_CAP 
GROUP=PWR_MLCC_CAP 
X6S 
GROUP=PWR_MLCC_CAP 
NEW_MATERIAL=X6S 
NEW_MATERIAL=X6S NEW_MATERIAL=X6S 
NEW_MATERIAL=X6S NEW_MATERIAL=X6S NEW_MATERIAL=X6S NEW_MATERIAL=X6S 
NEW_MATERIAL=X6S NEW_MATERIAL=X6S NEW_MATERIAL=X6S 
GROUP=PWR_MLCC_CAP 
GROUP=PWR_MLCC_CAP 
GROUP=PWR_MLCC_CAP 
GROUP=PWR_MLCC_CAP 
GROUP=PWR_MLCC_CAP 
GROUP=PWR_MLCC_CAP 
GROUP=PWR_MLCC_CAP 
GROUP=PWR_MLCC_CAP 
GROUP=PWR_MLCC_CAPGROUP=PWR_MLCC_CAP 
X6S 
4V 
GROUP=PWR_MLCC_CAP 
GROUP=PWR_MLCC_CAP 
GROUP=PWR_MLCC_CAP 
X6S 
GROUP=PWR_MLCC_CAP 
GROUP=PWR_MLCC_CAP 
X6S 
GROUP=PWR_MLCC_CAP 
GROUP=PWR_MLCC_CAP 
GROUP=PWR_MLCC_CAP 
GROUP=PWR_MLCC_CAP 
4V 
X6S 
GROUP=PWR_MLCC_CAP 
GROUP=PWR_MLCC_CAP GROUP=PWR_MLCC_CAP 
GROUP=PWR_MLCC_CAP 
GROUP=PWR_MLCC_CAP 
GROUP=PWR_MLCC_CAP 
GROUP=PWR_MLCC_CAP 
GROUP=PWR_MLCC_CAP 
GROUP=PWR_MLCC_CAP 
4V 
X6S 
X6S 
4V 
X6S 
4V 
X6S 
4V 4V 
X6S 
4V 
X6S 
4V 
X6S 
4V 4V 
X6S 
4V 
X6S 
4V 
X6S 
4V 
4V 
X6S 
4V 
X6S 
4V 
4V 4V 
4V 
X6S 
4V 
X6S 
4V 4V 
X6S 
GROUP=PWR_MLCC_CAP 
GROUP=PWR_MLCC_CAP GROUP=PWR_MLCC_CAP 
GROUP=PWR_MLCC_CAP 
GROUP=PWR_MLCC_CAPGROUP=PWR_MLCC_CAP 
GROUP=PWR_MLCC_CAP 
GROUP=PWR_MLCC_CAP 
GROUP=PWR_MLCC_CAP 
GROUP=PWR_MLCC_CAP 
GROUP=PWR_MLCC_CAP 
GROUP=PWR_MLCC_CAP 
GROUP=PWR_MLCC_CAP 
GROUP=PWR_MLCC_CAP 
GROUP=PWR_MLCC_CAP 
GROUP=PWR_MLCC_CAP 
GROUP=PWR_MLCC_CAP 
GROUP=PWR_MLCC_CAP 
GROUP=PWR_MLCC_CAP 
GROUP=PWR_MLCC_CAP 
GROUP=PWR_MLCC_CAP 
602433-112 
602433-112 
602433-112 
602433-112 
602433-112 
602433-112 
602433-112 
602433-112 
602433-112 
602433-112 
602433-112 
602433-112 
602433-112 
602433-112 
602433-112 
602433-112 
C95333-006 
C95333-006 
C95333-006 
C95333-006 
C95333-006 
C95333-006 
C95333-006 
C95333-006 
C95333-006 
C95333-006 
C95333-006 
C95333-006 
C95333-006 
C95333-006 
C95333-006 
C95333-006 
C95333-006 
DESIGN NOTE: 
DESIGN NOTE: 
1
1
2
1
2
2
1 1
2 2
DO NOT SCALE DRAWING SHEET 
B
AA
B
B
SIZE 
SCALE: 
234
1234
DEPARTMENT CODE 
1
DOCUMENT NUMBER REV 
PVSA_CPU0 
PVCCIO_CPU0 
PVCCIN_CPU0 
PVCCIN_CPU0 
PVCCIN_CPU0 
PVCCIN_CPU0 
PVSA_CPU0 
PVCCIN_CPU0 
PVCCIN_CPU0 
PVCCIN_CPU0 
PVCCIN_CPU0 
PVCCIO_CPU0 
PVCCIN_CPU0 
PVCCIN_CPU0 
PVCCIN_CPU0 
PVCCIN_CPU0 
PVCCIN_CPU0 
PVCCIN_CPU0 
PVMCP: 100UF, 805, 17X 
FULL CAP CONFIG FOR -P SUPPORT. 
PVCCIO: 22UF, 603, 6X 
PVCCIN: 47UF, 805, 17X 
PVCCIN: 22UF/603/25X 
FULL CAP CONFIG FOR -P SUPPORT. 
PVMCP: 22UF, 603, 21X 
PVCCIO: 47UF/805/3X, 22UF/603/2X 
42 OF 270 
Wed Feb 08 16:34:38 2017 
SKT 0 CAVITY (TOP,48.11MIL/1.22MM) 
* HIGH TEMPERATURE 
* TO BE PLACED IN 
CAPACITORS. 
SKT 0 CAVITY (BOTTOM, 98MIL/2.49MM) 
CAPACITORS. 
* TO BE PLACED IN 
* HIGH TEMPERATURE 
(DEBUG ONLY) 
TP FAB1 MOVE TO PAGE 220 0314 
(DEBUG ONLY) 
REMOVE DURING MASS PRODUCTION 
CPU0 DECOUPLING CAVITY CAPS 
WIWYNN CORPORATION ROOM = PVCCIN_CPU0_DECAP_VR 



H44441-004 
146 
284 
285 
141 
230 
238 
140 
139 
237 
93 
89 
84 
144 
227 
205 
58 
222 
91 
87 
78 
280 
135 
273 
128 
137 
275 
130 
124 
262 
117 
271 
126 
264 
119 
258 
113 
251 
106 
260 
115 
253 
108 
247 
95 
249 
104 
97 
188 
43 
181 
36 
190 
45 
183 
38 
177 
32 
170 
25 
179 
34 
172 
27 
166 
21 
159 
14 
168 
23 
161 
16 
155 
10 
148 
3
157 
12 
150 
5
203 
60 
218 
219 
74 
75 
199 
54 
192 
201 
56 
194 
49 
235 
207 
63 
81 
208 
62 
234 
82 
86 
228 
232 
225 
66 
68 
211 
69 
213 
71 
79 
269 
210 
242 
56 
59 
58 
61 
63 
60 
62 
51 
50 
52 
53 
55 
54 
57 
48 
31 
28 
30 
33 
32 
34 
37 
36 
38 
39 
41 
40 
43 
45 
42 
44 
47 
49 
46 
17 
14 
16 
19 
18 
20 
21 
23 
22 
24 
25 
27 
26 
29 
8
11 
13 
10 
12 
15 
9
1
3
0
2
5
4
6
7
10 
11 
8
9
5
6
7
3
J4G1 
H44441-004 
SCONN 
51 
52 
132 
133 
121 
122 
110 
111 
99 
100 
40 
41 
29 
18 
19 
7
8
197 
196 
278 
277 
267 
266 
256 
255 
245 
244 
186 
185 
175 
174 
164 
163 
153 
152 
4
0
1
2
15 
17 
16 
13 
14 
12 
17 
16 
15 
14 
13 
12 
11 
10 
17 
9
8
7
6
5
4
3
2
1
0
16 
0
1
1
0
15 
3
2
1
0
0
14 
1
0
1
SMB_DDR_ABC_VPP_SDA 
125 
J4G1 
H44441-004 
SCONN 
2
4
6
9
11 
13 
15 
17 
20 
22 
24 
26 
28 
31 
33 
35 
37 
39 
42 
44 
46 
48 
50 
53 
55 
57 
94 
96 
98 
101 
103 
105 
107 
109 
112 
114 
116 
118 
123 
127 
129 
131 
134 
136 
138 
147 
149 
151 
154 
156 
158 
160 
162 
165 
167 
169 
171 
173 
176 
178 
180 
182 
184 
187 
189 
191 
193 
195 
198 
200 
202 
239 
241 
243 
246 
248 
250 
252 
254 
257 
259 
261 
263 
265 
268 
270 
272 
274 
276 
279 
281 
283 
13 
J4G1 
H44441-004 
SCONN 
77 
221 
142 
143 
288 
286 
287 
59 
61 
64 
67 
70 
73 
76 
80 
83 
85 
88 
90 
92 
204 
206 
209 
212 
215 
217 
220 
223 
226 
229 
231 
233 
236 
1
145 
12 
X7R 
25V 
10% 
0.01UF 
A36096-045 
C4F10 
0402V 
11 
10 
9
8
6
7
5
3
4
2
1
0
0
1
1
0
6
7
4
5
2
0
3
1
M_A_DQS_DN<17:0> 
M_A_DQS_DP<17:0> 
M_A_ODT<3:0> 
M_A_CS_N<7:0> 
M_A_ECC<7:0> 
M_A_CKE<3:0> 
M_A_BG<1:0> 
M_A_VREF 
TP_CH_A_DIMM_A0_RFU_1 
TP_CH_A_DIMM_A0_RFU_0 
TP_CH_A_DIMM_A0_RFU_2 
SMB_DDR_ABC_VPP_SCL 
FM_ADR_COMPLETE_ABC_N 
M_A_ALERT_N 
M_A_ACT_N 
M_ABC_RST_N 
FM_DIMM_EVENT_COD_N 
M_A_PAR 
65 
M_A_DQ<63:0> 
224 
120 
30 
282 
J4G1 
SCONN 
M_A_MA<17:0> 
214 
216 
72 
102 
240 
35 
47 
M_A_C<2> 
M_A_CLK_DN<3:0> 
M_A_CLK_DP<3:0> 
M_A_BA<1:0> 
44 45 46 47 48 99 
23 44 
23 44 
23 44 
23 44 
23 44 
23 44 
23 44 
98 44 
99 44 45 46 47 48 
89 44 45 46 
47 48 
44 23 
23 44 
21 44 45 46 47 48 
44 45 46 47 48 49 50 51 52 53 
54 77 78 79 80 81 82 83 84 85 
86 87 88 94 
23 44 
23 44 23 44 
23 44 
23 44 
23 44 
23 44 
BOM NOTE: 
1
2
DO NOT SCALE DRAWING 
SCONN288_H44441004 
SCONN288_H44441004 
SCONN288_H44441004 
SCONN288_H44441004 
SHEET 
B
AA
B
B
SIZE 
SCALE: 
234
1234
DEPARTMENT CODE 
1
DOCUMENT NUMBER REV 
IN 
IN 
OUT 
IN 
BI 
IN 
IN 
IN 
IN 
P12V_NVDIMM_ABC 
IN 
PVTT_ABC 
PVPP_ABC 
PVPP_ABC 
OUT 
IN PVDDQ_ABC 
BI 
IN 
IN 
IN 
IN 
IN 
IN 
BI 
BI 
BI 
43 OF 270 
12V<0> VPP<2> 
VPP<4> 
VTT<0> VTT<1> 
VPP<0> VPP<1> 
VDD<0> VDD<1> 
VDD<2> VDD<3> VDD<4> VDD<5> VDD<6> VDD<7> VDD<8> VDD<9> VDD<10> VDD<11> VDD<12> VDD<13> 
VDD<14> VDD<15> VDD<16> VDD<17> VDD<18> VDD<19> VDD<20> VDD<21> VDD<22> VDD<23> VDD<24> VDD<25> 
12V<1> VPP<3> 
VSS<0> VSS<1> VSS<2> VSS<3> VSS<4> 
VSS<5> VSS<6> VSS<7> VSS<8> VSS<9> VSS<10> VSS<11> VSS<12> VSS<13> VSS<14> VSS<15> VSS<16> VSS<17> 
VSS<18> VSS<19> VSS<20> VSS<21> VSS<22> VSS<23> VSS<24> VSS<25> VSS<26> VSS<27> VSS<28> VSS<29> VSS<30> 
VSS<31> VSS<32> VSS<33> VSS<34> VSS<35> VSS<36> VSS<37> VSS<38> VSS<39> VSS<40> VSS<41> VSS<42> VSS<43> 
VSS<44> 
VSS<47> VSS<48> VSS<49> VSS<50> VSS<51> 
VSS<52> VSS<53> VSS<54> VSS<55> VSS<56> VSS<57> VSS<58> VSS<59> VSS<60> VSS<61> VSS<62> VSS<63> VSS<64> 
VSS<65> VSS<66> VSS<67> 
VSS<84> VSS<85> VSS<86> VSS<87> VSS<88> VSS<89> VSS<90> 
VSS<91> VSS<92> VSS<93> 
VSS<68> VSS<69> VSS<70> VSS<71> VSS<72> VSS<73> VSS<74> VSS<75> VSS<76> VSS<77> 
VSS<78> VSS<79> VSS<80> VSS<81> VSS<82> VSS<83> 
VSS<45> VSS<46> 
DQS9P DQS9N DQS8P DQS8N DQS7P DQS7N DQS6P DQS6N DQS5P DQS5N DQS4P DQS4N DQS3P 
DQS3N DQS2P DQS2N DQS1P DQS1N 
DQS17P DQS17N DQS16P 
DQS16N DQS15P DQS15N DQS14P DQS14N DQS13P DQS13N DQS12P DQS12N DQS11P DQS11N DQS10P DQS10N 
DQS0P DQS0N 
BA<1> 
BA<0> DQ<42> 
DQ<29> 
CK0N CK0P CK1N CK1P 
BG<0> 
SAVE_N_NC 
RFU<0> RFU<1> 
RESET_N PAR 
EVENT_N 
DQ<0> 
DQ<3> DQ<4> DQ<5> 
DQ<13> DQ<14> DQ<15> DQ<16> DQ<17> 
DQ<20> 
DQ<22> DQ<23> DQ<24> DQ<25> DQ<26> 
DQ<30> 
DQ<39> DQ<40> 
DQ<43> 
DQ<46> DQ<47> DQ<48> DQ<49> 
DQ<52> DQ<53> DQ<54> DQ<55> DQ<56> DQ<57> 
DQ<59> 
DQ<61> DQ<62> DQ<63> 
CB<0> CB<1> 
CB<6> CB<7> 
C<2> 
BG<1> 
A9 
A5 
A4 
A3 
A14_WE_N 
A13 
A12 
A11 
A10 
A1 
A0 
DQ<38> 
DQ<37> 
DQ<36> 
DQ<35> 
DQ<34> 
DQ<33> 
DQ<32> 
DQ<31> 
RFU<2> 
DQ<2> 
DQ<1> 
VDDSPD 
SA<2> 
SA<1> 
SA<0> 
SDA 
SCL 
VREFCA 
ACT_N ALERT_N 
A2 
DQ<51> 
DQ<41> 
DQ<44> 
DQ<45> 
A6 A7 A8 
CB<2> CB<3> 
CB<4> CB<5> 
DQ<28> 
DQ<27> 
DQ<18> 
DQ<19> 
DQ<21> 
ODT<0> ODT<1> 
CKE<0> CKE<1> 
S0_N S1_N 
S2_N_C<0> S3_N_C<1> 
DQ<50> 
DQ<58> 
DQ<60> A15_CAS_N A16_RAS_N A17 
DQ<6> DQ<7> DQ<8> DQ<9> DQ<10> DQ<11> DQ<12> 
PVPP CAP: 10UF X12 
PVTT CAP: 100UF X2, 47UF X1 
PVDDQ (DOUBLE SIDE) CAP: 100UF X8, 47UF X41 
PVDDQ (SINGLE SIDE) CAP: 10UF X1, 22UF X50 
PLACE CAP NEAR DIMM CONNECTOR 
Wed Feb 08 16:34:39 2017 
STUFF FOR SKU A & B 
CPU0 DDR4 CH A DIMM0 
CAP BETWEEN DIMM 
SMBUS ADDR: 0XA0 
ROOM = DDR4_CH_A 
WIWYNN CORPORATION 
4/4 
3/4 
2/4 
1/4 



M_A_MA<17:0> M_A_DQ<63:0> 
132 
M_A_DQS_DN<17:0> 
M_A_DQS_DP<17:0> 
15 
100 
41 
273 
34 
36 
190 
172 
27 
166 
159 
135 
280 
128 
137 
130 
39 
231 
H44441-003 
224 
SCONN 
126 50 
7
92 
244 
M_A_C<2> 
M_ABC_RST_N 
M_A_PAR 
FM_DIMM_EVENT_COD_N 
FM_ADR_COMPLETE_ABC_N 
M_A_ALERT_N 
M_A_ACT_N 
SMB_DDR_ABC_VPP_SCL 
TP_CH_A_DIMM_A1_RFU_0 
TP_CH_A_DIMM_A1_RFU_2 
TP_CH_A_DIMM_A1_RFU_1 
M_A_VREF 
M_A_ECC<7:0> 
M_A_ODT<3:0> 
M_A_CKE<3:0> 
M_A_CS_N<7:0> 
M_A_CLK_DN<3:0> 
M_A_CLK_DP<3:0> 
M_A_BG<1:0> 
M_A_BA<1:0> 
38 
37 
36 
35 
33 
32 
31 
29 
30 
28 
27 
24 
26 
25 
23 
22 
20 
21 
19 
18 
17 
16 
145 
1
236 
233 
229 
226 
223 
220 
217 
215 
212 
209 
206 
204 
90 
88 
85 
83 
80 
76 
73 
70 
67 
64 
61 
59 
287 
286 
288 
143 
142 
221 
77 
SCONN 
J6T1 
14 
15 
13 
11 
12 
10 
9
6
8
4
5
3
1
2
0
10 
9
7
6
8
5
3
1
2
4
0
0
1
1
0
2
3
3
6
7
5
4
2
3
2
7
3
2
6
5
4
2
1
3
2
1
X7R 
25V 
0402V 
10% 
0.01UF 
A36096-045 
C6T1 
16 
17 
15 
17 
16 
14 
13 
11 
12 
10 
13 
14 
12 
9
11 
10 
9
8
7
6
5
7
8
4
6
5
4
3
2
1
0
2
3
1
0
42 
283 
281 
279 
276 
274 
272 
270 
268 
265 
263 
261 
259 
257 
254 
252 
250 
248 
246 
243 
241 
239 
202 
200 
198 
195 
193 
191 
189 
187 
184 
182 
180 
178 
176 
173 
171 
169 
167 
165 
162 
160 
158 
156 
154 
151 
149 
147 
138 
136 
134 
131 
129 
127 
125 
123 
120 
118 
116 
114 
112 
109 
107 
105 
103 
101 
98 
96 
94 
57 
55 
53 
50 
48 
46 
44 
39 
37 
35 
33 
31 
28 
26 
24 
22 
20 
17 
15 
13 
11 
9
6
4
2
SCONN 
H44441-003 
J6T1 
63 
61 
62 
60 
59 
58 79 
72 
216 
71 
214 
213 
69 
211 
68 
66 
225 
210 
65 
232 
228 
86 
82 
234 
62 
208 
81 
63 
207 
235 
49 
194 
56 
201 
47 
192 
54 
199 
75 
74 
219 
218 
60 
203 
5
150 
12 
157 
3
148 
10 
155 
16 
161 
23 
168 
14 
21 
34 
179 
25 
170 
32 
177 
38 
183 
45 
181 
43 
188 
97 
242 
104 
249 
95 
240 
102 
247 
108 
253 
115 
260 
106 
251 
113 
258 
119 
264 
271 
117 
262 
124 
269 
275 
282 
78 
87 
91 
222 
58 
205 
227 
144 
84 
89 
93 
237 
139 
140 
238 
230 
141 
285 
284 
146 
H44441-003 
J6T1 
57 
17 
16 
15 
14 
12 
11 
13 
152 
153 
163 
164 
174 
175 
185 
186 
245 
255 
256 
266 
267 
277 
278 
196 
197 
8
7
19 
18 
30 
29 
40 
99 
111 
110 
122 
121 
133 
52 
51 
SCONN 
H44441-003 
J6T1 
0
56 
55 
54 
52 
53 
51 
47 
48 
49 
46 
45 
43 
44 
42 
41 
40 
SMB_DDR_ABC_VPP_SDA 
23 43 23 43 
23 43 
23 43 
23 43 
21 43 45 46 47 48 
23 43 
43 45 46 47 48 49 50 51 52 53 
54 77 78 79 80 81 82 83 84 85 
86 87 88 94 
89 43 45 46 
47 48 
43 23 
23 43 
99 43 45 46 47 48 
98 43 
23 43 
23 43 
23 43 
23 43 
23 43 
23 43 
23 43 
23 43 
43 45 46 47 48 99 
BOM NOTE: 
DO NOT SCALE DRAWING 
SCONN288_H44441003 
SCONN288_H44441003 
SCONN288_H44441003 
SCONN288_H44441003 
SHEET 
B
AA
B
B
SIZE 
SCALE: 
234
1234
DEPARTMENT CODE 
1
DOCUMENT NUMBER REV 
PVDDQ_ABC 
IN 
OUT 
OUT 
IN 
PVPP_ABC 
IN 
IN 
IN 
IN 
IN 
IN 
IN 
P12V_NVDIMM_ABC 
BI 
BI 
IN 
IN 
IN 
BI 
IN 
BI IN 
PVPP_ABC 
PVTT_ABC 
IN 
BI 
44 OF 270 
Wed Feb 08 16:34:39 2017 
VDD<25> 
VDD<24> 
VDD<23> 
VDD<22> 
VDD<21> 
VDD<20> 
VDD<19> 
VDD<18> 
VDD<17> 
VDD<16> 
VDD<15> 
VDD<14> 
VDD<13> 
VDD<12> 
VDD<11> 
VDD<10> 
VDD<9> 
VDD<8> 
VDD<7> 
VDD<6> 
VDD<5> 
VDD<4> 
VDD<3> 
VDD<2> 
VDD<1> 
VDD<0> 
VPP<1> 
VPP<0> 
VTT<1> 
VTT<0> 
VPP<4> 
VPP<3> 
VPP<2> 12V<0> 12V<1> 
VSS<83> 
VSS<82> 
VSS<81> 
VSS<80> 
VSS<79> 
VSS<78> 
VSS<77> 
VSS<76> 
VSS<75> 
VSS<74> 
VSS<73> 
VSS<72> 
VSS<71> 
VSS<70> 
VSS<69> 
VSS<68> 
VSS<93> 
VSS<92> 
VSS<91> 
VSS<90> 
VSS<89> 
VSS<88> 
VSS<87> 
VSS<86> 
VSS<85> 
VSS<84> 
VSS<67> 
VSS<66> 
VSS<65> 
VSS<64> 
VSS<63> 
VSS<62> 
VSS<61> 
VSS<60> 
VSS<59> 
VSS<58> 
VSS<57> 
VSS<56> 
VSS<55> 
VSS<54> 
VSS<53> 
VSS<52> 
VSS<51> 
VSS<50> 
VSS<49> 
VSS<48> 
VSS<47> 
VSS<46> 
VSS<45> 
VSS<44> 
VSS<43> 
VSS<42> 
VSS<41> 
VSS<40> 
VSS<39> 
VSS<38> 
VSS<37> 
VSS<36> 
VSS<35> 
VSS<34> 
VSS<33> 
VSS<32> 
VSS<31> 
VSS<30> 
VSS<29> 
VSS<28> 
VSS<27> 
VSS<26> 
VSS<25> 
VSS<24> 
VSS<23> 
VSS<22> 
VSS<21> 
VSS<20> 
VSS<19> 
VSS<18> 
VSS<17> 
VSS<16> 
VSS<15> 
VSS<14> 
VSS<13> 
VSS<12> 
VSS<11> 
VSS<10> VSS<9> 
VSS<8> 
VSS<7> 
VSS<6> 
VSS<5> 
VSS<4> 
VSS<3> 
VSS<2> 
VSS<1> 
VSS<0> 
DQ<12> 
DQ<11> 
DQ<10> DQ<9> 
DQ<8> 
DQ<7> 
DQ<6> 
A17 
A16_RAS_N 
A15_CAS_N DQ<60> 
DQ<58> 
DQ<50> 
S3_N_C<1> 
S2_N_C<0> 
S1_N 
S0_N 
CKE<1> 
CKE<0> 
ODT<1> 
ODT<0> 
DQ<21> 
DQ<19> 
DQ<18> 
DQ<27> DQ<28> 
CB<5> 
CB<4> 
CB<3> 
CB<2> 
A8 
A7 
A6 
DQ<45> 
DQ<44> 
DQ<41> 
DQ<51> 
A2 
ALERT_N 
ACT_N 
VREFCA 
SCL SDA SA<0> SA<1> SA<2> 
VDDSPD 
DQ<1> DQ<2> 
RFU<2> 
DQ<31> DQ<32> 
DQ<33> DQ<34> DQ<35> DQ<36> DQ<37> DQ<38> 
A0 A1 
A10 A11 
A12 A13 A14_WE_N 
A3 A4 A5 
A9 
BG<1> 
C<2> 
CB<7> 
CB<6> 
CB<1> 
CB<0> 
DQ<63> 
DQ<62> 
DQ<61> 
DQ<59> 
DQ<57> 
DQ<56> 
DQ<55> 
DQ<54> 
DQ<53> 
DQ<52> 
DQ<49> 
DQ<48> 
DQ<47> 
DQ<46> 
DQ<43> 
DQ<40> 
DQ<39> 
DQ<30> 
DQ<26> 
DQ<25> 
DQ<24> 
DQ<23> 
DQ<22> 
DQ<20> 
DQ<17> 
DQ<16> 
DQ<15> 
DQ<14> 
DQ<13> 
DQ<5> 
DQ<4> 
DQ<3> 
DQ<0> 
EVENT_N 
PAR 
RESET_N 
RFU<1> 
RFU<0> 
SAVE_N_NC 
BG<0> 
CK1P 
CK1N 
CK0P 
CK0N 
DQ<29> 
DQ<42> BA<0> BA<1> 
DQS0N DQS0P 
DQS10N DQS10P DQS11N DQS11P DQS12N DQS12P DQS13N DQS13P DQS14N DQS14P DQS15N DQS15P DQS16N 
DQS16P DQS17N DQS17P 
DQS1N DQS1P DQS2N DQS2P DQS3N DQS3P 
DQS4N DQS4P DQS5N DQS5P DQS6N DQS6P DQS7N DQS7P DQS8N DQS8P DQS9N DQS9P 
PVDDQ (SINGLE SIDE) CAP: 10UF X1, 22UF X50 
PVDDQ (DOUBLE SIDE) CAP: 100UF X8, 47UF X41 
PVPP CAP: 10UF X12 
PVTT CAP: 100UF X2, 47UF X1 
PLACE CAP NEAR DIMM CONNECTOR 
BOM_SS=NOPOP 
BOM_SS=NOPOP 
BOM_SS=NOPOP 
BOM_SS=NOPOP 
UNSTUFF FOR SKU B 
CPU0 DDR4 CH A DIMM1 
CAP BETWEEN DIMM 
SMBUS ADDR: 0XA2 WIWYNN CORPORATION 
4/4 
3/4 
1/4 
2/4 



136 
M_B_DQ<63:0> 
116 
J4G2 
M_B_C<2> 
M_B_PAR 
M_ABC_RST_N 
FM_ADR_COMPLETE_ABC_N 
SMB_DDR_ABC_VPP_SCL 
M_B_ACT_N 
M_B_ALERT_N 
TP_CH_B_DIMM_B0_RFU_2 
TP_CH_B_DIMM_B0_RFU_0 
TP_CH_B_DIMM_B0_RFU_1 
M_B_VREF 
FM_DIMM_EVENT_COD_N 
M_B_ODT<3:0> 
M_B_CKE<3:0> 
M_B_CS_N<7:0> 
M_B_CLK_DP<3:0> 
M_B_BA<1:0> 
M_B_ECC<7:0> 
M_B_CLK_DN<3:0> 
M_B_BG<1:0> 
M_B_MA<17:0> 
M_B_DQS_DN<17:0> 
M_B_DQS_DP<17:0> 
13 
10 
14 
15 
12 
16 
17 
19 
18 
21 
15 
23 
20 
25 
24 
22 
27 
26 
31 
28 
29 
14 
30 
33 
32 
34 
35 
39 
36 
37 
41 
38 
16 
40 
43 
42 
45 
44 
49 
46 
47 
122 
152 
153 
163 
164 
174 
175 
185 
186 
244 
245 
255 
256 
266 
267 
277 
278 
196 
197 
8
7
19 
18 
30 
29 
41 
40 
100 
99 
111 
110 
121 
133 
132 
52 
51 
SCONN 
H44441-004 
J4G2 
48 
15 
51 
50 
52 
53 
57 
54 
55 
59 
56 
60 
16 
61 
58 
63 
62 
283 
281 
279 
276 
274 
272 
270 
268 
265 
263 
261 
259 
257 
254 
252 
250 
248 
246 
243 
241 
239 
202 
200 
198 
195 
193 
191 
189 
187 
184 
182 
180 
178 
176 
173 
171 
169 
167 
165 
162 
160 
158 
156 
154 
151 
149 
147 
138 
134 
131 
129 
127 
125 
123 
120 
118 
114 
112 
109 
107 
105 
103 
101 
98 
96 
94 
57 
55 
53 
50 
48 
46 
44 
42 
39 
37 
35 
33 
31 
28 
26 
24 
22 
20 
17 
15 
13 
11 
9
6
4
2
SCONN 
H44441-004 
J4G2 
0
0
17 
1
2
3
2
1
3
4
5
4
6
17 
5
6
7
8
8
7
9
10 
9
11 
10 
11 
0402V 
X7R 
25V 
10% 
0.01UF 
A36096-045 
C4G3 
SMB_DDR_ABC_VPP_SDA 
12 
145 
1
236 
233 
231 
229 
226 
223 
220 
217 
215 
212 
209 
206 
204 
92 
90 
88 
85 
83 
80 
76 
73 
70 
67 
64 
61 
59 
287 
286 
288 
143 
142 
221 
77 
SCONN 
H44441-004 
J4G2 
1
0
0
1
0
1
2
13 
3
0
1
0
1
13 
1
0
3
2
5
4
12 
7
6
1
0
0
1
0
1
2
3
4
5
6
7
8
9
10 
11 
12 
13 
14 
15 
16 
17 
H44441-004 
79 
72 
216 
71 
214 
213 
69 
211 
68 
66 
225 
210 
65 
232 
228 
86 
82 
234 
62 
208 
81 
224 
63 
207 
235 
49 
194 
56 
201 
47 
192 
54 
199 
75 
74 
219 
218 
60 
203 
5
150 
12 
157 
3
148 
10 
155 
16 
161 
23 
168 
14 
159 
21 
166 
27 
172 
34 
179 
25 
170 
32 
177 
38 
183 
45 
190 
36 
181 
43 
188 
97 
242 
104 
249 
95 
240 
102 
247 
108 
253 
115 
260 
106 
251 
113 
258 
119 
264 
126 
271 
117 
262 
124 
269 
130 
275 
137 
282 
128 
273 
135 
280 
78 
87 
91 
222 
58 
205 
227 
144 
84 
89 
93 
237 
139 
140 
238 
230 
141 
285 
284 
146 
SCONN 
1
3
0
2
5
6
7
4
8
11 
9
14 
24 46 
24 46 
24 46 
21 43 44 46 47 48 
89 43 44 46 47 48 
99 43 44 46 47 48 
24 46 
46 24 
98 46 
43 44 46 47 48 49 50 51 52 53 
54 77 78 79 80 81 82 83 84 
85 86 87 88 94 
24 46 
24 46 
24 46 
24 46 
24 46 
24 46 
24 46 
24 46 
24 46 
24 46 
24 46 
43 44 46 47 48 99 
BOM NOTE: 
1
2
DO NOT SCALE DRAWING 
SCONN288_H44441004 
SCONN288_H44441004 
SCONN288_H44441004 
SCONN288_H44441004 
SHEET 
B
AA
B
B
SIZE 
SCALE: 
234
1234
DEPARTMENT CODE 
1
DOCUMENT NUMBER REV 
BI 
BI 
P12V_NVDIMM_ABC 
IN 
PVPP_ABC 
PVPP_ABC 
OUT 
IN 
BI 
IN 
IN 
IN 
IN 
IN 
IN 
BI 
IN 
OUT 
IN 
IN 
IN 
IN 
IN 
PVDDQ_ABC 
IN 
PVTT_ABC 
BI 
45 OF 270 
Wed Feb 08 16:34:39 2017 
DQS9P DQS9N DQS8P DQS8N DQS7P DQS7N DQS6P DQS6N DQS5P DQS5N DQS4P DQS4N 
DQS3P DQS3N DQS2P DQS2N DQS1P DQS1N 
DQS17P DQS17N DQS16P 
DQS16N DQS15P DQS15N DQS14P DQS14N DQS13P DQS13N DQS12P DQS12N DQS11P DQS11N DQS10P DQS10N 
DQS0P DQS0N 
VSS<0> VSS<1> VSS<2> VSS<3> VSS<4> VSS<5> VSS<6> VSS<7> 
VSS<8> VSS<9> VSS<10> VSS<11> VSS<12> VSS<13> VSS<14> VSS<15> VSS<16> VSS<17> VSS<18> VSS<19> VSS<20> 
VSS<21> VSS<22> VSS<23> VSS<24> VSS<25> VSS<26> VSS<27> VSS<28> VSS<29> VSS<30> VSS<31> VSS<32> VSS<33> 
VSS<34> VSS<35> VSS<36> VSS<37> VSS<38> VSS<39> VSS<40> VSS<41> VSS<42> VSS<43> VSS<44> 
VSS<47> VSS<48> VSS<49> VSS<50> VSS<51> VSS<52> VSS<53> VSS<54> 
VSS<55> VSS<56> VSS<57> VSS<58> VSS<59> VSS<60> VSS<61> VSS<62> VSS<63> VSS<64> VSS<65> VSS<66> VSS<67> 
VSS<84> VSS<85> VSS<86> VSS<87> VSS<88> VSS<89> VSS<90> VSS<91> VSS<92> VSS<93> 
VSS<68> VSS<69> VSS<70> VSS<71> VSS<72> VSS<73> VSS<74> VSS<75> VSS<76> VSS<77> VSS<78> VSS<79> VSS<80> 
VSS<81> VSS<82> VSS<83> 
VSS<45> VSS<46> 
12V<0> VPP<2> 
VPP<4> 
VTT<0> VTT<1> 
VPP<0> VPP<1> 
VDD<0> 
VDD<1> VDD<2> VDD<3> VDD<4> VDD<5> VDD<6> VDD<7> VDD<8> VDD<9> VDD<10> VDD<11> VDD<12> VDD<13> 
VDD<14> VDD<15> VDD<16> VDD<17> VDD<18> VDD<19> VDD<20> VDD<21> VDD<22> VDD<23> VDD<24> VDD<25> 
12V<1> VPP<3> 
BA<1> 
BA<0> DQ<42> 
DQ<29> 
CK0N CK0P CK1N CK1P 
BG<0> 
SAVE_N_NC 
RFU<0> RFU<1> 
RESET_N PAR 
EVENT_N 
DQ<0> 
DQ<3> DQ<4> DQ<5> 
DQ<13> DQ<14> DQ<15> DQ<16> DQ<17> 
DQ<20> 
DQ<22> DQ<23> DQ<24> DQ<25> DQ<26> 
DQ<30> 
DQ<39> DQ<40> 
DQ<43> 
DQ<46> 
DQ<47> DQ<48> DQ<49> 
DQ<52> DQ<53> DQ<54> DQ<55> DQ<56> DQ<57> 
DQ<59> 
DQ<61> DQ<62> DQ<63> 
CB<0> CB<1> 
CB<6> CB<7> 
C<2> 
BG<1> 
A9 
A5 
A4 
A3 
A14_WE_N 
A13 
A12 
A11 
A10 
A1 
A0 
DQ<38> 
DQ<37> 
DQ<36> 
DQ<35> 
DQ<34> 
DQ<33> 
DQ<32> 
DQ<31> 
RFU<2> 
DQ<2> 
DQ<1> 
VDDSPD 
SA<2> 
SA<1> 
SA<0> 
SDA 
SCL 
VREFCA 
ACT_N ALERT_N 
A2 
DQ<51> 
DQ<41> 
DQ<44> DQ<45> 
A6 A7 A8 
CB<2> CB<3> CB<4> CB<5> 
DQ<28> 
DQ<27> 
DQ<18> DQ<19> 
DQ<21> 
ODT<0> ODT<1> 
CKE<0> CKE<1> 
S0_N S1_N S2_N_C<0> S3_N_C<1> 
DQ<50> 
DQ<58> 
DQ<60> A15_CAS_N A16_RAS_N A17 
DQ<6> DQ<7> 
DQ<8> DQ<9> DQ<10> DQ<11> DQ<12> 
PVDDQ (SINGLE SIDE) CAP: 10UF X1, 22UF X50 
PVTT CAP: 100UF X2, 47UF X1 PVPP CAP: 10UF X12 
PVDDQ (DOUBLE SIDE) CAP: 100UF X8, 47UF X41 
STUFF FOR SKU A & B 
CPU0 DDR4 CH B DIMM0 
CAP BETWEEN DIMM 
PLACE CAP NEAR DIMM CONNECTOR 
WIWYNN CORPORATION SMBUS ADDR: 0XA4 
2/4 
3/4 
4/4 1/4 



134 
M_B_MA<17:0> 
SCONN 
18 
M_B_DQ<63:0> 
J6U1 
J6U1 
H44441-003 
145 
53 
43 
45 
47 
46 
49 
48 
50 
51 
52 
H44441-003 
SCONN 
51 
52 
132 
133 
121 
122 
110 
111 
99 
100 
40 
41 
29 
30 
19 
7
8
197 
196 
278 
277 
267 
266 
245 
185 
175 
174 
164 
163 
153 
152 
186 
244 
256 
7
8
11 
10 
9
12 
13 
14 
16 
15 
17 
53 
55 
54 
57 
56 
SMB_DDR_ABC_VPP_SDA 
58 
59 
60 
61 
62 
63 
J6U1 
2
4
6
9
11 
13 
15 
17 
20 
22 
24 
26 
28 
31 
33 
35 
37 
39 
42 
44 
46 
48 
50 
55 
57 
94 
96 
98 
101 
103 
105 
107 
109 
112 
116 
118 
120 
123 
125 
127 
129 
131 
136 
138 
147 
149 
151 
154 
156 
158 
160 
162 
165 
167 
169 
171 
173 
176 
178 
180 
182 
184 
187 
189 
191 
193 
195 
198 
200 
202 
239 
241 
243 
246 
248 
250 
252 
254 
257 
259 
261 
263 
265 
268 
270 
272 
274 
276 
279 
281 
283 
SCONN 
87 
H44441-003 
146 
284 
285 
141 
230 
238 
140 
139 
237 
93 
89 
84 
144 
227 
205 
58 
222 
91 
78 
280 
135 
273 
128 
282 
137 
275 
130 
269 
124 
262 
117 
271 
126 
264 
119 
258 
113 
251 
106 
260 
115 
253 
108 
102 
240 
95 
249 
104 
242 
97 
188 
43 
181 
36 
190 
45 
183 
38 
177 
32 
170 
25 
179 
34 
172 
27 
21 
14 
23 
161 
16 
155 
10 
148 
3
157 
12 
150 
5
203 
60 
218 
219 
74 
75 
199 
54 
192 
47 
201 
56 
194 
49 
235 
207 
63 
224 
81 
208 
62 
234 
82 
86 
232 
65 
210 
225 
66 
68 
211 
69 
213 
214 
71 
216 
72 
79 
0
1
0
1
2
3
5
4
6
4
3
2
5
6
7
9
8
10 
11 
9
8
7
12 
10 
11 
12 
14 
13 
15 
16 
13 
14 
17 
15 
16 
17 
1
0
2
3
4
6
5
7
3
2
2
5
4
3
6
2
3
7
2
0
1
3
1
0
0
1
C6U9 
A36096-045 
0.01UF 
10% 
0402V 
25V 
X7R 
1
2
2
3
6
5
4
1
0
3
2
4
6
5
7
9
8
11 
10 
J6U1 
H44441-003 
SCONN 
77 
221 
142 
143 
288 
286 
287 
59 
61 
64 
67 
70 
73 
76 
80 
83 
85 
88 
90 
92 
204 
206 
209 
212 
215 
217 
220 
223 
226 
229 
231 
233 
236 
1
12 
14 
13 
16 
15 
17 
18 
19 
20 
22 
21 
23 
24 
25 
26 
27 
29 
28 
30 
31 
32 
33 
34 
35 
36 
40 
38 
39 
42 
41 
44 
M_B_ECC<7:0> 
M_B_CLK_DN<3:0> 
M_B_ODT<3:0> 
M_B_CKE<3:0> 
M_B_CS_N<7:0> 
M_B_CLK_DP<3:0> 
M_B_BA<1:0> 
M_B_BG<1:0> 
M_B_DQS_DN<17:0> 
M_B_DQS_DP<17:0> 
M_B_C<2> 
M_ABC_RST_N 
M_B_PAR 
FM_DIMM_EVENT_COD_N 
M_B_ACT_N 
M_B_ALERT_N 
SMB_DDR_ABC_VPP_SCL 
FM_ADR_COMPLETE_ABC_N 
TP_CH_B_DIMM_B1_RFU_2 
TP_CH_B_DIMM_B1_RFU_0 
TP_CH_B_DIMM_B1_RFU_1 
M_B_VREF 
228 
255 37 
114 168 
159 
166 
247 
24 45 24 45 
43 44 45 47 48 99 
24 45 
24 45 
24 45 
24 45 
24 45 
24 45 
24 45 
24 45 
24 45 
24 45 
24 45 
21 43 44 45 47 48 
24 45 
43 44 45 47 48 49 50 51 52 53 
54 77 78 79 80 81 82 83 84 
85 86 87 88 94 
24 45 
45 24 
99 43 44 45 47 48 
89 43 44 45 47 48 
98 45 
BOM NOTE: 
DO NOT SCALE DRAWING 
SCONN288_H44441003 
SCONN288_H44441003 
SCONN288_H44441003 
SCONN288_H44441003 
SHEET 
B
AA
B
B
SIZE 
SCALE: 
234
1234
DEPARTMENT CODE 
1
DOCUMENT NUMBER REV 
IN 
OUT 
IN 
OUT PVPP_ABC 
IN 
IN 
IN 
IN 
IN 
IN 
P12V_NVDIMM_ABC 
BI 
IN 
BI 
BI 
IN 
IN 
BI 
BI 
IN 
IN 
PVPP_ABC 
PVTT_ABC 
IN 
PVDDQ_ABC 
IN 
46 OF 270 
Wed Feb 08 16:34:40 2017 
VDD<25> 
VDD<24> 
VDD<23> 
VDD<22> 
VDD<21> 
VDD<20> 
VDD<19> 
VDD<18> 
VDD<17> 
VDD<16> 
VDD<15> 
VDD<14> 
VDD<13> 
VDD<12> 
VDD<11> 
VDD<10> 
VDD<9> 
VDD<8> 
VDD<7> 
VDD<6> 
VDD<5> 
VDD<4> 
VDD<3> 
VDD<2> 
VDD<1> 
VDD<0> 
VPP<1> 
VPP<0> 
VTT<1> 
VTT<0> 
VPP<4> 
VPP<3> 
VPP<2> 12V<0> 12V<1> 
DQ<12> 
DQ<11> 
DQ<10> DQ<9> 
DQ<8> 
DQ<7> 
DQ<6> 
A17 
A16_RAS_N 
A15_CAS_N DQ<60> 
DQ<58> 
DQ<50> 
S3_N_C<1> 
S2_N_C<0> 
S1_N 
S0_N 
CKE<1> 
CKE<0> 
ODT<1> 
ODT<0> 
DQ<21> 
DQ<19> 
DQ<18> 
DQ<27> DQ<28> 
CB<5> 
CB<4> 
CB<3> 
CB<2> 
A8 
A7 
A6 
DQ<45> 
DQ<44> 
DQ<41> 
DQ<51> 
A2 
ALERT_N 
ACT_N 
VREFCA 
SCL SDA SA<0> SA<1> SA<2> VDDSPD 
DQ<1> DQ<2> 
RFU<2> 
DQ<31> DQ<32> DQ<33> DQ<34> 
DQ<35> DQ<36> DQ<37> DQ<38> 
A0 A1 
A10 A11 A12 A13 
A14_WE_N 
A3 A4 A5 
A9 
BG<1> 
C<2> 
CB<7> 
CB<6> 
CB<1> 
CB<0> 
DQ<63> 
DQ<62> 
DQ<61> 
DQ<59> 
DQ<57> 
DQ<56> 
DQ<55> 
DQ<54> 
DQ<53> 
DQ<52> 
DQ<49> 
DQ<48> 
DQ<47> 
DQ<46> 
DQ<43> 
DQ<40> 
DQ<39> 
DQ<30> 
DQ<26> 
DQ<25> 
DQ<24> 
DQ<23> 
DQ<22> 
DQ<20> 
DQ<17> 
DQ<16> 
DQ<15> 
DQ<14> 
DQ<13> 
DQ<5> 
DQ<4> 
DQ<3> 
DQ<0> 
EVENT_N 
PAR 
RESET_N 
RFU<1> 
RFU<0> 
SAVE_N_NC 
BG<0> 
CK1P 
CK1N 
CK0P 
CK0N 
DQ<29> 
DQ<42> BA<0> BA<1> 
VSS<83> 
VSS<82> 
VSS<81> 
VSS<80> 
VSS<79> 
VSS<78> 
VSS<77> 
VSS<76> 
VSS<75> 
VSS<74> 
VSS<73> 
VSS<72> 
VSS<71> 
VSS<70> 
VSS<69> 
VSS<68> 
VSS<93> 
VSS<92> 
VSS<91> 
VSS<90> 
VSS<89> 
VSS<88> 
VSS<87> 
VSS<86> 
VSS<85> 
VSS<84> 
VSS<67> 
VSS<66> 
VSS<65> 
VSS<64> 
VSS<63> 
VSS<62> 
VSS<61> 
VSS<60> 
VSS<59> 
VSS<58> 
VSS<57> 
VSS<56> 
VSS<55> 
VSS<54> 
VSS<53> 
VSS<52> 
VSS<51> 
VSS<50> 
VSS<49> 
VSS<48> 
VSS<47> 
VSS<46> 
VSS<45> 
VSS<44> 
VSS<43> 
VSS<42> 
VSS<41> 
VSS<40> 
VSS<39> 
VSS<38> 
VSS<37> 
VSS<36> 
VSS<35> 
VSS<34> 
VSS<33> 
VSS<32> 
VSS<31> 
VSS<30> 
VSS<29> 
VSS<28> 
VSS<27> 
VSS<26> 
VSS<25> 
VSS<24> 
VSS<23> 
VSS<22> 
VSS<21> 
VSS<20> 
VSS<19> 
VSS<18> 
VSS<17> 
VSS<16> 
VSS<15> 
VSS<14> 
VSS<13> 
VSS<12> 
VSS<11> 
VSS<10> VSS<9> 
VSS<8> 
VSS<7> 
VSS<6> 
VSS<5> 
VSS<4> 
VSS<3> 
VSS<2> 
VSS<1> 
VSS<0> 
DQS0N DQS0P 
DQS10N 
DQS10P DQS11N DQS11P DQS12N DQS12P DQS13N DQS13P DQS14N DQS14P DQS15N DQS15P DQS16N DQS16P 
DQS17N DQS17P 
DQS1N DQS1P DQS2N DQS2P DQS3N DQS3P DQS4N 
DQS4P DQS5N DQS5P DQS6N DQS6P DQS7N DQS7P DQS8N DQS8P DQS9N DQS9P 
PVDDQ (SINGLE SIDE) CAP: 10UF X1, 22UF X50 
PVDDQ (DOUBLE SIDE) CAP: 100UF X8, 47UF X41 
PVTT CAP: 100UF X2, 47UF X1 PVPP CAP: 10UF X12 
BOM_SS=NOPOP 
BOM_SS=NOPOP 
BOM_SS=NOPOP 
BOM_SS=NOPOP 
UNSTUFF FOR SKU B 
CPU0 DDR4 CH B DIMM1 
CAP BETWEEN DIMM 
PLACE CAP NEAR DIMM CONNECTOR 
WIWYNN CORPORATION SMBUS ADDR: 0XA6 
4/4 1/4 
3/4 
2/4 



138 
118 
M_C_MA<17:0> 
12 65 
J4G3 
SCONN 
7
213 
113 
153 
28 
182 
M_C_DQ<63:0> 
M_C_C<2> 
M_C_PAR 
M_ABC_RST_N 
FM_DIMM_EVENT_COD_N 
FM_ADR_COMPLETE_ABC_N 
SMB_DDR_ABC_VPP_SCL 
M_C_ACT_N 
M_C_ALERT_N 
TP_CH_C_DIMM_C0_RFU_2 
TP_CH_C_DIMM_C0_RFU_0 
TP_CH_C_DIMM_C0_RFU_1 
M_C_VREF 
M_C_ODT<3:0> 
M_C_BG<1:0> 
M_C_CKE<3:0> 
M_C_ECC<7:0> 
M_C_CS_N<7:0> 
M_C_BA<1:0> 
M_C_CLK_DP<3:0> 
M_C_CLK_DN<3:0> 
M_C_DQS_DP<17:0> 
M_C_DQS_DN<17:0> 
13 
10 
14 
15 
12 
16 
17 
19 
18 
21 
15 
23 
20 
25 
24 
22 
27 
26 
31 
28 
29 
14 
30 
33 
32 
34 
35 
39 
36 
37 
41 
38 
16 
40 
43 
42 
45 
44 
49 
46 
47 
40 
152 
163 
164 
174 
175 
185 
186 
244 
245 
255 
256 
266 
267 
277 
278 
196 
197 
8
7
19 
18 
30 
29 
41 
100 
99 
111 
110 
122 
121 
133 
132 
52 
51 
SCONN 
H44441-004 
J4G3 
48 
15 
51 
50 
52 
53 
57 
54 
55 
59 
56 
60 
16 
61 
58 
63 
62 
283 
281 
279 
276 
274 
272 
270 
268 
265 
263 
261 
259 
257 
254 
252 
250 
248 
246 
243 
241 
239 
202 
200 
198 
195 
193 
191 
189 
187 
184 
180 
178 
176 
173 
171 
169 
167 
165 
162 
160 
158 
156 
154 
151 
149 
147 
136 
134 
131 
129 
127 
125 
123 
120 
116 
114 
112 
109 
107 
105 
103 
101 
98 
96 
94 
57 
55 
53 
50 
48 
46 
44 
42 
39 
37 
35 
33 
31 
26 
24 
22 
20 
17 
15 
13 
11 
9
6
4
2
SCONN 
H44441-004 
J4G3 
0
0
17 
1
2
3
2
1
3
4
5
4
6
17 
5
6
7
8
8
7
9
10 
9
11 
1
1
10 
2
1
X7R 
25V 
0402V 
10% 
0.01UF 
A36096-045 
C4G19 
SMB_DDR_ABC_VPP_SDA 
11 
145 
1
236 
233 
231 
229 
226 
223 
220 
217 
215 
212 
209 
206 
204 
92 
90 
88 
85 
83 
80 
76 
73 
70 
67 
64 
61 
59 
287 
286 
288 
143 
142 
221 
77 
SCONN 
H44441-004 
J4G3 
0
0
12 
0
1
2
13 
3
0
1
1
0
13 
1
0
3
2
5
4
12 
7
6
1
0
0
1
0
1
2
3
4
5
6
8
9
10 
11 
13 
14 
15 
16 
17 
79 
72 
216 
71 
214 
69 
211 
68 
66 
225 
210 
232 
228 
86 
82 
234 
62 
208 
81 
224 
63 
207 
235 
49 
194 
56 
201 
47 
192 
54 
199 
75 
74 
219 
218 
60 
203 
5
150 
12 
157 
3
148 
10 
155 
16 
161 
23 
168 
14 
159 
21 
166 
27 
172 
34 
179 
25 
170 
32 
177 
38 
183 
45 
190 
36 
181 
43 
188 
97 
242 
104 
249 
95 
240 
102 
247 
108 
253 
115 
260 
106 
251 
258 
119 
264 
126 
271 
117 
262 
124 
269 
130 
275 
137 
282 
128 
273 
135 
280 
78 
87 
91 
222 
58 
205 
227 
144 
84 
89 
93 
237 
139 
140 
238 
230 
141 
285 
284 
146 
H44441-004 
1
3
0
2
5
6
7
4
8
11 
9
14 
25 48 25 48 
25 48 
25 48 
21 43 44 45 46 48 
43 44 45 46 48 49 50 51 52 53 
54 77 78 79 80 81 82 83 84 
85 86 87 88 94 
89 43 44 45 46 48 
99 43 44 45 46 48 
25 48 
48 25 
98 48 
25 48 
25 48 
25 48 
25 48 
25 48 
25 48 
25 48 
25 48 
25 48 
25 48 
43 44 45 46 48 99 
BOM NOTE: 
DO NOT SCALE DRAWING 
SCONN288_H44441004 
SCONN288_H44441004 
SCONN288_H44441004 
SCONN288_H44441004 
SHEET 
B
AA
B
B
SIZE 
SCALE: 
234
1234
DEPARTMENT CODE 
1
DOCUMENT NUMBER REV 
BI 
BI 
P12V_NVDIMM_ABC 
IN 
PVPP_ABC 
PVPP_ABC 
BI 
IN 
OUT 
IN 
IN 
IN 
IN 
IN 
IN 
BI 
IN 
OUT 
IN 
IN 
IN 
IN 
IN 
PVDDQ_ABC 
IN 
PVTT_ABC 
BI 
47 OF 270 
Wed Feb 08 16:34:40 2017 
DQS9P 
DQS9N DQS8P DQS8N DQS7P DQS7N DQS6P DQS6N DQS5P DQS5N DQS4P DQS4N DQS3P 
DQS3N DQS2P DQS2N DQS1P DQS1N 
DQS17P DQS17N DQS16P DQS16N 
DQS15P DQS15N DQS14P DQS14N DQS13P DQS13N DQS12P DQS12N DQS11P DQS11N DQS10P DQS10N 
DQS0P DQS0N 
VSS<0> VSS<1> VSS<2> VSS<3> VSS<4> VSS<5> VSS<6> 
VSS<7> VSS<8> VSS<9> VSS<10> VSS<11> VSS<12> VSS<13> VSS<14> VSS<15> VSS<16> VSS<17> VSS<18> VSS<19> 
VSS<20> VSS<21> VSS<22> VSS<23> VSS<24> VSS<25> VSS<26> VSS<27> VSS<28> VSS<29> VSS<30> VSS<31> VSS<32> 
VSS<33> VSS<34> VSS<35> VSS<36> VSS<37> VSS<38> VSS<39> VSS<40> VSS<41> VSS<42> VSS<43> VSS<44> 
VSS<47> VSS<48> VSS<49> VSS<50> VSS<51> VSS<52> VSS<53> 
VSS<54> VSS<55> VSS<56> VSS<57> VSS<58> VSS<59> VSS<60> VSS<61> VSS<62> VSS<63> VSS<64> VSS<65> VSS<66> 
VSS<67> 
VSS<84> VSS<85> VSS<86> VSS<87> VSS<88> VSS<89> VSS<90> VSS<91> VSS<92> 
VSS<93> 
VSS<68> VSS<69> VSS<70> VSS<71> VSS<72> VSS<73> VSS<74> VSS<75> VSS<76> VSS<77> VSS<78> VSS<79> 
VSS<80> VSS<81> VSS<82> VSS<83> 
VSS<45> 
VSS<46> 
12V<0> VPP<2> 
VPP<4> 
VTT<0> VTT<1> 
VPP<0> VPP<1> 
VDD<0> VDD<1> VDD<2> VDD<3> VDD<4> VDD<5> VDD<6> VDD<7> VDD<8> VDD<9> VDD<10> VDD<11> VDD<12> 
VDD<13> VDD<14> VDD<15> VDD<16> VDD<17> VDD<18> VDD<19> VDD<20> VDD<21> VDD<22> VDD<23> VDD<24> VDD<25> 
12V<1> VPP<3> 
BA<1> 
BA<0> DQ<42> 
DQ<29> 
CK0N CK0P CK1N CK1P 
BG<0> 
SAVE_N_NC 
RFU<0> RFU<1> 
RESET_N PAR 
EVENT_N 
DQ<0> 
DQ<3> DQ<4> DQ<5> 
DQ<13> DQ<14> DQ<15> DQ<16> DQ<17> 
DQ<20> 
DQ<22> DQ<23> DQ<24> DQ<25> DQ<26> 
DQ<30> 
DQ<39> DQ<40> 
DQ<43> 
DQ<46> DQ<47> DQ<48> DQ<49> 
DQ<52> DQ<53> DQ<54> DQ<55> DQ<56> DQ<57> 
DQ<59> 
DQ<61> DQ<62> DQ<63> 
CB<0> CB<1> 
CB<6> CB<7> 
C<2> 
BG<1> 
A9 
A5 
A4 
A3 
A14_WE_N 
A13 
A12 
A11 
A10 
A1 
A0 
DQ<38> 
DQ<37> 
DQ<36> 
DQ<35> 
DQ<34> 
DQ<33> 
DQ<32> 
DQ<31> 
RFU<2> 
DQ<2> 
DQ<1> 
VDDSPD 
SA<2> 
SA<1> 
SA<0> 
SDA 
SCL 
VREFCA 
ACT_N ALERT_N 
A2 
DQ<51> 
DQ<41> 
DQ<44> DQ<45> 
A6 A7 A8 
CB<2> CB<3> CB<4> 
CB<5> 
DQ<28> 
DQ<27> 
DQ<18> DQ<19> 
DQ<21> 
ODT<0> ODT<1> 
CKE<0> CKE<1> 
S0_N S1_N S2_N_C<0> 
S3_N_C<1> 
DQ<50> 
DQ<58> 
DQ<60> A15_CAS_N A16_RAS_N A17 
DQ<6> 
DQ<7> DQ<8> DQ<9> DQ<10> DQ<11> DQ<12> 
PVDDQ (SINGLE SIDE) CAP: 10UF X1, 22UF X50 PVTT CAP: 100UF X2, 47UF X1 PVPP CAP: 10UF X12 
PVDDQ (DOUBLE SIDE) CAP: 100UF X8, 47UF X41 
STUFF FOR SKU A & B 
CPU0 DDR4 CH C DIMM0 
CAP BETWEEN DIMM 
SMBUS ADDR: 0XA8 
PLACE CAP NEAR DIMM CONNECTOR 
WIWYNN CORPORATION 
2/4 
3/4 
4/4 1/4 



136 
165 
M_C_DQ<63:0> 
H44441-003 
SCONN 
M_C_DQS_DP<17:0> 
M_C_DQS_DN<17:0> 
249 
104 
206 
116 
31 
M_C_MA<17:0> 
7
214 
71 
216 
72 
79 
224 
81 
M_C_C<2> 
10% 
A36096-045 
106 
38 
37 
68 
M_C_VREF 
TP_CH_C_DIMM_C1_RFU_2 
TP_CH_C_DIMM_C1_RFU_0 
TP_CH_C_DIMM_C1_RFU_1 
SMB_DDR_ABC_VPP_SCL 
SMB_DDR_ABC_VPP_SDA 
FM_ADR_COMPLETE_ABC_N 
FM_DIMM_EVENT_COD_N 
M_C_PAR 
M_ABC_RST_N 
M_C_ALERT_N 
M_C_ACT_N 
M_C_ODT<3:0> 
M_C_BG<1:0> 
M_C_CKE<3:0> 
M_C_ECC<7:0> 
M_C_CS_N<7:0> 
M_C_CLK_DP<3:0> 
M_C_CLK_DN<3:0> 
M_C_BA<1:0> 
12 
11 
15 
14 
13 
17 
16 
18 
19 
20 
15 
22 
21 
24 
25 
23 
26 
27 
30 
29 
28 
14 
32 
33 
35 
34 
36 
40 
39 
16 
41 
42 
43 
44 
45 
48 
47 
46 
152 
153 
163 
164 
174 
175 
185 
186 
244 
245 
255 
256 
266 
267 
278 
196 
197 
8
7
19 
18 
30 
29 
41 
40 
100 
99 
111 
110 
122 
121 
133 
132 
52 
51 
SCONN 
J6U2 
277 
49 
15 
50 
51 
53 
52 
56 
55 
54 
58 
57 
61 
16 
60 
59 
62 
63 
283 
281 
279 
276 
274 
272 
270 
268 
265 
263 
261 
259 
257 
254 
252 
250 
248 
246 
243 
241 
239 
202 
200 
198 
195 
193 
191 
189 
187 
184 
182 
180 
178 
176 
173 
171 
169 
167 
162 
160 
158 
156 
154 
151 
149 
147 
138 
134 
131 
129 
127 
125 
123 
120 
118 
114 
112 
109 
107 
105 
103 
101 
98 
96 
94 
57 
55 
53 
50 
48 
46 
44 
42 
39 
37 
35 
33 
31 
28 
26 
24 
22 
20 
17 
15 
13 
11 
9
6
4
2
SCONN 
H44441-003 
J6U2 
0
0
17 
1
2
3
2
1
3
4
5
4
6
17 
5
6
7
8
8
7
9
10 
9
11 
10 
11 
2
1
X7R 
25V 
0402V 
0.01UF 
C6U17 
SCONN 
H44441-003 
145 
1
236 
233 
231 
229 
226 
223 
220 
217 
215 
212 
209 
204 
92 
90 
88 
85 
83 
80 
76 
73 
70 
67 
64 
61 
59 
287 
286 
288 
143 
142 
221 
77 
J6U2 
12 
2
3
2
3
4
5
13 
6
7
2
3
2
3
13 
0
1
2
3
4
5
12 
6
7
1
0
0
1
0
1
2
3
4
5
6
8
9
10 
11 
12 
13 
14 
15 
16 
17 
234 
269 
J6U2 
213 
69 
211 
66 
225 
210 
65 
232 
228 
86 
82 
62 
208 
63 
207 
235 
49 
194 
56 
201 
47 
192 
54 
199 
75 
74 
219 
218 
60 
203 
5
150 
12 
157 
3
148 
10 
155 
16 
161 
23 
168 
14 
159 
21 
166 
27 
172 
34 
179 
25 
170 
32 
177 
38 
183 
45 
190 
36 
181 
43 
188 
97 
242 
95 
240 
102 
247 
108 
253 
115 
260 
251 
113 
258 
119 
264 
126 
271 
117 
262 
124 
130 
275 
137 
282 
128 
273 
135 
280 
78 
87 
91 
222 
58 
205 
227 
144 
84 
89 
93 
237 
139 
140 
238 
230 
141 
285 
284 
146 
H44441-003 
0
2
1
3
4
7
6
5
9
10 
8
14 
25 47 
25 47 
25 47 
25 47 
25 47 
98 47 
99 43 44 45 46 47 
43 44 45 46 47 99 
89 43 44 45 46 47 
43 44 45 46 47 49 50 51 52 53 
54 77 78 79 80 81 82 83 84 
85 86 87 88 94 
25 47 
21 43 44 45 46 47 
47 25 
25 47 
25 47 
25 47 
25 47 
25 47 
25 47 
25 47 
25 47 
25 47 
BOM NOTE: 
DO NOT SCALE DRAWING 
SCONN288_H44441003 
SCONN288_H44441003 
SCONN288_H44441003 
SCONN288_H44441003 
SHEET 
B
AA
B
B
SIZE 
SCALE: 
234
1234
DEPARTMENT CODE 
1
DOCUMENT NUMBER REV 
BI 
BI 
P12V_NVDIMM_ABC 
IN 
PVPP_ABC 
PVPP_ABC 
OUT 
BI 
IN 
IN 
IN 
IN 
IN 
IN 
IN 
BI 
IN 
OUT 
IN 
IN 
IN 
IN 
IN 
PVDDQ_ABC 
IN 
PVTT_ABC 
BI 
48 OF 270 
DQS0N DQS0P 
DQS10N DQS10P DQS11N DQS11P DQS12N DQS12P DQS13N DQS13P DQS14N DQS14P DQS15N DQS15P DQS16N 
DQS16P DQS17N DQS17P 
DQS1N DQS1P DQS2N DQS2P DQS3N DQS3P 
DQS4N DQS4P DQS5N DQS5P DQS6N DQS6P DQS7N DQS7P DQS8N DQS8P DQS9N DQS9P 
VSS<83> 
VSS<82> 
VSS<81> 
VSS<80> 
VSS<79> 
VSS<78> 
VSS<77> 
VSS<76> 
VSS<75> 
VSS<74> 
VSS<73> 
VSS<72> 
VSS<71> 
VSS<70> 
VSS<69> 
VSS<68> 
VSS<93> 
VSS<92> 
VSS<91> 
VSS<90> 
VSS<89> 
VSS<88> 
VSS<87> 
VSS<86> 
VSS<85> 
VSS<84> 
VSS<67> 
VSS<66> 
VSS<65> 
VSS<64> 
VSS<63> 
VSS<62> 
VSS<61> 
VSS<60> 
VSS<59> 
VSS<58> 
VSS<57> 
VSS<56> 
VSS<55> 
VSS<54> 
VSS<53> 
VSS<52> 
VSS<51> 
VSS<50> 
VSS<49> 
VSS<48> 
VSS<47> 
VSS<46> 
VSS<45> 
VSS<44> 
VSS<43> 
VSS<42> 
VSS<41> 
VSS<40> 
VSS<39> 
VSS<38> 
VSS<37> 
VSS<36> 
VSS<35> 
VSS<34> 
VSS<33> 
VSS<32> 
VSS<31> 
VSS<30> 
VSS<29> 
VSS<28> 
VSS<27> 
VSS<26> 
VSS<25> 
VSS<24> 
VSS<23> 
VSS<22> 
VSS<21> 
VSS<20> 
VSS<19> 
VSS<18> 
VSS<17> 
VSS<16> 
VSS<15> 
VSS<14> 
VSS<13> 
VSS<12> 
VSS<11> 
VSS<10> VSS<9> 
VSS<8> 
VSS<7> 
VSS<6> 
VSS<5> 
VSS<4> 
VSS<3> 
VSS<2> 
VSS<1> 
VSS<0> 
VDD<25> 
VDD<24> 
VDD<23> 
VDD<22> 
VDD<21> 
VDD<20> 
VDD<19> 
VDD<18> 
VDD<17> 
VDD<16> 
VDD<15> 
VDD<14> 
VDD<13> 
VDD<12> 
VDD<11> 
VDD<10> 
VDD<9> 
VDD<8> 
VDD<7> 
VDD<6> 
VDD<5> 
VDD<4> 
VDD<3> 
VDD<2> 
VDD<1> 
VDD<0> 
VPP<1> 
VPP<0> 
VTT<1> 
VTT<0> 
VPP<4> 
VPP<3> 
VPP<2> 12V<0> 12V<1> 
DQ<12> 
DQ<11> 
DQ<10> DQ<9> 
DQ<8> 
DQ<7> 
DQ<6> 
A17 
A16_RAS_N 
A15_CAS_N DQ<60> 
DQ<58> 
DQ<50> 
S3_N_C<1> 
S2_N_C<0> 
S1_N 
S0_N 
CKE<1> 
CKE<0> 
ODT<1> 
ODT<0> 
DQ<21> 
DQ<19> 
DQ<18> 
DQ<27> DQ<28> 
CB<5> 
CB<4> 
CB<3> 
CB<2> 
A8 
A7 
A6 
DQ<45> 
DQ<44> 
DQ<41> 
DQ<51> 
A2 
ALERT_N 
ACT_N 
VREFCA 
SCL 
SDA SA<0> SA<1> SA<2> VDDSPD 
DQ<1> DQ<2> 
RFU<2> 
DQ<31> DQ<32> DQ<33> DQ<34> DQ<35> DQ<36> DQ<37> DQ<38> 
A0 A1 
A10 A11 A12 A13 A14_WE_N 
A3 A4 A5 
A9 
BG<1> 
C<2> 
CB<7> 
CB<6> 
CB<1> 
CB<0> 
DQ<63> 
DQ<62> 
DQ<61> 
DQ<59> 
DQ<57> 
DQ<56> 
DQ<55> 
DQ<54> 
DQ<53> 
DQ<52> 
DQ<49> 
DQ<48> 
DQ<47> 
DQ<46> 
DQ<43> 
DQ<40> 
DQ<39> 
DQ<30> 
DQ<26> 
DQ<25> 
DQ<24> 
DQ<23> 
DQ<22> 
DQ<20> 
DQ<17> 
DQ<16> 
DQ<15> 
DQ<14> 
DQ<13> 
DQ<5> 
DQ<4> 
DQ<3> 
DQ<0> 
EVENT_N 
PAR 
RESET_N 
RFU<1> 
RFU<0> 
SAVE_N_NC 
BG<0> 
CK1P 
CK1N 
CK0P 
CK0N 
DQ<29> 
DQ<42> BA<0> BA<1> 
PVDDQ (SINGLE SIDE) CAP: 10UF X1, 22UF X50 PVTT CAP: 100UF X2, 47UF X1 
PVDDQ (DOUBLE SIDE) CAP: 100UF X8, 47UF X41 
PVPP CAP: 10UF X12 
BOM_SS=NOPOP 
BOM_SS=NOPOP 
BOM_SS=NOPOP 
BOM_SS=NOPOP 
Wed Feb 08 16:34:41 2017 
UNSTUFF FOR SKU B 
CPU0 DDR4 CH C DIMM1 
CAP BETWEEN DIMM 
SMBUS ADDR: 0XAA 
PLACE CAP NEAR DIMM CONNECTOR 
WIWYNN CORPORATION 
2/4 
3/4 
4/4 
1/4 



129 
FM_ADR_COMPLETE_DEF_N 
TP_CH_D_DIMM_D0_RFU_0 
TP_CH_D_DIMM_D0_RFU_1 
TP_CH_D_DIMM_D0_RFU_2 
M_D_VREF 
SMB_DDR_DEF_VPP_SCL 
SMB_DDR_DEF_VPP_SDA 
146 
284 
108 
109 
230 
140 
238 
FM_DIMM_EVENT_COD_N 
47 
M_D_ALERT_N 
M_D_C<2> 
M_D_PAR 
M_DEF_RST_N 
M_D_ACT_N 
M_D_ODT<3:0> 
M_D_ECC<7:0> 
M_D_CS_N<7:0> 
M_D_CKE<3:0> 
M_D_CLK_DN<3:0> 
M_D_CLK_DP<3:0> 
M_D_MA<17:0> 
M_D_BA<1:0> 
M_D_BG<1:0> 
M_D_DQ<63:0> 
M_D_DQS_DP<17:0> 
M_D_DQS_DN<17:0> 
10 
12 
13 
15 
14 
16 
17 
19 
18 
21 
12 
20 
22 
23 
24 
25 
27 
29 
26 
31 
30 
14 
28 
33 
32 
34 
35 
37 
36 
39 
40 
38 
13 
41 
43 
42 
152 
153 
163 
164 
174 
175 
185 
186 
244 
245 
255 
256 
266 
267 
277 
278 
196 
197 
8
7
19 
18 
30 
29 
41 
40 
100 
99 
111 
110 
122 
121 
133 
132 
52 
51 
SCONN 
H44441-004 
J4B1 
45 
44 
47 
49 
46 
48 
15 
51 
50 
53 
55 
52 
54 
57 
59 
56 
58 
16 60 
61 
63 
62 
J4B1 
283 
281 
279 
276 
274 
272 
270 
268 
265 
263 
261 
259 
257 
254 
252 
250 
248 
246 
243 
241 
239 
202 
200 
198 
195 
193 
191 
189 
187 
184 
182 
180 
178 
176 
173 
171 
169 
167 
165 
162 
160 
158 
156 
154 
151 
149 
147 
138 
136 
134 
131 
127 
125 
123 
120 
118 
116 
114 
112 
107 
105 
103 
101 
98 
96 
94 
57 
55 
53 
50 
48 
46 
44 
42 
39 
37 
35 
33 
31 
28 
26 
24 
22 
20 
17 
15 
13 
11 
9
6
4
2
SCONN 
H44441-004 
0
1
17 
0
1
2
3
5
4
2
3
4
5
17 
6
7
6
8
10 
9
7
8
9
10 
11 
0402V 
X7R 
25V 
10% 
0.01UF 
A36096-045 
C4B12 
145 
1
236 
233 
231 
229 
226 
223 
220 
217 
215 
212 
209 
206 
204 
92 
90 
88 
85 
83 
80 
76 
73 
70 
67 
64 
61 
59 
287 
286 
288 
143 
142 
221 
77 
SCONN 
H44441-004 
J4B1 
0
1
0
1
0
1
2
3
0
1
0
1
12 
1
0
3
2
5
4
11 
6
7
0
1
0
1
13 
0
1
2
3
4
5
6
7
8
9
14 
10 
11 
12 
13 
14 
15 
16 
17 228 
H44441-004 
12 
227 
144 
285 
139 
207 
216 
86 
137 
79 
72 
71 
214 
213 
69 
211 
68 
66 
225 
210 
65 
232 
82 
234 
62 
208 
81 
224 
63 
235 
49 
194 
56 
201 
192 
54 
199 
75 
74 
219 
218 
60 
203 
5
150 
157 
3
148 
10 
155 
16 
161 
23 
168 
14 
159 
21 
166 
27 
172 
34 
179 
25 
170 
32 
177 
38 
183 
45 
190 
36 
181 
43 
188 
97 
242 
104 
249 
95 
240 
102 
247 
253 
115 
260 
106 
251 
113 
258 
119 
264 
126 
271 
117 
262 
124 
269 
130 
275 
282 
128 
273 
135 
280 
78 
87 
91 
222 
58 
205 
84 
89 
93 
237 
141 
SCONN 
J4B1 
1
15 
3
0
5
2
4
7
9
6
8
11 
16 
89 50 51 52 53 54 
98 50 
99 50 51 52 53 54 
50 51 52 53 54 99 
43 44 45 46 47 48 50 51 52 53 
54 77 78 79 80 81 82 83 84 85 
86 87 88 94 
50 26 
26 50 
26 50 
21 50 51 52 53 54 
26 50 
26 50 
26 50 
26 50 
26 50 
26 50 
26 50 
26 
50 
26 50 
26 50 
26 50 
26 50 
26 50 
BOM NOTE: 
1
2
DO NOT SCALE DRAWING 
SCONN288_H44441004 
SCONN288_H44441004 
SCONN288_H44441004 
SCONN288_H44441004 
SHEET 
B
AA
B
B
SIZE 
SCALE: 
234
1234
DEPARTMENT CODE 
1
DOCUMENT NUMBER REV 
BI BI 
P12V_NVDIMM_DEF 
IN 
PVPP_DEF 
PVPP_DEF 
OUT 
IN 
BI 
PVTT_DEF 
IN 
IN 
IN 
PVDDQ_DEF 
IN 
IN 
IN 
BI 
IN 
OUT 
IN 
IN 
IN 
IN 
IN 
IN 
BI 
49 OF 270 
Wed Feb 08 16:34:41 2017 
DQS9P 
DQS9N DQS8P DQS8N DQS7P DQS7N DQS6P DQS6N DQS5P DQS5N DQS4P DQS4N DQS3P 
DQS3N DQS2P DQS2N DQS1P DQS1N 
DQS17P DQS17N DQS16P DQS16N 
DQS15P DQS15N DQS14P DQS14N DQS13P DQS13N DQS12P DQS12N DQS11P DQS11N DQS10P DQS10N 
DQS0P DQS0N 
VSS<0> VSS<1> VSS<2> VSS<3> VSS<4> VSS<5> VSS<6> VSS<7> VSS<8> VSS<9> VSS<10> 
VSS<11> VSS<12> VSS<13> VSS<14> VSS<15> VSS<16> VSS<17> VSS<18> VSS<19> VSS<20> VSS<21> VSS<22> VSS<23> 
VSS<24> VSS<25> VSS<26> VSS<27> VSS<28> VSS<29> VSS<30> VSS<31> VSS<32> VSS<33> VSS<34> VSS<35> VSS<36> 
VSS<37> VSS<38> VSS<39> VSS<40> VSS<41> VSS<42> VSS<43> VSS<44> 
VSS<47> VSS<48> VSS<49> VSS<50> VSS<51> VSS<52> VSS<53> VSS<54> VSS<55> VSS<56> VSS<57> 
VSS<58> VSS<59> VSS<60> VSS<61> VSS<62> VSS<63> VSS<64> VSS<65> VSS<66> VSS<67> 
VSS<84> VSS<85> VSS<86> VSS<87> VSS<88> VSS<89> VSS<90> VSS<91> VSS<92> VSS<93> 
VSS<68> VSS<69> VSS<70> 
VSS<71> VSS<72> VSS<73> VSS<74> VSS<75> VSS<76> VSS<77> VSS<78> VSS<79> VSS<80> VSS<81> VSS<82> VSS<83> 
VSS<45> VSS<46> 
12V<0> VPP<2> 
VPP<4> 
VTT<0> 
VTT<1> 
VPP<0> VPP<1> 
VDD<0> VDD<1> 
VDD<2> VDD<3> VDD<4> VDD<5> VDD<6> VDD<7> VDD<8> VDD<9> VDD<10> VDD<11> VDD<12> VDD<13> VDD<14> 
VDD<15> VDD<16> VDD<17> VDD<18> VDD<19> VDD<20> VDD<21> VDD<22> VDD<23> VDD<24> VDD<25> 
12V<1> VPP<3> 
BA<1> 
BA<0> DQ<42> 
DQ<29> 
CK0N CK0P CK1N CK1P 
BG<0> 
SAVE_N_NC 
RFU<0> 
RFU<1> 
RESET_N PAR 
EVENT_N 
DQ<0> 
DQ<3> DQ<4> DQ<5> 
DQ<13> DQ<14> DQ<15> DQ<16> DQ<17> 
DQ<20> 
DQ<22> 
DQ<23> DQ<24> DQ<25> DQ<26> 
DQ<30> 
DQ<39> DQ<40> 
DQ<43> 
DQ<46> DQ<47> 
DQ<48> DQ<49> 
DQ<52> DQ<53> DQ<54> DQ<55> DQ<56> DQ<57> 
DQ<59> 
DQ<61> DQ<62> DQ<63> 
CB<0> CB<1> 
CB<6> CB<7> 
C<2> 
BG<1> 
A9 
A5 
A4 
A3 
A14_WE_N 
A13 
A12 
A11 
A10 
A1 
A0 
DQ<38> 
DQ<37> 
DQ<36> 
DQ<35> 
DQ<34> 
DQ<33> 
DQ<32> 
DQ<31> 
RFU<2> 
DQ<2> 
DQ<1> 
VDDSPD 
SA<2> 
SA<1> 
SA<0> 
SDA 
SCL 
VREFCA 
ACT_N 
ALERT_N 
A2 
DQ<51> 
DQ<41> 
DQ<44> DQ<45> 
A6 A7 A8 
CB<2> CB<3> CB<4> CB<5> 
DQ<28> 
DQ<27> 
DQ<18> DQ<19> 
DQ<21> 
ODT<0> ODT<1> 
CKE<0> CKE<1> 
S0_N S1_N S2_N_C<0> S3_N_C<1> 
DQ<50> 
DQ<58> 
DQ<60> 
A15_CAS_N A16_RAS_N A17 
DQ<6> DQ<7> DQ<8> DQ<9> 
DQ<10> DQ<11> DQ<12> 
PVDDQ (SINGLE SIDE) CAP: 10UF X1, 22UF X50 
PVDDQ (DOUBLE SIDE) CAP: 100UF X8, 47UF X41 
PVTT CAP: 100UF X2, 47UF X1 PVPP CAP: 10UF X12 
STUFF FOR SKU A & B 
CPU0 DDR4 CH D DIMM0 
CAP BETWEEN DIMM 
SMBUS ADDR: 0XA0 
PLACE CAP NEAR DIMM CONNECTOR 
WIWYNN CORPORATION 
2/4 
3/4 
4/4 
1/4 



27 
172 
18 
H44441-003 
FM_ADR_COMPLETE_DEF_N 
58 
282 
128 
J6M1 
SCONN 
124 
153 
239 
40 
117 
271 
126 
109 
105 
TP_CH_D_DIMM_D1_RFU_0 
H44441-003 215 
206 
FM_DIMM_EVENT_COD_N 
TP_CH_D_DIMM_D1_RFU_2 
TP_CH_D_DIMM_D1_RFU_1 
M_D_ALERT_N 
M_D_ACT_N 
SMB_DDR_DEF_VPP_SCL 
M_D_PAR 
M_DEF_RST_N 
M_D_C<2> 
M_D_VREF 
M_D_DQS_DN<17:0> 
M_D_DQS_DP<17:0> 
M_D_BG<1:0> 
M_D_MA<17:0> 
M_D_BA<1:0> 
M_D_CS_N<7:0> 
M_D_CLK_DP<3:0> 
M_D_CLK_DN<3:0> 
M_D_ODT<3:0> 
M_D_CKE<3:0> 
M_D_ECC<7:0> 
M_D_DQ<63:0> 
31 
30 
34 
33 
32 
39 
37 
38 
36 
35 
15 
40 
41 
44 
43 
42 
46 
49 
48 
45 
47 
16 
4
5
6
7
8
9
10 
11 
12 
15 
13 
14 
15 
17 
16 
54 
53 
50 
51 
52 
17 
59 
57 
56 
55 
63 
61 
60 
62 
226 
145 
1
236 
233 
231 
229 
223 
220 
217 
212 
209 
204 
92 
90 
88 
85 
83 
80 
76 
73 
70 
67 
64 
61 
59 
287 
286 
288 
143 
142 
221 
77 
SCONN 
H44441-003 
J6M1 
16 
175 
18 
152 
163 
164 
174 
185 
186 
244 
245 
255 
256 
266 
267 
277 
278 
196 
197 
8
7
19 
30 
29 
41 
100 
99 
111 
110 
122 
121 
133 
132 
52 
51 
SCONN 
J6M1 
44 
184 
283 
281 
279 
276 
274 
272 
270 
268 
265 
263 
261 
259 
257 
254 
252 
250 
248 
246 
243 
241 
202 
200 
198 
195 
193 
191 
189 
187 
182 
180 
178 
176 
173 
171 
169 
167 
165 
162 
160 
158 
156 
154 
151 
149 
147 
138 
136 
134 
131 
129 
127 
125 
123 
120 
118 
116 
114 
112 
107 
103 
101 
98 
96 
94 
57 
55 
53 
50 
48 
46 
42 
39 
37 
35 
33 
31 
28 
26 
24 
22 
20 
17 
15 
13 
11 
9
6
4
2
SCONN 
H44441-003 
J6M1 
0
17 
1
2
3
4
1
0
2
3
4
5
5
7
6
8
9
6
7
8
10 
9
10 
0402V 
10% 
X7R 
A36096-045 
25V 
0.01UF 
C6M1 
SMB_DDR_DEF_VPP_SDA 
11 
12 
86 
102 
137 
79 
72 
216 
71 
214 
213 
69 
211 
68 
66 
225 
210 
65 
232 
228 
82 
234 
62 
208 
81 
224 
63 
207 
235 
49 
194 
56 
201 
47 
192 
54 
199 
75 
74 
219 
218 
60 
203 
5
150 
12 
157 
3
148 
10 
155 
16 
161 
23 
168 
14 
159 
21 
166 
34 
179 
25 
170 
32 
177 
38 
183 
45 
190 
36 
181 
43 
188 
97 
242 
104 
249 
95 
240 
247 
108 
253 
115 
260 
106 
251 
113 
258 
119 
264 
262 
269 
130 
275 
273 
135 
280 
78 
87 
91 
222 
58 
205 
227 
144 
84 
89 
93 
237 
139 
140 
238 
230 
141 
285 
284 
146 
3
1
2
0
6
8
7
4
13 
5
3
2
1
0
4
5
7
6
3
14 
3
2
2
2
3
4
5
6
7
2
11 
3
1
0
0
1
2
1
0
3
13 
12 
12 
11 
9
10 
17 
16 
15 
14 
23 
14 
22 
19 
20 
21 
28 
27 
26 
24 
25 
29 
13 
89 49 51 52 53 54 
43 44 45 46 47 48 49 51 52 53 
54 77 78 79 80 81 82 83 84 85 
86 87 88 94 
49 26 
26 49 
99 49 51 52 53 54 
26 49 
21 49 51 52 53 54 
26 49 
98 49 
26 49 
26 49 
26 49 
26 49 
26 49 
26 49 
26 49 
26 49 
26 49 
26 49 
26 49 
26 49 
49 51 52 53 54 99 
BOM NOTE: 
1
2
DO NOT SCALE DRAWING 
SCONN288_H44441003 
SCONN288_H44441003 
SCONN288_H44441003 
SCONN288_H44441003 
SHEET 
B
AA
B
B
SIZE 
SCALE: 
234
1234
DEPARTMENT CODE 
1
DOCUMENT NUMBER REV 
IN 
PVDDQ_DEF 
PVTT_DEF 
PVPP_DEF 
BI 
BI 
BI 
P12V_NVDIMM_DEF 
IN 
IN 
IN 
BI 
IN 
PVPP_DEF 
OUT 
OUT 
IN 
BI 
IN 
IN 
IN 
IN 
IN 
IN 
IN 
IN 
IN 
50 OF 270 
Wed Feb 08 16:34:41 2017 
VDD<25> 
VDD<24> 
VDD<23> 
VDD<22> 
VDD<21> 
VDD<20> 
VDD<19> 
VDD<18> 
VDD<17> 
VDD<16> 
VDD<15> 
VDD<14> 
VDD<13> 
VDD<12> 
VDD<11> 
VDD<10> 
VDD<9> 
VDD<8> 
VDD<7> 
VDD<6> 
VDD<5> 
VDD<4> 
VDD<3> 
VDD<2> 
VDD<1> 
VDD<0> 
VPP<1> 
VPP<0> 
VTT<1> 
VTT<0> 
VPP<4> 
VPP<3> 
VPP<2> 12V<0> 12V<1> 
DQS0N DQS0P 
DQS10N 
DQS10P DQS11N DQS11P DQS12N DQS12P DQS13N DQS13P DQS14N DQS14P DQS15N DQS15P DQS16N DQS16P 
DQS17N DQS17P 
DQS1N DQS1P DQS2N DQS2P DQS3N DQS3P 
DQS4N DQS4P DQS5N DQS5P DQS6N DQS6P DQS7N DQS7P DQS8N DQS8P DQS9N DQS9P 
VSS<83> 
VSS<82> 
VSS<81> 
VSS<80> 
VSS<79> 
VSS<78> 
VSS<77> 
VSS<76> 
VSS<75> 
VSS<74> 
VSS<73> 
VSS<72> 
VSS<71> 
VSS<70> 
VSS<69> 
VSS<68> 
VSS<93> 
VSS<92> 
VSS<91> 
VSS<90> 
VSS<89> 
VSS<88> 
VSS<87> 
VSS<86> 
VSS<85> 
VSS<84> 
VSS<67> 
VSS<66> 
VSS<65> 
VSS<64> 
VSS<63> 
VSS<62> 
VSS<61> 
VSS<60> 
VSS<59> 
VSS<58> 
VSS<57> 
VSS<56> 
VSS<55> 
VSS<54> 
VSS<53> 
VSS<52> 
VSS<51> 
VSS<50> 
VSS<49> 
VSS<48> 
VSS<47> 
VSS<46> 
VSS<45> 
VSS<44> 
VSS<43> 
VSS<42> 
VSS<41> 
VSS<40> 
VSS<39> 
VSS<38> 
VSS<37> 
VSS<36> 
VSS<35> 
VSS<34> 
VSS<33> 
VSS<32> 
VSS<31> 
VSS<30> 
VSS<29> 
VSS<28> 
VSS<27> 
VSS<26> 
VSS<25> 
VSS<24> 
VSS<23> 
VSS<22> 
VSS<21> 
VSS<20> 
VSS<19> 
VSS<18> 
VSS<17> 
VSS<16> 
VSS<15> 
VSS<14> 
VSS<13> 
VSS<12> 
VSS<11> 
VSS<10> VSS<9> 
VSS<8> 
VSS<7> 
VSS<6> 
VSS<5> 
VSS<4> 
VSS<3> 
VSS<2> 
VSS<1> 
VSS<0> 
DQ<12> 
DQ<11> 
DQ<10> DQ<9> 
DQ<8> 
DQ<7> 
DQ<6> 
A17 
A16_RAS_N 
A15_CAS_N DQ<60> 
DQ<58> 
DQ<50> 
S3_N_C<1> 
S2_N_C<0> 
S1_N 
S0_N 
CKE<1> 
CKE<0> 
ODT<1> 
ODT<0> 
DQ<21> 
DQ<19> 
DQ<18> 
DQ<27> DQ<28> 
CB<5> 
CB<4> 
CB<3> 
CB<2> 
A8 
A7 
A6 
DQ<45> 
DQ<44> 
DQ<41> 
DQ<51> 
A2 
ALERT_N 
ACT_N 
VREFCA 
SCL SDA SA<0> SA<1> SA<2> VDDSPD 
DQ<1> DQ<2> 
RFU<2> 
DQ<31> DQ<32> DQ<33> DQ<34> DQ<35> DQ<36> 
DQ<37> DQ<38> 
A0 A1 
A10 A11 A12 A13 A14_WE_N 
A3 
A4 A5 
A9 
BG<1> 
C<2> 
CB<7> 
CB<6> 
CB<1> 
CB<0> 
DQ<63> 
DQ<62> 
DQ<61> 
DQ<59> 
DQ<57> 
DQ<56> 
DQ<55> 
DQ<54> 
DQ<53> 
DQ<52> 
DQ<49> 
DQ<48> 
DQ<47> 
DQ<46> 
DQ<43> 
DQ<40> 
DQ<39> 
DQ<30> 
DQ<26> 
DQ<25> 
DQ<24> 
DQ<23> 
DQ<22> 
DQ<20> 
DQ<17> 
DQ<16> 
DQ<15> 
DQ<14> 
DQ<13> 
DQ<5> 
DQ<4> 
DQ<3> 
DQ<0> 
EVENT_N 
PAR 
RESET_N 
RFU<1> 
RFU<0> 
SAVE_N_NC 
BG<0> 
CK1P 
CK1N 
CK0P 
CK0N 
DQ<29> 
DQ<42> BA<0> BA<1> 
PVDDQ (SINGLE SIDE) CAP: 10UF X1, 22UF X50 
PVTT CAP: 100UF X2, 47UF X1 PVPP CAP: 10UF X12 
PVDDQ (DOUBLE SIDE) CAP: 100UF X8, 47UF X41 
BOM_SS=NOPOP 
BOM_SS=NOPOP 
BOM_SS=NOPOP BOM_SS=NOPOP 
UNSTUFF FOR SKU B 
CPU0 DDR4 CH D DIMM1 
CAP BETWEEN DIMM PLACE CAP NEAR DIMM CONNECTOR 
WIWYNN CORPORATION 
SMBUS ADDR: 0XA2 
4/4 
2/4 
3/4 
1/4 



131 
52 
M_E_MA<17:0> 
112 
218 
H44441-004 
FM_ADR_COMPLETE_DEF_N 
TP_CH_E_DIMM_E0_RFU_0 
TP_CH_E_DIMM_E0_RFU_2 
M_E_C<2> 
M_E_ALERT_N 
M_E_ACT_N 
M_E_PAR 
M_DEF_RST_N 
FM_DIMM_EVENT_COD_N 
SMB_DDR_DEF_VPP_SCL 
M_E_VREF 
TP_CH_E_DIMM_E0_RFU_1 
M_E_CKE<3:0> 
M_E_CLK_DP<3:0> 
M_E_CLK_DN<3:0> 
M_E_ODT<3:0> 
M_E_ECC<7:0> 
M_E_CS_N<7:0> 
M_E_BG<1:0> 
M_E_BA<1:0> 
M_E_DQ<63:0> 
M_E_DQS_DN<17:0> 
M_E_DQS_DP<17:0> 
10 
12 
13 
15 
14 
16 
17 
19 
18 
21 
12 
20 
22 
23 
24 
25 
27 
29 
26 
31 
30 
14 
28 
33 
32 
34 
35 
37 
36 
39 
40 
38 
13 
41 
43 
42 
152 
153 
163 
164 
174 
175 
185 
186 
244 
245 
255 
256 
266 
267 
277 
278 
196 
197 
8
7
19 
18 
30 
29 
41 
40 
100 
99 
111 
110 
122 
121 
133 
132 
52 
51 
SCONN 
H44441-004 
J4A2 
45 
44 
47 
49 
46 
48 
15 
51 
50 
53 
55 
54 
57 
59 
56 
58 
16 
60 
61 
63 
62 
J4A2 
283 
281 
279 
276 
274 
272 
270 
268 
265 
263 
261 
259 
257 
254 
252 
250 
248 
246 
243 
241 
239 
202 
200 
198 
195 
193 
191 
189 
187 
184 
182 
180 
178 
176 
173 
171 
169 
167 
165 
162 
160 
158 
156 
154 
151 
149 
147 
138 
136 
134 
129 
127 
125 
123 
120 
118 
116 
114 
109 
107 
105 
103 
101 
98 
96 
94 
57 
55 
53 
50 
48 
46 
44 
42 
39 
37 
35 
33 
31 
28 
26 
24 
22 
20 
17 
15 
13 
11 
9
6
4
2
SCONN 
H44441-004 
0
1
17 
0
1
2
3
5
4
2
3
4
5
17 
6
7
6
8
10 
9
7
8
9
10 
11 
1
1
0402V 
X7R 
25V 
10% 
0.01UF 
A36096-045 
C6L6 
SMB_DDR_DEF_VPP_SDA 
145 
1
236 
233 
231 
229 
226 
223 
220 
217 
215 
212 
209 
206 
204 
92 
90 
88 
85 
83 
80 
76 
73 
70 
67 
64 
61 
59 
287 
286 
288 
143 
142 
221 
77 
SCONN 
H44441-004 
J4A2 
0
1
0
1
0
1
2
3
0
0
12 
1
0
3
2
5
4
11 
6
7
0
1
0
1
13 
0
1
2
3
4
5
6
7
8
9
14 
10 
11 
12 
13 
14 
15 
16 
17 
82 
161 
16 
155 
10 
146 
144 
79 
72 
216 
71 
214 
213 
69 
211 
68 
66 
225 
210 
65 
232 
228 
86 
234 
62 
208 
81 
224 
63 
207 
235 
49 
194 
56 
201 
47 
192 
54 
199 
75 
74 
219 
60 
203 
5
150 
12 
157 
3
148 
23 
168 
14 
159 
21 
166 
27 
172 
34 
179 
25 
170 
32 
177 
38 
183 
45 
190 
36 
181 
43 
188 
97 
242 
104 
249 
95 
240 
102 
247 
108 
253 
115 
260 
106 
251 
113 
258 
119 
264 
126 
271 
117 
262 
124 
269 
130 
275 
137 
282 
128 
273 
135 
280 
78 
87 
91 
222 
58 
205 
227 
84 
89 
93 
237 
139 
140 
238 
230 
141 
285 
284 
SCONN 
J4A2 
1
15 
3
0
5
2
4
7
9
6
8
11 
16 
27 52 
89 49 50 52 53 54 
27 52 
52 27 
27 52 
27 52 
21 49 50 52 53 54 
43 44 45 46 47 48 49 50 52 53 
54 77 78 79 80 81 82 83 84 85 
86 87 88 94 
99 49 50 52 53 54 
98 52 
27 52 
27 52 
27 52 
27 52 
27 52 
27 52 
27 52 
27 52 
27 52 
27 52 
27 52 
49 50 52 53 54 99 
BOM NOTE: 
1
2
DO NOT SCALE DRAWING 
SCONN288_H44441004 
SCONN288_H44441004 
SCONN288_H44441004 
SCONN288_H44441004 
SHEET 
B
AA
B
B
SIZE 
SCALE: 
234
1234
DEPARTMENT CODE 
1
DOCUMENT NUMBER REV 
BI 
BI 
P12V_NVDIMM_DEF 
IN 
PVPP_DEF 
PVPP_DEF 
BI 
OUT 
PVTT_DEF 
IN 
IN 
IN 
IN 
PVDDQ_DEF 
IN 
IN 
IN 
BI 
IN 
OUT 
IN 
IN 
IN 
IN 
IN 
IN 
BI 
51 OF 270 
Wed Feb 08 16:34:42 2017 
DQS9P DQS9N DQS8P DQS8N DQS7P DQS7N DQS6P DQS6N DQS5P DQS5N DQS4P DQS4N 
DQS3P DQS3N DQS2P DQS2N DQS1P DQS1N 
DQS17P DQS17N DQS16P 
DQS16N DQS15P DQS15N DQS14P DQS14N DQS13P DQS13N DQS12P DQS12N DQS11P DQS11N DQS10P DQS10N 
DQS0P DQS0N 
VSS<0> VSS<1> VSS<2> VSS<3> VSS<4> VSS<5> VSS<6> VSS<7> VSS<8> VSS<9> 
VSS<10> VSS<11> VSS<12> VSS<13> VSS<14> VSS<15> VSS<16> VSS<17> VSS<18> VSS<19> VSS<20> VSS<21> VSS<22> 
VSS<23> VSS<24> VSS<25> VSS<26> VSS<27> VSS<28> VSS<29> VSS<30> VSS<31> VSS<32> VSS<33> VSS<34> VSS<35> 
VSS<36> VSS<37> VSS<38> VSS<39> VSS<40> VSS<41> VSS<42> VSS<43> VSS<44> 
VSS<47> VSS<48> VSS<49> VSS<50> VSS<51> VSS<52> VSS<53> VSS<54> VSS<55> VSS<56> 
VSS<57> VSS<58> VSS<59> VSS<60> VSS<61> VSS<62> VSS<63> VSS<64> VSS<65> VSS<66> VSS<67> 
VSS<84> VSS<85> VSS<86> VSS<87> VSS<88> VSS<89> VSS<90> VSS<91> VSS<92> VSS<93> 
VSS<68> VSS<69> 
VSS<70> VSS<71> VSS<72> VSS<73> VSS<74> VSS<75> VSS<76> VSS<77> VSS<78> VSS<79> VSS<80> VSS<81> VSS<82> 
VSS<83> 
VSS<45> VSS<46> 
12V<0> VPP<2> 
VPP<4> 
VTT<0> VTT<1> 
VPP<0> VPP<1> 
VDD<0> VDD<1> VDD<2> VDD<3> VDD<4> VDD<5> VDD<6> VDD<7> VDD<8> VDD<9> VDD<10> VDD<11> VDD<12> 
VDD<13> VDD<14> VDD<15> VDD<16> VDD<17> VDD<18> VDD<19> VDD<20> VDD<21> VDD<22> VDD<23> VDD<24> VDD<25> 
12V<1> VPP<3> 
BA<1> 
BA<0> DQ<42> 
DQ<29> 
CK0N CK0P CK1N CK1P 
BG<0> 
SAVE_N_NC 
RFU<0> RFU<1> 
RESET_N PAR 
EVENT_N 
DQ<0> 
DQ<3> DQ<4> DQ<5> 
DQ<13> DQ<14> 
DQ<15> DQ<16> DQ<17> 
DQ<20> 
DQ<22> DQ<23> DQ<24> DQ<25> DQ<26> 
DQ<30> 
DQ<39> DQ<40> 
DQ<43> 
DQ<46> DQ<47> DQ<48> DQ<49> 
DQ<52> 
DQ<53> DQ<54> DQ<55> DQ<56> DQ<57> 
DQ<59> 
DQ<61> DQ<62> DQ<63> 
CB<0> CB<1> 
CB<6> CB<7> 
C<2> 
BG<1> 
A9 
A5 
A4 
A3 
A14_WE_N 
A13 
A12 
A11 
A10 
A1 
A0 
DQ<38> 
DQ<37> 
DQ<36> 
DQ<35> 
DQ<34> 
DQ<33> 
DQ<32> 
DQ<31> 
RFU<2> 
DQ<2> 
DQ<1> 
VDDSPD 
SA<2> 
SA<1> 
SA<0> 
SDA 
SCL 
VREFCA 
ACT_N ALERT_N 
A2 
DQ<51> 
DQ<41> 
DQ<44> DQ<45> 
A6 
A7 A8 
CB<2> CB<3> CB<4> CB<5> 
DQ<28> 
DQ<27> 
DQ<18> DQ<19> 
DQ<21> 
ODT<0> ODT<1> 
CKE<0> 
CKE<1> 
S0_N S1_N S2_N_C<0> S3_N_C<1> 
DQ<50> 
DQ<58> 
DQ<60> A15_CAS_N A16_RAS_N A17 
DQ<6> DQ<7> DQ<8> DQ<9> DQ<10> DQ<11> DQ<12> 
PVDDQ (SINGLE SIDE) CAP: 10UF X1, 22UF X50 PVTT CAP: 100UF X2, 47UF X1 PVPP CAP: 10UF X12 
PVDDQ (DOUBLE SIDE) CAP: 100UF X8, 47UF X41 
STUFF FOR SKU A & B 
CPU0 DDR4 CH E DIMM0 
CAP BETWEEN DIMM PLACE CAP NEAR DIMM CONNECTOR 
WIWYNN CORPORATION SMBUS ADDR: 0XA4 
2/4 
3/4 
4/4 
1/4 



127 
55 
80 
94 
254 
SCONN 
282 
M_E_MA<17:0> 
11 
159 
9
107 
207 
H44441-003 
224 
M_E_VREF 
TP_CH_E_DIMM_E1_RFU_2 
TP_CH_E_DIMM_E1_RFU_0 
TP_CH_E_DIMM_E1_RFU_1 
M_E_ALERT_N 
M_E_ACT_N 
FM_ADR_COMPLETE_DEF_N 
SMB_DDR_DEF_VPP_SCL 
M_DEF_RST_N 
FM_DIMM_EVENT_COD_N 
M_E_PAR 
M_E_C<2> 
M_E_BG<1:0> 
M_E_BA<1:0> 
M_E_CLK_DN<3:0> 
M_E_CLK_DP<3:0> 
M_E_CKE<3:0> 
M_E_CS_N<7:0> 
M_E_ODT<3:0> 
M_E_ECC<7:0> 
M_E_DQ<63:0> 
M_E_DQS_DN<17:0> 
M_E_DQS_DP<17:0> 
45 
46 
42 
43 
44 
41 
40 
37 
38 
39 
35 
36 
32 
33 
34 
30 
31 
29 
28 
27 
25 
24 
26 
23 
22 
19 
20 
21 
17 
18 
14 
15 
16 
13 
12 
11 
10 
6
8
7
145 
1
236 
233 
231 
229 
226 
223 
220 
217 
215 
212 
209 
206 
204 
92 
90 
88 
85 
83 
76 
73 
70 
67 
64 
61 
59 
287 
286 
288 
143 
142 
221 
77 
SCONN 
H44441-003 
J6L2 
4
5
2
1
3
0
0
1
0
1
0
2
3
6
7
4
5
2
3
3
2
0402V 
25V 
0.01UF 
X7R 
10% 
A36096-045 
C4A18 
2
3
7
6
4
5
2
3
1
0
17 
15 
16 
17 
13 
14 
16 
15 
13 
14 
12 
12 
10 
11 
8
7
9
11 
10 
8
9
7
5
6
3
2
4
6
5
4
3
2
1
0
1
0
SCONN 
283 
281 
279 
276 
274 
272 
270 
268 
265 
263 
261 
259 
257 
252 
250 
248 
246 
243 
241 
239 
202 
200 
198 
195 
193 
191 
189 
187 
184 
182 
180 
178 
176 
173 
171 
169 
167 
165 
162 
160 
158 
156 
154 
151 
149 
147 
138 
136 
134 
131 
129 
125 
123 
120 
118 
116 
114 
112 
109 
105 
103 
101 
98 
96 
57 
55 
53 
50 
48 
46 
44 
42 
39 
37 
35 
33 
31 
28 
26 
24 
22 
20 
17 
15 
13 
11 
9
6
4
2
H44441-003 
J6L2 
63 
61 
60 
62 
58 
59 
56 
57 
54 
53 
50 
51 
52 
48 
47 
148 
10 
155 
79 
72 
216 
71 
214 
213 
69 
211 
68 
66 
225 
210 
65 
232 
228 
86 
82 
234 
62 
208 
81 
63 
235 
49 
194 
56 
201 
47 
192 
54 
199 
75 
74 
219 
218 
60 
203 
5
150 
12 
157 
3
16 
161 
23 
168 
14 
21 
166 
27 
172 
34 
179 
25 
170 
32 
177 
38 
183 
45 
190 
36 
181 
43 
188 
97 
242 
104 
249 
95 
240 
102 
247 
108 
253 
115 
260 
106 
251 
113 
258 
119 
264 
126 
271 
117 
262 
124 
269 
130 
275 
137 
128 
273 
135 
280 
78 
87 
91 
222 
58 
205 
227 
144 
84 
89 
93 
237 
139 
140 
238 
230 
141 
285 
284 
146 
SCONN 
J6L2 
49 
17 
16 
14 
15 
12 
13 
9
10 
7
8
6
4
5
3
1
2
164 
152 
153 
163 
174 
175 
185 
186 
244 
245 
255 
256 
266 
267 
277 
278 
196 
197 
8
7
19 
18 
30 
29 
41 
40 
100 
99 
111 
110 
122 
121 
133 
132 
52 
51 
H44441-003 
J6L2 
SMB_DDR_DEF_VPP_SDA 
27 51 
98 51 
51 27 
27 51 
89 49 50 51 53 54 
99 49 50 51 53 54 
21 49 50 51 53 54 
43 44 45 46 47 48 49 50 51 53 
54 77 78 79 80 81 82 83 84 85 
86 87 88 94 
27 51 
27 51 
27 51 
27 51 
27 51 
27 51 
27 51 
27 51 
27 51 
27 51 
27 51 
27 51 
27 51 
49 50 51 53 54 99 
BOM NOTE: 
1
2
DO NOT SCALE DRAWING 
SCONN288_H44441003 
SCONN288_H44441003 
SCONN288_H44441003 
SCONN288_H44441003 
SHEET 
B
AA
B
B
SIZE 
SCALE: 
234
1234
DEPARTMENT CODE 
1
DOCUMENT NUMBER REV 
PVPP_DEF 
PVTT_DEF 
IN 
IN 
PVDDQ_DEF 
IN 
OUT 
PVPP_DEF 
IN 
IN 
IN 
IN 
IN 
IN P12V_NVDIMM_DEF 
BI 
IN 
BI 
IN 
BI 
IN 
IN 
BI 
OUT 
IN 
IN 
BI 
52 OF 270 
Wed Feb 08 16:34:42 2017 
VDD<25> 
VDD<24> 
VDD<23> 
VDD<22> 
VDD<21> 
VDD<20> 
VDD<19> 
VDD<18> 
VDD<17> 
VDD<16> 
VDD<15> 
VDD<14> 
VDD<13> 
VDD<12> 
VDD<11> 
VDD<10> 
VDD<9> 
VDD<8> 
VDD<7> 
VDD<6> 
VDD<5> 
VDD<4> 
VDD<3> 
VDD<2> 
VDD<1> 
VDD<0> 
VPP<1> 
VPP<0> 
VTT<1> 
VTT<0> 
VPP<4> 
VPP<3> 
VPP<2> 12V<0> 12V<1> 
VSS<83> 
VSS<82> 
VSS<81> 
VSS<80> 
VSS<79> 
VSS<78> 
VSS<77> 
VSS<76> 
VSS<75> 
VSS<74> 
VSS<73> 
VSS<72> 
VSS<71> 
VSS<70> 
VSS<69> 
VSS<68> 
VSS<93> 
VSS<92> 
VSS<91> 
VSS<90> 
VSS<89> 
VSS<88> 
VSS<87> 
VSS<86> 
VSS<85> 
VSS<84> 
VSS<67> 
VSS<66> 
VSS<65> 
VSS<64> 
VSS<63> 
VSS<62> 
VSS<61> 
VSS<60> 
VSS<59> 
VSS<58> 
VSS<57> 
VSS<56> 
VSS<55> 
VSS<54> 
VSS<53> 
VSS<52> 
VSS<51> 
VSS<50> 
VSS<49> 
VSS<48> 
VSS<47> 
VSS<46> 
VSS<45> 
VSS<44> 
VSS<43> 
VSS<42> 
VSS<41> 
VSS<40> 
VSS<39> 
VSS<38> 
VSS<37> 
VSS<36> 
VSS<35> 
VSS<34> 
VSS<33> 
VSS<32> 
VSS<31> 
VSS<30> 
VSS<29> 
VSS<28> 
VSS<27> 
VSS<26> 
VSS<25> 
VSS<24> 
VSS<23> 
VSS<22> 
VSS<21> 
VSS<20> 
VSS<19> 
VSS<18> 
VSS<17> 
VSS<16> 
VSS<15> 
VSS<14> 
VSS<13> 
VSS<12> 
VSS<11> 
VSS<10> VSS<9> 
VSS<8> 
VSS<7> 
VSS<6> 
VSS<5> 
VSS<4> 
VSS<3> 
VSS<2> 
VSS<1> 
VSS<0> 
DQ<12> 
DQ<11> 
DQ<10> DQ<9> 
DQ<8> 
DQ<7> 
DQ<6> 
A17 
A16_RAS_N 
A15_CAS_N DQ<60> 
DQ<58> 
DQ<50> 
S3_N_C<1> 
S2_N_C<0> 
S1_N 
S0_N 
CKE<1> 
CKE<0> 
ODT<1> 
ODT<0> 
DQ<21> 
DQ<19> 
DQ<18> 
DQ<27> DQ<28> 
CB<5> 
CB<4> 
CB<3> 
CB<2> 
A8 
A7 
A6 
DQ<45> 
DQ<44> 
DQ<41> 
DQ<51> 
A2 
ALERT_N 
ACT_N 
VREFCA 
SCL SDA 
SA<0> SA<1> SA<2> VDDSPD 
DQ<1> DQ<2> 
RFU<2> 
DQ<31> DQ<32> DQ<33> DQ<34> DQ<35> DQ<36> DQ<37> DQ<38> 
A0 A1 
A10 A11 A12 A13 A14_WE_N 
A3 A4 A5 
A9 
BG<1> 
C<2> 
CB<7> 
CB<6> 
CB<1> 
CB<0> 
DQ<63> 
DQ<62> 
DQ<61> 
DQ<59> 
DQ<57> 
DQ<56> 
DQ<55> 
DQ<54> 
DQ<53> 
DQ<52> 
DQ<49> 
DQ<48> 
DQ<47> 
DQ<46> 
DQ<43> 
DQ<40> 
DQ<39> 
DQ<30> 
DQ<26> 
DQ<25> 
DQ<24> 
DQ<23> 
DQ<22> 
DQ<20> 
DQ<17> 
DQ<16> 
DQ<15> 
DQ<14> 
DQ<13> 
DQ<5> 
DQ<4> 
DQ<3> 
DQ<0> 
EVENT_N 
PAR 
RESET_N 
RFU<1> 
RFU<0> 
SAVE_N_NC 
BG<0> 
CK1P 
CK1N 
CK0P 
CK0N 
DQ<29> 
DQ<42> 
BA<0> BA<1> 
DQS0N DQS0P 
DQS10N DQS10P 
DQS11N DQS11P DQS12N DQS12P DQS13N DQS13P DQS14N DQS14P DQS15N DQS15P DQS16N DQS16P DQS17N 
DQS17P 
DQS1N DQS1P DQS2N DQS2P DQS3N DQS3P DQS4N DQS4P 
DQS5N DQS5P DQS6N DQS6P DQS7N DQS7P DQS8N DQS8P DQS9N DQS9P 
PVDDQ (SINGLE SIDE) CAP: 10UF X1, 22UF X50 
PVPP CAP: 10UF X12 
PVTT CAP: 100UF X2, 47UF X1 
PVDDQ (DOUBLE SIDE) CAP: 100UF X8, 47UF X41 
BOM_SS=NOPOP 
BOM_SS=NOPOP 
BOM_SS=NOPOP 
BOM_SS=NOPOP 
UNSTUFF FOR SKU B 
CPU0 DDR4 CH E DIMM1 
CAP BETWEEN DIMM PLACE CAP NEAR DIMM CONNECTOR 
WIWYNN CORPORATION 
SMBUS ADDR: 0XA6 4/4 
3/4 
1/4 
2/4 



43 
188 
242 
104 
37 
36 
H44441-004 
J4A1 
M_F_MA<17:0> 
130 
216 
128 
213 
M_F_C<2> 
M_F_PAR 
FM_DIMM_EVENT_COD_N 
M_DEF_RST_N 
FM_ADR_COMPLETE_DEF_N 
SMB_DDR_DEF_VPP_SDA 
SMB_DDR_DEF_VPP_SCL 
M_F_ALERT_N 
M_F_ACT_N 
TP_CH_F_DIMM_F0_RFU_2 
TP_CH_F_DIMM_F0_RFU_0 
TP_CH_F_DIMM_F0_RFU_1 
M_F_VREF 
M_F_CLK_DN<3:0> 
M_F_ECC<7:0> 
M_F_ODT<3:0> 
M_F_CKE<3:0> 
M_F_CS_N<7:0> 
M_F_BG<1:0> 
M_F_CLK_DP<3:0> 
M_F_BA<1:0> 
M_F_DQ<63:0> 
M_F_DQS_DP<17:0> 
M_F_DQS_DN<17:0> 
10 
12 
13 
15 
14 
16 
17 
19 
18 
21 
12 
20 
22 
23 
24 
25 
27 
29 
26 
31 
30 
14 
28 
33 
32 
34 
35 
39 
40 
38 
13 
41 
43 
42 
152 
153 
163 
164 
174 
175 
185 
186 
244 
245 
255 
256 
266 
267 
277 
278 
196 
197 
8
7
19 
18 
30 
29 
41 
40 
100 
99 
111 
110 
122 
121 
133 
132 
52 
51 
SCONN 
J4A1 
45 
44 
47 
49 
46 
48 
15 
51 
50 
53 
55 
52 
54 
57 
59 
56 
58 
16 
60 
61 
63 
62 
283 
281 
279 
276 
274 
272 
270 
268 
265 
263 
261 
259 
257 
254 
252 
250 
248 
246 
243 
241 
239 
202 
200 
198 
195 
193 
191 
189 
187 
184 
182 
180 
178 
176 
173 
171 
169 
167 
165 
162 
160 
158 
156 
154 
151 
149 
147 
138 
136 
134 
131 
129 
127 
125 
123 
120 
118 
116 
114 
112 
109 
107 
105 
103 
101 
98 
96 
94 
57 
55 
53 
50 
48 
46 
44 
42 
39 
37 
35 
33 
31 
28 
26 
24 
22 
20 
17 
15 
13 
11 
9
6
4
2
SCONN 
H44441-004 
J4A1 
0
1
17 
0
1
2
3
5
4
2
3
4
5
17 
6
7
6
8
10 
9
7
8
9
10 
11 
0402V 
25V 
X7R 
10% 
0.01UF 
A36096-045 
C6L1 
SCONN 
145 
1
236 
233 
231 
229 
226 
223 
220 
217 
215 
212 
209 
206 
204 
92 
90 
88 
85 
83 
80 
76 
73 
70 
67 
64 
61 
59 
287 
286 
288 
143 
142 
221 
77 
H44441-004 
J4A1 
0
1
0
1
0
1
2
3
0
1
0
1
12 
1
0
3
2
5
4
11 
6
7
0
1
0
1
13 
0
1
2
3
4
5
6
7
8
9
14 
10 
11 
12 
13 
14 
15 
16 
17 
SCONN 
68 
115 
79 
72 
71 
214 
69 
211 
66 
225 
210 
65 
232 
228 
86 
82 
234 
62 
208 
81 
224 
63 
207 
235 
49 
194 
56 
201 
47 
192 
54 
199 
75 
74 
219 
218 
60 
203 
5
150 
12 
157 
3
148 
10 
155 
16 
161 
23 
168 
14 
159 
21 
166 
27 
172 
34 
179 
25 
170 
32 
177 
38 
183 
45 
190 
36 
181 
97 
249 
95 
240 
102 
247 
108 
253 
260 
106 
251 
113 
258 
119 
264 
126 
271 
117 
262 
124 
269 
275 
137 
282 
273 
135 
280 
78 
87 
91 
222 
58 
205 
227 
144 
84 
89 
93 
237 
139 
140 
238 
230 
141 
285 
284 
146 
H44441-004 
1
15 
3
0
5
2
4
7
9
6
8
11 
16 
28 54 
28 54 
28 54 
43 44 45 46 47 48 49 50 51 52 
54 77 78 79 80 81 82 83 84 85 
86 87 88 94 
21 49 50 51 52 54 
89 49 50 51 52 54 
49 50 51 52 54 99 
99 49 50 51 52 54 
54 28 
28 54 
98 54 
28 54 
28 54 
28 54 
28 54 
28 54 
28 54 
28 54 
28 54 
28 54 
28 54 
28 54 
BOM NOTE: 
1
2
DO NOT SCALE DRAWING 
SCONN288_H44441004 
SCONN288_H44441004 
SCONN288_H44441004 
SCONN288_H44441004 
SHEET 
B
AA
B
B
SIZE 
SCALE: 
234
1234
DEPARTMENT CODE 
1
DOCUMENT NUMBER REV 
BI 
BI 
P12V_NVDIMM_DEF 
IN 
PVPP_DEF 
PVPP_DEF 
IN 
OUT 
PVDDQ_DEF 
BI 
PVTT_DEF 
IN 
IN 
IN 
IN 
IN 
IN 
BI 
IN 
OUT 
IN 
IN 
IN 
IN 
IN 
IN 
BI 
53 OF 270 
DQS9P 
DQS9N DQS8P DQS8N DQS7P DQS7N DQS6P DQS6N DQS5P DQS5N DQS4P DQS4N DQS3P 
DQS3N DQS2P DQS2N DQS1P DQS1N 
DQS17P DQS17N DQS16P DQS16N 
DQS15P DQS15N DQS14P DQS14N DQS13P DQS13N DQS12P DQS12N DQS11P DQS11N DQS10P DQS10N 
DQS0P DQS0N 
VSS<0> VSS<1> VSS<2> VSS<3> VSS<4> VSS<5> VSS<6> VSS<7> VSS<8> VSS<9> VSS<10> VSS<11> 
VSS<12> VSS<13> VSS<14> VSS<15> VSS<16> VSS<17> VSS<18> VSS<19> VSS<20> VSS<21> VSS<22> VSS<23> VSS<24> 
VSS<25> VSS<26> VSS<27> VSS<28> VSS<29> VSS<30> VSS<31> VSS<32> VSS<33> VSS<34> VSS<35> VSS<36> VSS<37> 
VSS<38> VSS<39> VSS<40> VSS<41> VSS<42> VSS<43> VSS<44> 
VSS<47> VSS<48> VSS<49> VSS<50> VSS<51> VSS<52> VSS<53> VSS<54> VSS<55> VSS<56> VSS<57> VSS<58> 
VSS<59> VSS<60> VSS<61> VSS<62> VSS<63> VSS<64> VSS<65> VSS<66> VSS<67> 
VSS<84> 
VSS<85> VSS<86> VSS<87> VSS<88> VSS<89> VSS<90> VSS<91> VSS<92> VSS<93> 
VSS<68> VSS<69> VSS<70> VSS<71> 
VSS<72> VSS<73> VSS<74> VSS<75> VSS<76> VSS<77> VSS<78> VSS<79> VSS<80> VSS<81> VSS<82> VSS<83> 
VSS<45> VSS<46> 
12V<0> VPP<2> 
VPP<4> 
VTT<0> VTT<1> 
VPP<0> VPP<1> 
VDD<0> VDD<1> VDD<2> VDD<3> VDD<4> VDD<5> VDD<6> VDD<7> VDD<8> VDD<9> VDD<10> VDD<11> VDD<12> 
VDD<13> VDD<14> VDD<15> VDD<16> VDD<17> VDD<18> VDD<19> VDD<20> VDD<21> VDD<22> VDD<23> VDD<24> VDD<25> 
12V<1> VPP<3> 
BA<1> 
BA<0> DQ<42> 
DQ<29> 
CK0N CK0P CK1N CK1P 
BG<0> 
SAVE_N_NC 
RFU<0> RFU<1> 
RESET_N PAR 
EVENT_N 
DQ<0> 
DQ<3> DQ<4> DQ<5> 
DQ<13> DQ<14> DQ<15> DQ<16> DQ<17> 
DQ<20> 
DQ<22> 
DQ<23> DQ<24> DQ<25> DQ<26> 
DQ<30> 
DQ<39> DQ<40> 
DQ<43> 
DQ<46> DQ<47> DQ<48> 
DQ<49> 
DQ<52> DQ<53> DQ<54> DQ<55> DQ<56> DQ<57> 
DQ<59> 
DQ<61> 
DQ<62> DQ<63> 
CB<0> CB<1> 
CB<6> CB<7> 
C<2> 
BG<1> 
A9 
A5 
A4 
A3 
A14_WE_N 
A13 
A12 
A11 
A10 
A1 
A0 
DQ<38> 
DQ<37> 
DQ<36> 
DQ<35> 
DQ<34> 
DQ<33> 
DQ<32> 
DQ<31> 
RFU<2> 
DQ<2> 
DQ<1> 
VDDSPD 
SA<2> 
SA<1> 
SA<0> 
SDA 
SCL 
VREFCA 
ACT_N 
ALERT_N 
A2 
DQ<51> 
DQ<41> 
DQ<44> DQ<45> 
A6 A7 A8 
CB<2> CB<3> CB<4> CB<5> 
DQ<28> 
DQ<27> 
DQ<18> DQ<19> 
DQ<21> 
ODT<0> ODT<1> 
CKE<0> CKE<1> 
S0_N S1_N S2_N_C<0> S3_N_C<1> 
DQ<50> 
DQ<58> 
DQ<60> A15_CAS_N 
A16_RAS_N A17 
DQ<6> DQ<7> DQ<8> DQ<9> 
DQ<10> DQ<11> DQ<12> 
PVDDQ (SINGLE SIDE) CAP: 10UF X1, 22UF X50 PVTT CAP: 100UF X2, 47UF X1 
PVDDQ (DOUBLE SIDE) CAP: 100UF X8, 47UF X41 
PLACE CAP NEAR DIMM CONNECTOR 
PVPP CAP: 10UF X12 
Wed Feb 08 16:34:43 2017 
STUFF FOR SKU A & B 
CPU0 DDR4 CH F DIMM0 
CAP BETWEEN DIMM 
SMBUS ADDR: 0XA8 WIWYNN CORPORATION 
2/4 
3/4 4/4 
1/4 



134 
M_F_DQ<63:0> 
31 
SCONN 
14 
9
10 
4
3
5
6
8
7
0
2
15 
1
H44441-003 
146 
284 
285 
141 
230 
238 
140 
139 
237 
93 
89 
84 
144 
227 
205 
58 
222 
91 
87 
78 
280 
135 
273 
282 
137 
275 
130 
269 
124 
262 
117 
271 
126 
264 
119 
258 
260 
247 
102 
240 
95 
249 
104 
97 
188 
45 
183 
38 
177 
32 
170 
25 
179 
34 
172 
27 
166 
21 
159 
14 
168 
23 
161 
16 
155 
10 
148 
3
157 
12 
5
203 
60 
218 
219 
74 
75 
199 
54 
192 
47 
201 
56 
194 
49 
235 
207 
63 
224 
81 
208 
62 
82 
86 
228 
232 
65 
210 
66 
68 
211 
69 
213 
214 
71 
216 
72 
79 
150 
251 
106 
115 
253 
108 
234 
128 
J6L1 
SCONN 
16 
17 
15 
14 
13 
12 
11 
10 
16 
9
8
7
6
5
4
2
3
1
0
11 
1
0
1
0
7
6
12 
5
4
3
2
1
0
13 
3
2
3
2
7
6
5
4
3
2
3
2
J6L1 
H44441-003 
SCONN 
77 
221 
142 
143 
288 
286 
287 
59 
61 
64 
67 
70 
73 
76 
80 
83 
85 
88 
90 
92 
204 
206 
209 
212 
215 
217 
220 
223 
226 
229 
231 
233 
236 
1
145 
A36096-045 
10% 
X7R 
0402V 
25V 
0.01UF 
C4A5 
11 
10 
9
8
7
10 
9
6
7
8
6
17 
5
4
3
2
5
4
3
0
17 
1
0
J6L1 
H44441-003 
2
4
6
9
11 
13 
17 
20 
26 
28 
33 
35 
46 
48 
50 
55 
57 
94 
96 
98 
101 
103 
105 
107 
109 
112 
116 
118 
120 
123 
125 
127 
129 
131 
136 
138 
149 
154 
156 
160 
162 
165 
167 
169 
171 
173 
176 
178 
180 
182 
184 
187 
189 
191 
193 
198 
200 
202 
239 
241 
243 
246 
248 
250 
252 
254 
257 
259 
261 
263 
265 
268 
270 
272 
274 
276 
279 
281 
283 
53 
151 
158 
44 
42 
39 
37 
24 
22 
147 
SCONN 
61 
60 
62 
63 
16 
55 
56 
58 
57 
59 
50 
51 
52 
54 
53 
15 
44 
45 
46 
48 
47 
49 
H44441-003 
52 
132 
133 
121 
122 
110 
111 
99 
100 
40 
41 
29 
30 
18 
19 
7
8
197 
196 
278 
277 
267 
266 
256 
255 
175 
174 
164 
153 
152 
51 
J6L1 
163 
41 
39 
40 
14 
42 
43 
35 
34 
36 
37 
38 
30 
31 
29 
13 
32 
25 
24 
26 
28 
27 
21 
12 
23 
22 
14 
15 
17 
16 
18 
13 
11 
12 
M_F_DQS_DP<17:0> 
M_F_DQS_DN<17:0> 
M_F_CLK_DN<3:0> 
M_F_CLK_DP<3:0> 
M_F_CKE<3:0> 
M_F_CS_N<7:0> 
M_F_ODT<3:0> 
M_F_ECC<7:0> 
M_F_BG<1:0> 
M_F_VREF 
TP_CH_F_DIMM_F1_RFU_2 
TP_CH_F_DIMM_F1_RFU_0 
TP_CH_F_DIMM_F1_RFU_1 
SMB_DDR_DEF_VPP_SCL 
SMB_DDR_DEF_VPP_SDA 
FM_ADR_COMPLETE_DEF_N 
FM_DIMM_EVENT_COD_N 
M_F_PAR 
M_DEF_RST_N 
M_F_ACT_N 
M_F_ALERT_N 
M_F_C<2> 
225 
M_F_MA<17:0> 
33 
114 
195 
1
2
245 
15 
185 
186 
244 
113 M_F_BA<1:0> 
19 
20 
190 
36 
181 
43 
242 
28 53 
28 53 
28 53 
28 53 
28 53 
28 53 
28 53 
28 53 
28 53 
28 53 
98 53 
99 49 50 51 52 53 
49 50 51 52 53 99 
89 49 50 51 52 53 
43 44 45 46 47 48 49 50 51 52 
53 77 78 79 80 81 82 83 84 
85 86 87 88 94 
28 53 
21 49 50 51 52 53 
28 53 
53 28 
28 53 
28 53 
28 53 
BOM NOTE: 
2
1
DO NOT SCALE DRAWING 
SCONN288_H44441003 
SCONN288_H44441003 
SCONN288_H44441003 
SCONN288_H44441003 
SHEET 
B
AA
B
B
SIZE 
SCALE: 
234
1234
DEPARTMENT CODE 
1
DOCUMENT NUMBER REV 
BI 
BI 
P12V_NVDIMM_DEF 
IN 
PVPP_DEF 
PVPP_DEF 
OUT 
IN 
BI 
IN 
PVTT_DEF 
IN 
IN 
IN 
PVDDQ_DEF 
IN 
IN 
BI 
IN 
OUT 
IN 
IN 
IN 
IN 
IN 
IN 
BI 
54 OF 270 
Wed Feb 08 16:34:43 2017 
DQS0N DQS0P 
DQS10N DQS10P DQS11N DQS11P DQS12N DQS12P DQS13N DQS13P DQS14N DQS14P DQS15N DQS15P DQS16N 
DQS16P DQS17N DQS17P 
DQS1N DQS1P DQS2N DQS2P DQS3N DQS3P 
DQS4N DQS4P DQS5N DQS5P DQS6N DQS6P DQS7N DQS7P DQS8N DQS8P DQS9N DQS9P 
VSS<83> 
VSS<82> 
VSS<81> 
VSS<80> 
VSS<79> 
VSS<78> 
VSS<77> 
VSS<76> 
VSS<75> 
VSS<74> 
VSS<73> 
VSS<72> 
VSS<71> 
VSS<70> 
VSS<69> 
VSS<68> 
VSS<93> 
VSS<92> 
VSS<91> 
VSS<90> 
VSS<89> 
VSS<88> 
VSS<87> 
VSS<86> 
VSS<85> 
VSS<84> 
VSS<67> 
VSS<66> 
VSS<65> 
VSS<64> 
VSS<63> 
VSS<62> 
VSS<61> 
VSS<60> 
VSS<59> 
VSS<58> 
VSS<57> 
VSS<56> 
VSS<55> 
VSS<54> 
VSS<53> 
VSS<52> 
VSS<51> 
VSS<50> 
VSS<49> 
VSS<48> 
VSS<47> 
VSS<46> 
VSS<45> 
VSS<44> 
VSS<43> 
VSS<42> 
VSS<41> 
VSS<40> 
VSS<39> 
VSS<38> 
VSS<37> 
VSS<36> 
VSS<35> 
VSS<34> 
VSS<33> 
VSS<32> 
VSS<31> 
VSS<30> 
VSS<29> 
VSS<28> 
VSS<27> 
VSS<26> 
VSS<25> 
VSS<24> 
VSS<23> 
VSS<22> 
VSS<21> 
VSS<20> 
VSS<19> 
VSS<18> 
VSS<17> 
VSS<16> 
VSS<15> 
VSS<14> 
VSS<13> 
VSS<12> 
VSS<11> 
VSS<10> VSS<9> 
VSS<8> 
VSS<7> 
VSS<6> 
VSS<5> 
VSS<4> 
VSS<3> 
VSS<2> 
VSS<1> 
VSS<0> 
VDD<25> 
VDD<24> 
VDD<23> 
VDD<22> 
VDD<21> 
VDD<20> 
VDD<19> 
VDD<18> 
VDD<17> 
VDD<16> 
VDD<15> 
VDD<14> 
VDD<13> 
VDD<12> 
VDD<11> 
VDD<10> 
VDD<9> 
VDD<8> 
VDD<7> 
VDD<6> 
VDD<5> 
VDD<4> 
VDD<3> 
VDD<2> 
VDD<1> 
VDD<0> 
VPP<1> 
VPP<0> 
VTT<1> 
VTT<0> 
VPP<4> 
VPP<3> 
VPP<2> 12V<0> 12V<1> 
DQ<12> 
DQ<11> 
DQ<10> DQ<9> 
DQ<8> 
DQ<7> 
DQ<6> 
A17 
A16_RAS_N 
A15_CAS_N DQ<60> 
DQ<58> 
DQ<50> 
S3_N_C<1> 
S2_N_C<0> 
S1_N 
S0_N 
CKE<1> 
CKE<0> 
ODT<1> 
ODT<0> 
DQ<21> 
DQ<19> 
DQ<18> 
DQ<27> DQ<28> 
CB<5> 
CB<4> 
CB<3> 
CB<2> 
A8 
A7 
A6 
DQ<45> 
DQ<44> 
DQ<41> 
DQ<51> 
A2 
ALERT_N 
ACT_N 
VREFCA 
SCL SDA SA<0> 
SA<1> SA<2> VDDSPD 
DQ<1> DQ<2> 
RFU<2> 
DQ<31> DQ<32> DQ<33> DQ<34> DQ<35> DQ<36> DQ<37> DQ<38> 
A0 A1 
A10 A11 A12 A13 A14_WE_N 
A3 A4 A5 
A9 
BG<1> 
C<2> 
CB<7> 
CB<6> 
CB<1> 
CB<0> 
DQ<63> 
DQ<62> 
DQ<61> 
DQ<59> 
DQ<57> 
DQ<56> 
DQ<55> 
DQ<54> 
DQ<53> 
DQ<52> 
DQ<49> 
DQ<48> 
DQ<47> 
DQ<46> 
DQ<43> 
DQ<40> 
DQ<39> 
DQ<30> 
DQ<26> 
DQ<25> 
DQ<24> 
DQ<23> 
DQ<22> 
DQ<20> 
DQ<17> 
DQ<16> 
DQ<15> 
DQ<14> 
DQ<13> 
DQ<5> 
DQ<4> 
DQ<3> 
DQ<0> 
EVENT_N 
PAR 
RESET_N 
RFU<1> 
RFU<0> 
SAVE_N_NC 
BG<0> 
CK1P 
CK1N 
CK0P 
CK0N 
DQ<29> 
DQ<42> BA<0> 
BA<1> 
PVDDQ (SINGLE SIDE) CAP: 10UF X1, 22UF X50 PVTT CAP: 100UF X2, 47UF X1 
PVDDQ (DOUBLE SIDE) CAP: 100UF X8, 47UF X41 
PVPP CAP: 10UF X12 
BOM_SS=NOPOP 
BOM_SS=NOPOP 
BOM_SS=NOPOP 
BOM_SS=NOPOP UNSTUFF FOR SKU B 
CPU0 DDR4 CH F DIMM1 
CAP BETWEEN DIMM 
PLACE CAP NEAR DIMM CONNECTOR 
WIWYNN CORPORATION SMBUS ADDR: 0XAA 
2/4 
3/4 
4/4 
1/4 



SOCKET_P_MECH_A 
SOCKET_P_MECH_A 
1/16W 
1/16W 
1/16W 
1/16W 
1/16W 
1/16W 
H_CPU1_MSMI_G_N 
H37604-101 
G21796-017 
PLASTIC 
PWRGD_CPU1_DRAMPWROK_GHJ_G 
AD17 
DB51 
RIGHT 
0402 
PD_CPU1_TXT_PLTEN 
PD_CPU1_BIST_ENABLE 
H_CPU1_FAST_WAKE_N 
PU_CPU1_SOCKET_ID_1 
FM_CPU1_SKTOCC_LVT3_N 
XDP_CPU1_TDO 
PU_PIROM_CPU1_ADDR0 
PD_PIROM_CPU1_ADDR1 
PD_PIROM_CPU1_ADDR2 
XDP_CPU_PRDY_N 
XDP_CPU_PREQ_N 
PD_CPU1_KSFC_DIS 
H_PMSYNC_CLK_24M 
FM_CPU1_SM_WP 
TP_CPU1_NMI 
PU_CPU1_LEGACY_SKT 
PD_CPU1_TEST12 
H_CPU1_PROCHOT_G_N 
TP_CPU1_PROC_DIS_G_N 
PU_CPU1_SAFE_MODE_BOOT 
PU_CPU1_FRMAGENT 
H_CPU1_THERMTRIP_G_N 
H_CPU1_BMCINIT 
PU_CPU1_TXT_AGENT 
SMB_CPU1_PE_HP_GTL_SCL 
SMB_DDR_GHJ_SCL_G_R 
SMB_CPU1_PE_HP_GTL_SDA 
SMB_DDR_KLM_SDA_G_R 
SMB_DDR_KLM_SCL_G_R 
H_CPU1_MEMKLM_MEMHOT_G_N 
H_CPU1_MEMGHJ_MEMHOT_G_N 
M_KLM_RST_N 
CLK_100M_CPU1_BCLK2_DP 
XDP_CPU_TRST_N 
XDP_CPU_TMS 
M_K_CPU_VREF 
M_J_CPU_VREF 
M_G_CPU_VREF 
SMB_PIROM_CPU1_SCL 
SMB_PIROM_CPU1_SDA 
RST_CPU1_G_N 
H_CPU1_ERR2_G_N 
H_CPU1_ERR0_G_N 
H_PM_SYNC_GTL 
FM_CPU1_PKGID1 
A_CPU1_MCP01_RBIAS 
TP_XDP_CPU1_OBSDATA_B2_MBP4_N 
TP_XDP_CPU1_OBSDATA_B3_MBP5_N 
M_L_CPU_VREF 
PD_CPU1_TEST14 
PD_CPU1_TEST13 
PU_CPU1_TSC_SYNC 
PWRGD_CPU1_G 
H_CPU1_ERR1_G_N 
CLK_100M_CPU1_BCLK0_DP 
CLK_100M_CPU1_BCLK0_DN 
CLK_100M_CPU1_BCLK1_DP 
CLK_100M_CPU1_BCLK1_DN 
CLK_100M_CPU1_BCLK2_DN 
M_GHJ_RST_N 
A_CPU1_GHJ_RCOMP1 
A_CPU1_KLM_RCOMP2 
SMB_DDR_GHJ_SDA_G_R 
M_H_CPU_VREF 
M_M_CPU_VREF 
TP_XDP_CPU1_OBSDATA_B0_MBP2_N 
XDP_CPU_MBP1_N 
XDP_CPU_MBP0_N 
XDP_CPU1_TDI 
XDP_CPU_TCK0 
XDP_CPU_OBSFN_B1_MBP7_N 
TP_XDP_CPU1_OBSDATA_B1_MBP3_N 
A_CPU1_UPI2_RBIAS 
A_CPU1_UPI01_RBIAS 
A_CPU1_PE012_RBIAS 
A_CPU1_PE3_RBIAS 
A_CPU1_KLM_RCOMP0 
A_CPU1_KLM_RCOMP1 
A_CPU1_GHJ_RCOMP0 
A_CPU1_GHJ_RCOMP2 
PWRGD_CPU1_DRAMPWROK_KLM_G 
H_PMSYNC_CLK_24M_CPU1 
H_PM_SYNC_GTL_R2 
PD_CPU1_EAR_N 
PECI_CPU_G 
SVID_ALERT0_CPU1_N 
SVID_CLK0_CPU1 
SVID_DIO0_CPU1 
SVID_ALERT1_CPU1_N 
SVID_CLK1_CPU1 
SVID_DIO1_CPU1 
FM_CPU1_PROC_ID1 
FM_CPU1_PKGID2 
FM_CPU1_PKGID0 
XDP_CPU_OBSFN_B0_MBP6_N 
FM_CPU1_PROC_ID0 
TP_CPU1_SOCKET_ID_2 
PU_CPU1_SOCKET_ID_0 
SVID_CLK0_CPU1_R 
SVID_CLK1_CPU1_R 
SVID_DIO1_CPU1_R 
SVID_ALERT1_CPU1_R_N 
SVID_DIO0_CPU1_R 
SVID_ALERT0_CPU1_R_N 
H_CPU1_CATERR_G_N 
1
2
G21796-017 
CHIP 
R9N2 
100.0 
G21796-047 
2 CHIP 
49.9 1
R9N1 
5% 0402 2 0.0 R3B3 1G21497-005 
5% 0.0 0402 2G21497-005 1R3B5 
1.0% 0402 2 221 R3B1 G21796-271 1
221 1.0% 0402 2R1C1 1G21796-271 
0402 0.0 R1C3 5% 21G21497-005 
0.0 5% 2R1C2 1G21497-005 
G21796-017 
CHIP 
100.0 
2
1
R3B4 
CHIP 
49.9 
R3B2 
G21796-047 
1
2
2
1
0402 
G21796-072 
1/16W 
CHIP 
1% 
4.75K 
R6P39 
DA72 
U64 
CK29 
DD47 
AM11 
AK11 
AL12 
AL14 
AT19 
TBD 
AH11 
AG10 
AC12 
AJ10 
AF11 
AA12 
Y11 
AE12 
CU32 
CT31 
CP29 
CR30 
CN30 
CL30 
AA14 
AC14 
W14 
Y13 
AT29 
AP29 
CL28 
AE18 
AK63 
AH63 
CP61 
CR26 
CP27 
CT25 
AJ64 
CT61 
CV61 
AN30 
Y43 
AB43 
AC42 
AJ18 
AF17 
CR28 
DC48 
DD49 
DV63 
AH13 
AF13 
AM19 
AL18 
CT59 
CW58 
CW56 
AE20 
AP11 
CU58 
CV57 
DC72 
CW72 
AG16 
AR12 
AB13 
CV59 
AE14 
AY19 
DC50 
AW14 
AB17 
AJ12 
BA20 
BD23 
AJ14 
AV17 
AN20 
AU12 
AF15 
AR14 
CY71 
DB71 
AC16 
AR18 
AU22 
AU16 
AU20 
DE44 
DC44 
DB45 
AB15 
AW18 
AV15 
DJ44 
DG44 
DL44 
AU24 
AW24 
U2D1 
IC 
BC24 
AP21 
CU26 
G21796-047 0402 CHIP 1/16W 
1
R7P25 49.9 1% 
2
1/16W 
2 CHIP 
0402 
1
1% 
R8N2 
10.0K 
CHIP 2
0402 
1
1% 
R8N5 
10.0K 
1/16W 
0402 
CHIP 2
1
R8N3 
1% 
1/16W 
10.0K 
2
1
1% 
0402 
CHIP 
1/16W 
1.8K 
R8N4 
2
1
R8N1 
1% 
0402 
1.8K 
1/16W 
CHIP 
CHIP G21796-047 R7P26 49.9 1% 
1
1/16W 
2
0402 
R3D4 
49.9 
1% 
1/16W 
CHIP 
1
G21796-047 
0402 
2
XLU2 
H37604-201 
LEFT 
PLASTIC 
XRU2 
1/16W 
G21796-365 
CHIP 
0402 
90.9 
R7P17 
2
1% 
1
49.9 
G21796-047 
0402 
CHIP 
1/16W 
R7P11 
2
1
1% 
49.9 
G21796-047 
1/16W 
CHIP 
0402 
1% 
2
1
R3D19 
1% 
1/16W 
G21796-047 
R7P10 
0402 
49.9 
CHIP 2
1
1/16W 
G21796-047 
0402 
CHIP 
1% 
49.9 
2
1
R7P8 
R7P16 
90.9 
1% 
1/16W 
CHIP 
G21796-365 
0402 
2
1
CHIP 
1/16W 
R3D3 
100.0 
1% 
0402 
2
1
G21796-365 
1/16W 
90.9 
R3D2 
CHIP 
0402 
2
1% 
1
CHIP 
1/16W 
0402 
1% 
90.9 
R3D1 
2
1
G21796-365 
0402 
G21796-017 
1/16W 
100.0 
R7P19 
1
2CHIP 
1% 
HOST FABRIC INTERFACE 
NON-MCP SUPPORT 
MCP SUPPORT 
RESERVED 
RESERVED 
3'B111-3'B011 
3'B000 
3'B010 
3'B001 RESERVED FOR FUTURE PROCESSOR 
SKYLAKE PROCESSOR 
RESERVED 
RESERVED 
2'B11 
2'B00 
2'B10 
2'B01 
92 
96 
90 
90 
97 
90 
112 118 146 190 
112 
156 
156 
156 
21 112 
112 21 
90 
114 21 
156 
90 
90 
95 93 
90 
90 
92 
90 156 
90 
163 
99 
163 
99 
99 
94 95 152 
94 95 152 
83 84 85 86 87 88 
103 
112 21 
112 21 
100 
100 
100 
156 
96 
92 
93 
118 21 
113 190 
100 
90 
90 
97 
96 
93 
103 
103 
103 
103 
103 
77 78 79 80 81 82 
99 
100 
100 
21 112 
21 112 
112 
111 254 21 112 
21 112 
96 
90 
21 166 
191 
190 
190 
21 112 
191 
90 
193 206 213
193 223 226
193 223 226
193 223 226
193 206 213
193 206 213
92 
1% 
0402 
1/16W 
0402 
1% 
1/16W 
0402 
1/16W 
1% 
1/16W 
1% 
0402 G21796-016 
G21796-016 
G21796-016 
G21796-336 
G21796-336 
DESIGN NOTE: 
DESIGN NOTE: 
CAD NOTE: 
BOM NOTE: 
CAD NOTE: 
DEFINITION PKG_ID[2:0] DEFINITION PROC_ID [1:0] 
ALTERNATE: H63715-002 
P0 
P0 
DO NOT SCALE DRAWING 
ASSEMBLY IPN PRIMARY :H63715-002, 
SHEET 
B
AA
B
B
SIZE 
SCALE: 
234
1234
DEPARTMENT CODE 
1
DOCUMENT NUMBER REV 
OUT 
OUT 
OUT 
OUT 
IN 
OUT 
OUT 
BI 
BI 
OUT 
OUT 
IN 
IN 
IN 
IN 
PVCCIO_CPU1 
IN 
IN 
OUT 
IN 
BI 
IN 
IN 
IN 
IN 
IN 
OUT 
BI 
OUT 
OUT 
BI 
OUT 
BI 
BI 
BI 
PVCCIO_CPU1 
BI 
IN 
IN 
IN 
IN 
BI 
IN 
OUT 
IN 
BI 
BI 
IN 
IN 
IN 
IN 
IN 
BI 
OUT 
BI 
P3V3_STBY 
OUT 
OUT 
OUT 
OUT 
OUT 
P3V3_STBY 
OUT 
OUT 
OUT 
IN 
OUT 
OUT 
IN 
IN 
OUT 
IN 
IN 
OUT 
IN 
OUT 
IN 
BI 
IN 
IN 
IN 
IN 
IN 
IN 
IN 
55 OF 270 
Wed Feb 08 16:34:43 2017 
WITHIN 1.1 OF CPU PINS 
PLACE RBIAS RESISTORS 
PLACE RCOMP RESISTORS 
WITHIN 1 OF CPU PINS UPI2_RBIAS<0> UPI2_RBIAS<1> UPI01_RBIAS<0> UPI01_RBIAS<1> 
TXT_PLTEN TXT_AGENT 
TSC_SYNC 
TRST_N TMS 
THERMTRIP_N 
TEST_15 
TEST_14 
TEST_13 
TEST_12 
TDO 
TDI 
TCK 
SVIDDATA<0> 
SVIDDATA<1> 
SVIDCLK<0> 
SVIDCLK<1> 
SVIDALERT_N<0> 
SVIDALERT_N<1> 
SOCKET_ID<0> 
SOCKET_ID<1> 
SOCKET_ID<2> 
SM_WP 
SMBDAT SMBCLK 
SKTOCC_N 
SAFE_MODE_BOOT 
RESET_N PWRGOOD 
PROC_ID<0> PROC_ID<1> 
PROCHOT_N PROCDIS_N 
PREQ_N PRDY_N 
PM_FAST_WAKE_N 
PMSYNC_CLK PMSYNC 
PKGID<0> PKGID<1> PKGID<2> 
PIROM_ADDR<0> PIROM_ADDR<1> PIROM_ADDR<2> 
PE_HP_SDA 
PE_HP_SCL 
PECI 
PE3_RBIAS<0> PE3_RBIAS<1> 
PE012_RBIAS<0> PE012_RBIAS<1> 
NMI 
MSMI_N 
MEM_HOT_C345_N MEM_HOT_C012_N 
MCP01_RBIAS<0> MCP01_RBIAS<1> LEGACY_SKT 
FRMAGENT 
ERROR_N<0> ERROR_N<1> ERROR_N<2> 
EAR_N 
DDR5_CAVREF 
DDR4_CAVREF 
DDR3_CAVREF 
DDR345_SPDSDA 
DDR345_SPDSCL 
DDR345_RESET_N 
DDR345_RCOMP<0> DDR345_RCOMP<1> DDR345_RCOMP<2> 
DDR345_DRAM_PWR_OK 
DDR2_CAVREF 
DDR1_CAVREF 
DDR0_CAVREF 
DDR012_SPDSDA 
DDR012_SPDSCL 
DDR012_RESET_N 
DDR012_RCOMP<0> DDR012_RCOMP<1> DDR012_RCOMP<2> 
DDR012_DRAM_PWR_OK 
CATERR_N 
BPM_N<0> BPM_N<1> BPM_N<2> BPM_N<3> BPM_N<4> BPM_N<5> BPM_N<6> BPM_N<7> 
BMCINIT 
BIST_ENABLE 
BCLK2_DP 
BCLK2_DN 
BCLK1_DP 
BCLK1_DN 
BCLK0_DP 
BCLK0_DN 
PIROM_ADDR[2:0] 3B001 
CPU1 PIROM ADDRESS: 0XA2 
CPU SYMBOLS 1-30 ARE PRELIMINARY AND SUBJECT TO CHANGE 
SKYLAKE - SKT1 - 1 OF 21 
SKX_EXT_B 
INA
ILER
RY
P
M
WIWYNN CORPORATION 
1/30 



TP_CPU1_RSVD_291 
TP_CPU1_RSVD_299 
C24 
H_CPU1_FIVR_FAULT_G 
CLK_322M_OSC_CPU1_RC_DP 
CPU_XDP_PRESENT_N 
TP_CPU1_RSVD_217 
B3 
TP_CPU1_RSVD_205 
VSENSE_P1V8MCP_CPU1_SKT_VRTN 
TP_CPU1_RSVD_241 
TP_CPU1_RSVD_236 
TP_CPU1_RSVD_235 
TP_CPU1_RSVD_234 
TP_CPU1_RSVD_230 
TP_CPU1_RSVD_229 
TP_CPU1_RSVD_227 
TP_CPU1_RSVD_226 
TP_CPU1_RSVD_211 
TP_CPU1_RSVD_212 
TP_CPU1_RSVD_300 
TP_CPU1_RSVD_303 
FM_CPU1_RC_ERROR_N 
TP_CPU1_RSVD_275 
TP_CPU1_RSVD_276 
TP_CPU1_RSVD_278 
TP_CPU1_RSVD_279 
TP_CPU1_RSVD_280 
TP_CPU1_RSVD_281 
TP_CPU1_RSVD_265 
TP_CPU1_RSVD_256 
TP_CPU1_RSVD_258 
TP_CPU1_RSVD_259 
TP_CPU1_RSVD_TEST_11 
TP_CPU1_RSVD_253 
TP_CPU1_RSVD_292 
TP_CPU1_RSVD_293 
TP_CPU1_RSVD_289 
TP_CPU1_RSVD_284 
TP_CPU1_RSVD_270 
TP_CPU1_RSVD_267 
TP_CPU1_RSVD_266 
TP_CPU1_RSVD_262 
TP_CPU1_RSVD_261 
TP_CPU1_RSVD_260 
TP_CPU1_RSVD_243 
TP_CPU1_RSVD_242 
TP_CPU1_RSVD_298 
TP_CPU1_RSVD_269 
TP_CPU1_RSVD_271 
TP_CPU1_RSVD_272 
TP_CPU1_RSVD_273 
TP_CPU1_RSVD_252 
TP_CPU1_RSVD_282 
TP_CPU1_RSVD_283 
TP_CPU1_RSVD_244 
TP_CPU1_RSVD_245 
TP_CPU1_RSVD_246 
TP_CPU1_RSVD_247 
TP_CPU1_RSVD_248 
TP_CPU1_RSVD_249 
TP_CPU1_RSVD_250 
TP_CPU1_RSVD_251 
TP_CPU1_RSVD_268 
TP_CPU1_RSVD_274 
TP_CPU1_RSVD_304 
TP_CPU1_RSVD_199 
TP_CPU1_RSVD_233 
TP_CPU1_RSVD_232 
TP_CPU1_RSVD_231 
TP_CPU1_RSVD_237 
TP_CPU1_RSVD_238 
TP_CPU1_RSVD_239 
TP_CPU1_RSVD_240 
TP_CPU1_RSVD_223 
TP_CPU1_RSVD_225 
TP_CPU1_RSVD_224 
TP_CPU1_RSVD_222 
VSENSE_P1V8MCP_CPU1_SKT_VSEN 
TP_CPU1_RSVD_TEST_3 
TP_CPU1_RSVD_TEST_5 
TP_CPU1_RSVD_216 
CLK_322M_OSC_CPU1_RC_DN 
TP_CPU1_RSVD_210 
CLK_100M_CPU1_RC_REFCLK0_DP 
TP_CPU1_RSVD_198 
TP_CPU1_RSVD_194 
CLK_100M_CPU1_RC_REFCLK0_DN 
TP_CPU1_RSVD_208 
PD_CPU1_DMIMODE_OVERRIDE 
TP_CPU1_RSVD_214 
TP_CPU1_RSVD_277 
TP_CPU1_RSVD_264 
TP_CPU1_RSVD_263 
TP_CPU1_RSVD_254 
TP_CPU1_RSVD_285 
TP_CPU1_RSVD_286 
TP_CPU1_RSVD_287 
TP_CPU1_RSVD_288 
TP_CPU1_RSVD_290 
PD_CPU1_RSVD_TEST_1 
PD_CPU1_RSVD_TEST_2 
TP_CPU1_RSVD_204 
TP_CPU1_RSVD_TEST_4 
XDP_CPU_PWR_DEBUG_N 
TP_CPU1_RSVD_219 
TP_CPU1_RSVD_218 
TP_CPU1_RSVD_228 
P1V8_MCP_CPU1 
PVCCMCP_CPU1 
R8R1 
G21796-047 
49.9 
1% 
0402 
CHIP 
1/16W 
2
1
G21796-047 
R8P3 
49.9 
1% 
0402 
CHIP 
1/16W 
2
1
AP17 
AM59 
AV21 
AW12 
AU14 
AP61 
AP27 
AP25 
AP23 
AN62 
AN60 
AN22 
AN18 
AM61 
AM27 
AM25 
AM23 
AM21 
AL62 
AL60 
AL58 
AL26 
AL22 
AL20 
AK69 
AK61 
AK59 
AK27 
AK21 
AJ70 
AJ62 
AJ60 
AJ58 
AJ56 
AJ20 
AH73 
AH71 
AH57 
AH55 
AH19 
AH15 
AG72 
AG56 
AG54 
AG52 
AG50 
AG48 
AG20 
AF71 
AF53 
AF51 
AF49 
AF47 
AF19 
AE72 
AE52 
AE50 
AE48 
AE46 
AD51 
AD49 
AD47 
Y65 
Y23 
W66 
V67 
V65 
U66 
T67 
R66 
R62 
P65 
M63 
K61 
J62 
J46 
H85 
H83 
H1 
G84 
G64 
F83 
F65 
F23 
F3 
E84 
E24 
E4 
E2 
D83 
D65 
D17 
D5 
C82 
C18 
C6 
B81 
B77 
B17 
B15 
B13 
B7 
A24 
A16 
A14 
A6 
A4 
AF45 
AG46 
AM13 
AN12 
AN14 
AY13 
IC 
TBD 
U2D1 
AK57 
AN26 
AN24 
G2 
TP FAB3 RECONNECT 0921 
92 
104 
111 255 22 
193 
133 120 145 
193 
104 
103 
103 
90 
111 118 254 22 
DESIGN NOTE: 
DESIGN NOTE: 
CLKS USED FOR DEBUG ONLY
DO NOT SCALE DRAWING SHEET 
B
AA
B
B
SIZE 
SCALE: 
234
1234
DEPARTMENT CODE 
1
DOCUMENT NUMBER REV 
IN 
IN 
OUT 
OUT 
IN 
IN 
OUT 
IN 
IN 
IN 
IN 
56 OF 270 
Wed Feb 08 16:34:44 2017 
TEST_5 
TEST_4 TEST_3 TEST_2 
TEST_11 
TEST_1 
RSVD<194> RSVD<195> RSVD<196> RSVD<197> RSVD<198> RSVD<199> RSVD<200> RSVD<201> RSVD<202> 
RSVD<203> RSVD<204> RSVD<205> RSVD<206> RSVD<207> RSVD<208> 
RSVD<209> RSVD<210> RSVD<211> RSVD<212> RSVD<213> 
RSVD<214> 
RSVD<215> RSVD<216> 
RSVD<217> RSVD<218> RSVD<219> 
RSVD<220> 
RSVD<221> RSVD<222> RSVD<223> RSVD<224> RSVD<225> RSVD<226> RSVD<227> 
RSVD<228> RSVD<229> RSVD<230> RSVD<231> RSVD<232> RSVD<233> RSVD<234> 
RSVD<235> RSVD<236> RSVD<237> RSVD<238> RSVD<239> RSVD<240> RSVD<241> 
RSVD<242> 
RSVD<243> RSVD<244> RSVD<245> RSVD<246> RSVD<247> RSVD<248> 
RSVD<249> RSVD<250> RSVD<251> RSVD<252> RSVD<253> RSVD<254> 
RSVD<256> RSVD<257> RSVD<258> RSVD<259> 
RSVD<260> RSVD<261> RSVD<262> RSVD<263> RSVD<264> RSVD<265> RSVD<266> RSVD<267> RSVD<268> RSVD<269> RSVD<270> 
RSVD<271> RSVD<272> RSVD<273> RSVD<274> RSVD<275> 
RSVD<276> RSVD<277> 
RSVD<278> RSVD<279> RSVD<280> RSVD<281> 
RSVD<282> RSVD<283> RSVD<284> RSVD<285> RSVD<286> RSVD<287> RSVD<288> RSVD<289> 
RSVD<290> RSVD<291> RSVD<292> RSVD<293> RSVD<294> RSVD<295> RSVD<296> 
RSVD<298> RSVD<299> RSVD<300> RSVD<301> RSVD<302> RSVD<303> RSVD<304> 
PWR_DEBUG_N 
FIVR_FAULT 
DMIMODE_OVERRIDE 
DEBUG_EN_N 
CPU SYMBOLS 1-30 ARE PRELIMINARY AND SUBJECT TO CHANGE 
SKYLAKE - SKT1 - 2 OF 21 
SKX_EXT_B 
INA
ILER
RY
P
M
BOM_COST=PROC_SOCKET 
ROOM=CPU1 
WIWYNN CORPORATION 
2/30 



M_G_DQ<63:0> 
37 
M_G_ACT_N 
M_G_ALERT_N 
M_G_PAR M_G_C<2> 
M_G_ECC<7:0> 
M_G_CLK_DP<3:0> 
M_G_CLK_DN<3:0> 
M_G_ODT<3:0> 
M_G_CS_N<7:0> 
M_G_CKE<3:0> 
M_G_BG<1:0> 
M_G_BA<1:0> 
M_G_MA<17:0> 
M_G_DQS_DN<17:0> 
M_G_DQS_DP<17:0> 
0
7
6
5
3
4
0
1
2
11
0
0
1
63 
62 
61 
60 
59 
58 
57 
2
56 
55 
54 
53 
52 
51 
50 
49 
48 
3
47 
46 
45 
44 
43 
42 
41 
40 
39 
38 
1
35 
36 
34 
33 
32 
30 
31 
29 
28 
0
27 
25 
26 
24 
23 
22 
21 
20 
19 
18 
17 
16 
15 
14 
13 
12 
11 
10 
9
7
8
6
5
4
3
2
1
0
7
6
5
M77 
J60 
B61 
C52 
G54 
D61 
F63 
G46 
C62 
C64 
B63 
D63 
F55 
C54 
J56 
C56 
D55 
B55 
G56 
B57 G52 
F49 
D47 
F47 
B51 
D49 
F45 
K45 
AN86 
AN84 
AE86 
AE84 
AR86 
AR84 
AG86 
AG84 
W86 
W84 
L86 
L84 
AA86 
AA84 
N86 
N84 
V81 
T79 
N82 
M81 
W80 
V79 
R82 
N80 
L76 
R76 
M73 
P73 
P77 
L74 
R74 
C42 
B41 
C38 
E38 
E42 
F41 
B39 
F39 
K37 
P37 
L34 
N34 
L38 
N38 
K35 
P35 
K31 
P31 
L28 
N28 
L32 
N32 
K29 
P29 
K25 
P25 
P23 
T23 
L26 
N26 
H23 
K23 
AJ84 
R84 
P79 
T75 
G40 
R36 
R30 
N24 
AH67 
AL84 
U84 
U82 
K75 
A40 
J36 
J30 
J24 
AB67 
AH85 
P85 
R80 
P75 
E40 
N36 
N30 
R24 
AF67 
AM85 
V85 
T81 
M75 
C40 
L36 
L30 
L24 
AD67 
AC68 
AG68 
AD65 
AF65 
AD69 
AF69 
AC66 
AG66 
F53 
F57 
D57 
C58 
G58 
F59 
D59 
G60 
C60 
F61 
J54 
G62 
J64 
J48 
F51 
K49 
D51 
K47 
C50 
C48 
G50 
G48 
D53 
IC 
TBD 
U2D1 
17 
3
16 
15 
12 
13 
14 
11 
10 
9
8
7
4
5
6
4
2
3
2
1
0
17 
16 
13 
1
14 
15 
11 
12 
10 
9
8
7
6
5
0
3
4
0
2
1
17 
16 
15 
14 
13 
3
12 
9
10 
11 
7
8
6
5
4
2
2
3
1
0
3
2
1
0
1
2
3
0
77 78 
77 78 
77 78 
77 78 77 78 
77 78 
77 78 
77 78 
77 78 
77 78 
77 78 
77 78 
77 78 
77 78 
77 78 
77 78 
DESIGN NOTE: 
DO NOT SCALE DRAWING SHEET 
B
AA
B
B
SIZE 
SCALE: 
234
1234
DEPARTMENT CODE 
1
DOCUMENT NUMBER REV 
BI 
BI 
OUT 
OUT 
BI 
BI 
OUT 
OUT 
OUT 
OUT 
OUT 
OUT 
OUT 
IN 
OUT OUT 
57 OF 270 
Wed Feb 08 16:34:44 2017 
DDR0_PAR 
DDR0_ODT<0> DDR0_ODT<1> DDR0_ODT<2> DDR0_ODT<3> 
DDR0_MA<0> 
DDR0_MA<1> DDR0_MA<2> DDR0_MA<3> DDR0_MA<4> DDR0_MA<5> DDR0_MA<6> DDR0_MA<7> DDR0_MA<8> DDR0_MA<9> DDR0_MA<10> DDR0_MA<11> DDR0_MA<12> DDR0_MA<13> 
DDR0_MA<14> DDR0_MA<15> DDR0_MA<16> DDR0_MA<17> 
DDR0_ECC<0> DDR0_ECC<1> DDR0_ECC<2> DDR0_ECC<3> DDR0_ECC<4> 
DDR0_ECC<5> DDR0_ECC<6> DDR0_ECC<7> 
DDR0_DQS_DP<0> DDR0_DQS_DP<1> 
DDR0_DQS_DP<2> DDR0_DQS_DP<3> DDR0_DQS_DP<4> DDR0_DQS_DP<5> DDR0_DQS_DP<6> DDR0_DQS_DP<7> DDR0_DQS_DP<8> DDR0_DQS_DP<9> DDR0_DQS_DP<10> DDR0_DQS_DP<11> DDR0_DQS_DP<12> DDR0_DQS_DP<13> DDR0_DQS_DP<14> 
DDR0_DQS_DP<15> DDR0_DQS_DP<16> DDR0_DQS_DP<17> 
DDR0_DQS_DN<0> DDR0_DQS_DN<1> DDR0_DQS_DN<2> DDR0_DQS_DN<3> DDR0_DQS_DN<4> DDR0_DQS_DN<5> DDR0_DQS_DN<6> DDR0_DQS_DN<7> 
DDR0_DQS_DN<8> DDR0_DQS_DN<9> DDR0_DQS_DN<10> DDR0_DQS_DN<11> DDR0_DQS_DN<12> DDR0_DQS_DN<13> DDR0_DQS_DN<14> DDR0_DQS_DN<15> DDR0_DQS_DN<16> DDR0_DQS_DN<17> 
DDR0_DQ<0> DDR0_DQ<1> DDR0_DQ<2> DDR0_DQ<3> DDR0_DQ<4> DDR0_DQ<5> DDR0_DQ<6> DDR0_DQ<7> DDR0_DQ<8> 
DDR0_DQ<9> DDR0_DQ<10> DDR0_DQ<11> DDR0_DQ<12> DDR0_DQ<13> DDR0_DQ<14> DDR0_DQ<15> DDR0_DQ<16> DDR0_DQ<17> DDR0_DQ<18> DDR0_DQ<19> DDR0_DQ<20> DDR0_DQ<21> 
DDR0_DQ<22> DDR0_DQ<23> DDR0_DQ<24> DDR0_DQ<25> DDR0_DQ<26> DDR0_DQ<27> DDR0_DQ<28> DDR0_DQ<29> DDR0_DQ<30> DDR0_DQ<31> DDR0_DQ<32> DDR0_DQ<33> DDR0_DQ<34> 
DDR0_DQ<35> DDR0_DQ<36> DDR0_DQ<37> DDR0_DQ<38> DDR0_DQ<39> DDR0_DQ<40> DDR0_DQ<41> DDR0_DQ<42> DDR0_DQ<43> DDR0_DQ<44> DDR0_DQ<45> DDR0_DQ<46> DDR0_DQ<47> 
DDR0_DQ<48> DDR0_DQ<49> DDR0_DQ<50> DDR0_DQ<51> DDR0_DQ<52> DDR0_DQ<53> DDR0_DQ<54> DDR0_DQ<55> DDR0_DQ<56> DDR0_DQ<57> DDR0_DQ<58> DDR0_DQ<59> DDR0_DQ<60> 
DDR0_DQ<61> DDR0_DQ<62> DDR0_DQ<63> 
DDR0_CS_N<0> DDR0_CS_N<1> DDR0_CS_N<2> DDR0_CS_N<3> DDR0_CS_N<4> DDR0_CS_N<5> DDR0_CS_N<6> 
DDR0_CS_N<7> 
DDR0_CLK_DP<0> DDR0_CLK_DP<1> DDR0_CLK_DP<2> DDR0_CLK_DP<3> 
DDR0_CLK_DN<0> DDR0_CLK_DN<1> 
DDR0_CLK_DN<2> DDR0_CLK_DN<3> 
DDR0_CKE<0> DDR0_CKE<1> DDR0_CKE<2> DDR0_CKE<3> 
DDR0_CID<2> 
DDR0_BG<0> DDR0_BG<1> 
DDR0_BA<0> DDR0_BA<1> 
DDR0_ALERT_N DDR0_ACT_N 
CPU SYMBOLS 1-30 ARE PRELIMINARY AND SUBJECT TO CHANGE 
SKYLAKE - SKT1 - 3 OF 21 
SKX_EXT_B 
INA
ILER
RY
P
M
ROOM=CPU1 
BOM_COST=PROC_SOCKET 
WIWYNN CORPORATION 
3/30 



M_H_DQ<63:0> 
F71 
M_H_ACT_N 
M_H_ALERT_N 
M_H_PAR M_H_C<2> 
M_H_ECC<7:0> 
M_H_CLK_DP<3:0> 
M_H_CLK_DN<3:0> 
M_H_ODT<3:0> 
M_H_CS_N<7:0> 
M_H_CKE<3:0> 
M_H_BG<1:0> 
M_H_BA<1:0> 
M_H_MA<17:0> 
M_H_DQS_DN<17:0> 
M_H_DQS_DP<17:0> 
0
7
6
5
3
4
0
1
2
11
0
0
1
63 
62 
61 
60 
59 
58 
57 
2
56 
55 
54 
53 
52 
51 
50 
49 
48 
3
47 
46 
45 
44 
43 
42 
41 
40 
39 
38 
1
37 
35 
36 
34 
33 
32 
30 
31 
29 
28 
0
27 
25 
26 
24 
23 
22 
21 
20 
19 
18 
17 
16 
15 
14 
13 
12 
11 
10 
9
7
8
6
5
4
3
2
1
0
7
6
5
F75 
T63 
W62 
T53 
K55 
M61 
N60 
M47 
N62 
R64 
K63 
L64 
M53 
R54 
N56 
R56 
N54 
T55 
M57 
T57 K51 
R50 
N46 
V47 
J50 
T49 
M45 
R46 
AV81 
AT79 
AN82 
AM81 
AW80 
AV79 
AR82 
AN80 
AH81 
AF79 
AC82 
AB81 
AJ80 
AH79 
AE82 
AC80 
E80 
J80 
F77 
H77 
F81 
H81 
E78 
J78 
D75 
C74 
D71 
G74 
C72 
G72 
K43 
H43 
L40 
N40 
P43 
T43 
K41 
P41 
C36 
B35 
C32 
E32 
E36 
F35 
B33 
F33 
C30 
B29 
C26 
E26 
E30 
F29 
B27 
F27 
U28 
AA28 
V25 
Y25 
V29 
Y29 
U26 
AA26 
AP79 
AD79 
K79 
H73 
N42 
G34 
G28 
AB27 
N68 
AU82 
AG82 
D79 
B73 
J42 
A34 
A28 
T27 
G68 
AR80 
AE80 
H79 
F73 
R42 
E34 
E28 
Y27 
L68 
AT81 
AF81 
F79 
D73 
L42 
C34 
C28 
V27 
J68 
J70 
H69 
J66 
L66 
L70 
M69 
H67 
M67 
J52 
J58 
K57 
N58 
M59 
R58 
T59 
V61 
W60 
K59 
M55 
R60 
T61 
M51 
T51 
N52 
R52 
N48 
N50 
R48 
M49 
T47 
K53 
IC 
TBD 
U2D1 
17 
3
16 
15 
12 
13 
14 
11 
10 
9
8
7
4
5
6
4
2
3
2
1
0
17 
16 
13 
1
14 
15 
11 
12 
10 
9
8
7
6
5
0
3
4
0
2
1
17 
16 
15 
14 
13 
3
12 
9
10 
11 
7
8
6
5
4
2
2
3
1
0
3
2
1
0
1
2
3
0
79 80 
79 80 
79 80 
79 80 79 80 
79 80 
79 80 
79 80 
79 80 
79 80 
79 80 
79 80 
79 80 
79 80 
79 80 
79 80 
DESIGN NOTE: 
DO NOT SCALE DRAWING SHEET 
B
AA
B
B
SIZE 
SCALE: 
234
1234
DEPARTMENT CODE 
1
DOCUMENT NUMBER REV 
BI 
BI 
OUT 
OUT 
BI 
BI 
OUT 
OUT 
OUT 
OUT 
OUT 
OUT 
OUT 
IN 
OUT OUT 
58 OF 270 
Wed Feb 08 16:34:44 2017 
DDR1_PAR 
DDR1_ODT<0> DDR1_ODT<1> DDR1_ODT<2> DDR1_ODT<3> 
DDR1_MA<0> 
DDR1_MA<1> DDR1_MA<2> DDR1_MA<3> DDR1_MA<4> DDR1_MA<5> DDR1_MA<6> DDR1_MA<7> DDR1_MA<8> DDR1_MA<9> DDR1_MA<10> DDR1_MA<11> DDR1_MA<12> DDR1_MA<13> 
DDR1_MA<14> DDR1_MA<15> DDR1_MA<16> DDR1_MA<17> 
DDR1_ECC<0> DDR1_ECC<1> DDR1_ECC<2> DDR1_ECC<3> DDR1_ECC<4> 
DDR1_ECC<5> DDR1_ECC<6> DDR1_ECC<7> 
DDR1_DQS_DP<0> DDR1_DQS_DP<1> 
DDR1_DQS_DP<2> DDR1_DQS_DP<3> DDR1_DQS_DP<4> DDR1_DQS_DP<5> DDR1_DQS_DP<6> DDR1_DQS_DP<7> DDR1_DQS_DP<8> DDR1_DQS_DP<9> DDR1_DQS_DP<10> DDR1_DQS_DP<11> DDR1_DQS_DP<12> DDR1_DQS_DP<13> DDR1_DQS_DP<14> 
DDR1_DQS_DP<15> DDR1_DQS_DP<16> DDR1_DQS_DP<17> 
DDR1_DQS_DN<0> DDR1_DQS_DN<1> DDR1_DQS_DN<2> DDR1_DQS_DN<3> DDR1_DQS_DN<4> DDR1_DQS_DN<5> DDR1_DQS_DN<6> DDR1_DQS_DN<7> 
DDR1_DQS_DN<8> DDR1_DQS_DN<9> DDR1_DQS_DN<10> DDR1_DQS_DN<11> DDR1_DQS_DN<12> DDR1_DQS_DN<13> DDR1_DQS_DN<14> DDR1_DQS_DN<15> DDR1_DQS_DN<16> DDR1_DQS_DN<17> 
DDR1_DQ<0> DDR1_DQ<1> DDR1_DQ<2> DDR1_DQ<3> DDR1_DQ<4> DDR1_DQ<5> DDR1_DQ<6> DDR1_DQ<7> DDR1_DQ<8> 
DDR1_DQ<9> DDR1_DQ<10> DDR1_DQ<11> DDR1_DQ<12> DDR1_DQ<13> DDR1_DQ<14> DDR1_DQ<15> DDR1_DQ<16> DDR1_DQ<17> DDR1_DQ<18> DDR1_DQ<19> DDR1_DQ<20> DDR1_DQ<21> 
DDR1_DQ<22> DDR1_DQ<23> DDR1_DQ<24> DDR1_DQ<25> DDR1_DQ<26> DDR1_DQ<27> DDR1_DQ<28> DDR1_DQ<29> DDR1_DQ<30> DDR1_DQ<31> DDR1_DQ<32> DDR1_DQ<33> DDR1_DQ<34> 
DDR1_DQ<35> DDR1_DQ<36> DDR1_DQ<37> DDR1_DQ<38> DDR1_DQ<39> DDR1_DQ<40> DDR1_DQ<41> DDR1_DQ<42> DDR1_DQ<43> DDR1_DQ<44> DDR1_DQ<45> DDR1_DQ<46> DDR1_DQ<47> 
DDR1_DQ<48> DDR1_DQ<49> DDR1_DQ<50> DDR1_DQ<51> DDR1_DQ<52> DDR1_DQ<53> DDR1_DQ<54> DDR1_DQ<55> DDR1_DQ<56> DDR1_DQ<57> DDR1_DQ<58> DDR1_DQ<59> DDR1_DQ<60> 
DDR1_DQ<61> DDR1_DQ<62> DDR1_DQ<63> 
DDR1_CS_N<0> DDR1_CS_N<1> DDR1_CS_N<2> DDR1_CS_N<3> DDR1_CS_N<4> DDR1_CS_N<5> DDR1_CS_N<6> 
DDR1_CS_N<7> 
DDR1_CLK_DP<0> DDR1_CLK_DP<1> DDR1_CLK_DP<2> DDR1_CLK_DP<3> 
DDR1_CLK_DN<0> DDR1_CLK_DN<1> 
DDR1_CLK_DN<2> DDR1_CLK_DN<3> 
DDR1_CKE<0> DDR1_CKE<1> DDR1_CKE<2> DDR1_CKE<3> 
DDR1_CID<2> 
DDR1_BG<0> DDR1_BG<1> 
DDR1_BA<0> DDR1_BA<1> 
DDR1_ALERT_N DDR1_ACT_N 
CPU SYMBOLS 1-30 ARE PRELIMINARY AND SUBJECT TO CHANGE 
SKYLAKE - SKT1 - 4 OF 21 
SKX_EXT_B 
INA
ILER
RY
P
M
ROOM=CPU1 
BOM_COST=PROC_SOCKET 
WIWYNN CORPORATION 
4/30 



M_J_DQ<63:0> 
BA72 
AN68 
M_J_ACT_N 
M_J_ALERT_N 
M_J_PAR M_J_C<2> 
M_J_ECC<7:0> 
M_J_CLK_DP<3:0> 
M_J_CLK_DN<3:0> 
M_J_ODT<3:0> 
M_J_CS_N<7:0> 
M_J_CKE <3:0> 
M_J_BG<1:0> 
M_J_BA<1:0> 
M_J_MA<17:0> 
M_J_DQS_DN<17:0> 
M_J_DQS_DP<17:0> 
0
7
6
5
3
4
0
1
2
11
0
0
1
63 
62 
61 
60 
59 
58 
57 
2
56 
55 
54 
53 
52 
51 
50 
49 
48 
3
47 
46 
45 
44 
43 
42 
41 
40 
39 
38 
1
37 
35 
36 
34 
33 
32 
30 
31 
29 
28 
0
27 
25 
26 
24 
23 
22 
21 
20 
19 
18 
17 
16 
15 
14 
13 
12 
11 
10 
9
7
8
6
5
4
3
2
1
0
7
6
5
AR68 
AB61 
AD61 
W52 
AE56 
AA60 
AE62 
AB45 
AA62 
AD63 
V63 
AB63 
AA54 
W54 
AA56 
W56 
AB55 
V55 
AB57 
V57 V51 
AB49 
W46 
AA46 
AB51 
W48 
T45 
V45 
AR76 
AN74 
AK77 
AJ76 
AT75 
AR74 
AM77 
AK75 
AE76 
AC74 
Y77 
W76 
AF75 
AE74 
AB77 
Y75 
W72 
AA70 
R70 
T69 
AA72 
AB71 
T71 
V69 
AM67 
AT67 
AN64 
AR64 
AM65 
AT65 
U40 
AA40 
V37 
Y37 
V41 
Y41 
U38 
AA38 
U34 
AA34 
V31 
Y31 
V35 
Y35 
U32 
AA32 
AD31 
AH31 
AE28 
AG28 
AE32 
AG32 
AD29 
AH29 
AD25 
AH25 
AE22 
AG22 
AE26 
AG26 
AD23 
AH23 
AL74 
AA74 
Y69 
AU66 
AB39 
AB33 
AJ30 
AJ24 
BB71 
AP77 
AD77 
U72 
AL66 
T39 
T33 
AC30 
AC24 
AT71 
AM75 
AB75 
W70 
AR66 
Y39 
Y33 
AG30 
AG24 
AY71 
AN76 
AC76 
V71 
AN66 
V39 
V33 
AE30 
AE24 
AV71 
AU72 
AV69 
AY69 
AV73 
AY73 
AU70 
BA70 
AB53 
AE58 
AD57 
W58 
AA58 
V59 
AB59 
AE60 
AD59 
AG58 
AD55 
AG60 
AG62 
AD53 
W50 
AE54 
AA52 
AC46 
AA50 
AA48 
V49 
AB47 
V53 
IC 
TBD 
U2D1 
17 
3
16 
15 
12 
13 
14 
11 
10 
9
8
7
4
5
6
4
2
3
2
1
0
17 
16 
13 
1
14 
15 
11 
12 
10 
9
8
7
6
5
0
3
4
0
2
1
17 
16 
15 
14 
13 
3
12 
9
10 
11 
7
8
6
5
4
2
2
3
1
0
3
2
1
0
1
2
3
0
81 82 
81 82 
81 82 
81 82 81 82 
81 82 
81 82 
81 82 
81 82 
81 82 
81 82 
81 82 
81 82 
81 82 
81 82 
81 82 
DESIGN NOTE: 
DO NOT SCALE DRAWING SHEET 
B
AA
B
B
SIZE 
SCALE: 
234
1234
DEPARTMENT CODE 
1
DOCUMENT NUMBER REV 
BI 
BI 
OUT 
OUT 
BI 
BI 
OUT 
OUT 
OUT 
OUT 
OUT 
OUT 
OUT 
IN 
OUT OUT 
59 OF 270 
Wed Feb 08 16:34:45 2017 
DDR2_PAR 
DDR2_ODT<0> DDR2_ODT<1> DDR2_ODT<2> DDR2_ODT<3> 
DDR2_MA<0> DDR2_MA<1> 
DDR2_MA<2> DDR2_MA<3> DDR2_MA<4> DDR2_MA<5> DDR2_MA<6> DDR2_MA<7> DDR2_MA<8> DDR2_MA<9> DDR2_MA<10> DDR2_MA<11> DDR2_MA<12> DDR2_MA<13> DDR2_MA<14> 
DDR2_MA<15> DDR2_MA<16> DDR2_MA<17> 
DDR2_ECC<0> DDR2_ECC<1> DDR2_ECC<2> DDR2_ECC<3> DDR2_ECC<4> DDR2_ECC<5> 
DDR2_ECC<6> DDR2_ECC<7> 
DDR2_DQS_DP<0> DDR2_DQS_DP<1> 
DDR2_DQS_DP<2> DDR2_DQS_DP<3> DDR2_DQS_DP<4> DDR2_DQS_DP<5> DDR2_DQS_DP<6> DDR2_DQS_DP<7> DDR2_DQS_DP<8> DDR2_DQS_DP<9> DDR2_DQS_DP<10> DDR2_DQS_DP<11> DDR2_DQS_DP<12> DDR2_DQS_DP<13> DDR2_DQS_DP<14> 
DDR2_DQS_DP<15> DDR2_DQS_DP<16> DDR2_DQS_DP<17> 
DDR2_DQS_DN<0> DDR2_DQS_DN<1> DDR2_DQS_DN<2> DDR2_DQS_DN<3> DDR2_DQS_DN<4> DDR2_DQS_DN<5> DDR2_DQS_DN<6> DDR2_DQS_DN<7> DDR2_DQS_DN<8> 
DDR2_DQS_DN<9> DDR2_DQS_DN<10> DDR2_DQS_DN<11> DDR2_DQS_DN<12> DDR2_DQS_DN<13> DDR2_DQS_DN<14> DDR2_DQS_DN<15> DDR2_DQS_DN<16> DDR2_DQS_DN<17> 
DDR2_DQ<0> DDR2_DQ<1> DDR2_DQ<2> DDR2_DQ<3> DDR2_DQ<4> DDR2_DQ<5> DDR2_DQ<6> DDR2_DQ<7> DDR2_DQ<8> DDR2_DQ<9> 
DDR2_DQ<10> DDR2_DQ<11> DDR2_DQ<12> DDR2_DQ<13> DDR2_DQ<14> DDR2_DQ<15> DDR2_DQ<16> DDR2_DQ<17> DDR2_DQ<18> DDR2_DQ<19> DDR2_DQ<20> DDR2_DQ<21> DDR2_DQ<22> 
DDR2_DQ<23> DDR2_DQ<24> DDR2_DQ<25> DDR2_DQ<26> DDR2_DQ<27> DDR2_DQ<28> DDR2_DQ<29> DDR2_DQ<30> DDR2_DQ<31> DDR2_DQ<32> DDR2_DQ<33> DDR2_DQ<34> DDR2_DQ<35> 
DDR2_DQ<36> DDR2_DQ<37> DDR2_DQ<38> DDR2_DQ<39> DDR2_DQ<40> DDR2_DQ<41> DDR2_DQ<42> DDR2_DQ<43> DDR2_DQ<44> DDR2_DQ<45> DDR2_DQ<46> DDR2_DQ<47> 
DDR2_DQ<48> DDR2_DQ<49> DDR2_DQ<50> DDR2_DQ<51> DDR2_DQ<52> DDR2_DQ<53> DDR2_DQ<54> DDR2_DQ<55> DDR2_DQ<56> DDR2_DQ<57> DDR2_DQ<58> DDR2_DQ<59> DDR2_DQ<60> 
DDR2_DQ<61> DDR2_DQ<62> DDR2_DQ<63> 
DDR2_CS_N<0> DDR2_CS_N<1> DDR2_CS_N<2> DDR2_CS_N<3> DDR2_CS_N<4> DDR2_CS_N<5> DDR2_CS_N<6> DDR2_CS_N<7> 
DDR2_CLK_DP<0> DDR2_CLK_DP<1> DDR2_CLK_DP<2> DDR2_CLK_DP<3> 
DDR2_CLK_DN<0> DDR2_CLK_DN<1> 
DDR2_CLK_DN<2> DDR2_CLK_DN<3> 
DDR2_CKE<0> DDR2_CKE<1> DDR2_CKE<2> DDR2_CKE<3> 
DDR2_CID<2> 
DDR2_BG<0> DDR2_BG<1> 
DDR2_BA<0> DDR2_BA<1> 
DDR2_ALERT_N DDR2_ACT_N 
CPU SYMBOLS 1-30 ARE PRELIMINARY AND SUBJECT TO CHANGE 
SKYLAKE - SKT1 - 5 OF 21 
SKX_EXT_B 
INA
ILER
RY
P
M
ROOM=CPU1 
BOM_COST=PROC_SOCKET 
WIWYNN CORPORATION 
5/30 



M_K_DQ<63:0> 
DT73 
37 
M_K_ACT_N 
M_K_ALERT_N 
M_K_PAR M_K_C<2> 
M_K_ECC<7:0> 
M_K_CLK_DP<3:0> 
M_K_CLK_DN<3:0> 
M_K_ODT<3:0> 
M_K_CS_N<7:0> 
M_K_CKE<3:0> 
M_K_BG<1:0> 
M_K_BA<1:0> 
M_K_MA<17:0> 
M_K_DQS_DN<17:0> 
M_K_DQS_DP<17:0> 
0
7
6
5
3
4
0
1
2
11
0
0
1
63 
62 
61 
60 
59 
58 
57 
2
56 
55 
54 
53 
52 
51 
50 
49 
48 
3
47 
46 
45 
44 
43 
42 
41 
40 
39 
38 
1
35 
36 
34 
33 
32 
30 
31 
29 
28 
0
27 
25 
26 
24 
23 
22 
21 
20 
19 
18 
17 
16 
15 
14 
13 
12 
11 
10 
9
7
8
6
5
4
3
2
1
0
7
6
5
DP77 
DW60 
ED63 
EE52 
EA54 
ED61 
DW62 
DV47 
EE62 
EF63 
EA62 
EB63 
ED55 
EF55 
DW56 
EF57 
EB55 
EE54 
EA56 
EE56 EF51 
ED49 
ED47 
EB47 
EB51 
EB49 
DV45 
EB45 
CN84 
CN86 
DA86 
DA84 
CL84 
CL86 
CW86 
CW84 
DG84 
DH85 
DV83 
DY83 
DD85 
DE84 
DR84 
DV85 
DM79 
DK81 
DT81 
DR82 
DK79 
DJ80 
DR80 
DN82 
DN76 
DU76 
DP73 
DT77 
DN74 
DU74 
EC40 
ED39 
EA36 
EC36 
DY39 
EA40 
DY37 
ED37 
DN36 
DU36 
DP33 
DT33 
DP37 
DT37 
DN34 
DU34 
DN30 
DU30 
DP27 
DT27 
DP31 
DT31 
DN28 
DU28 
DN24 
DU24 
DY21 
EB21 
DP25 
DT25 
EC22 
DW22 
CU84 
DN84 
DL82 
DV75 
EE38 
DV35 
DV29 
DV23 
DF67 
CR84 
DM85 
DN80 
DP75 
EA38 
DP35 
DM29 
DM23 
DB67 
CV85 
DP85 
DM81 
DT75 
EC38 
DT35 
DT29 
DT23 
DD67 
CP85 
DL84 
DP79 
DM75 
DW38 
DM35 
DP29 
DP23 
CY67 
DA68 
DE68 
DB65 
DD65 
DB69 
DD69 
DA66 
DE66 
EB53 
ED57 
EE58 
EB57 
ED59 
EA58 
EE60 
EA60 
EB59 
EF61 
DW54 
EB61 
DT63 
DW48 
ED51 
DV49 
EA52 
EA46 
EE50 
EE48 
EA50 
EA48 
ED53 
IC 
TBD 
U2D1 
17 
3
16 
15 
12 
13 
14 
11 
10 
9
8
7
4
5
6
4
2
3
2
1
0
17 
16 
13 
1
14 
15 
11 
12 
10 
9
8
7
6
5
0
3
4
0
2
1
17 
16 
15 
14 
13 
3
12 
9
10 
11 
7
8
6
5
4
2
2
3
1
0
3
2
1
0
1
2
3
0
83 84 
83 84 
83 84 
83 84 83 84 
83 84 
83 84 
83 84 
83 84 
83 84 
83 84 
83 84 
83 84 
83 84 
83 84 
83 84 
DESIGN NOTE: 
DO NOT SCALE DRAWING SHEET 
B
AA
B
B
SIZE 
SCALE: 
234
1234
DEPARTMENT CODE 
1
DOCUMENT NUMBER REV 
BI 
BI 
OUT 
OUT 
BI 
BI 
OUT 
OUT 
OUT 
OUT 
OUT 
OUT 
OUT 
IN 
OUT OUT 
60 OF 270 
Wed Feb 08 16:34:45 2017 
DDR3_PAR 
DDR3_ODT<0> DDR3_ODT<1> DDR3_ODT<2> DDR3_ODT<3> 
DDR3_MA<0> 
DDR3_MA<1> DDR3_MA<2> DDR3_MA<3> DDR3_MA<4> DDR3_MA<5> DDR3_MA<6> DDR3_MA<7> DDR3_MA<8> DDR3_MA<9> DDR3_MA<10> DDR3_MA<11> DDR3_MA<12> DDR3_MA<13> 
DDR3_MA<14> DDR3_MA<15> DDR3_MA<16> DDR3_MA<17> 
DDR3_ECC<0> DDR3_ECC<1> DDR3_ECC<2> DDR3_ECC<3> DDR3_ECC<4> 
DDR3_ECC<5> DDR3_ECC<6> DDR3_ECC<7> 
DDR3_DQS_DP<0> DDR3_DQS_DP<1> 
DDR3_DQS_DP<2> DDR3_DQS_DP<3> DDR3_DQS_DP<4> DDR3_DQS_DP<5> DDR3_DQS_DP<6> DDR3_DQS_DP<7> DDR3_DQS_DP<8> DDR3_DQS_DP<9> DDR3_DQS_DP<10> DDR3_DQS_DP<11> DDR3_DQS_DP<12> DDR3_DQS_DP<13> DDR3_DQS_DP<14> 
DDR3_DQS_DP<15> DDR3_DQS_DP<16> DDR3_DQS_DP<17> 
DDR3_DQS_DN<0> DDR3_DQS_DN<1> DDR3_DQS_DN<2> DDR3_DQS_DN<3> DDR3_DQS_DN<4> DDR3_DQS_DN<5> DDR3_DQS_DN<6> DDR3_DQS_DN<7> 
DDR3_DQS_DN<8> DDR3_DQS_DN<9> DDR3_DQS_DN<10> DDR3_DQS_DN<11> DDR3_DQS_DN<12> DDR3_DQS_DN<13> DDR3_DQS_DN<14> DDR3_DQS_DN<15> DDR3_DQS_DN<16> DDR3_DQS_DN<17> 
DDR3_DQ<0> DDR3_DQ<1> DDR3_DQ<2> DDR3_DQ<3> DDR3_DQ<4> DDR3_DQ<5> DDR3_DQ<6> DDR3_DQ<7> DDR3_DQ<8> 
DDR3_DQ<9> DDR3_DQ<10> DDR3_DQ<11> DDR3_DQ<12> DDR3_DQ<13> DDR3_DQ<14> DDR3_DQ<15> DDR3_DQ<16> DDR3_DQ<17> DDR3_DQ<18> DDR3_DQ<19> DDR3_DQ<20> DDR3_DQ<21> 
DDR3_DQ<22> DDR3_DQ<23> DDR3_DQ<24> DDR3_DQ<25> DDR3_DQ<26> DDR3_DQ<27> DDR3_DQ<28> DDR3_DQ<29> DDR3_DQ<30> DDR3_DQ<31> DDR3_DQ<32> DDR3_DQ<33> DDR3_DQ<34> 
DDR3_DQ<35> DDR3_DQ<36> DDR3_DQ<37> DDR3_DQ<38> DDR3_DQ<39> DDR3_DQ<40> DDR3_DQ<41> DDR3_DQ<42> DDR3_DQ<43> DDR3_DQ<44> DDR3_DQ<45> DDR3_DQ<46> DDR3_DQ<47> 
DDR3_DQ<48> DDR3_DQ<49> DDR3_DQ<50> DDR3_DQ<51> DDR3_DQ<52> DDR3_DQ<53> DDR3_DQ<54> DDR3_DQ<55> DDR3_DQ<56> DDR3_DQ<57> DDR3_DQ<58> DDR3_DQ<59> DDR3_DQ<60> 
DDR3_DQ<61> DDR3_DQ<62> DDR3_DQ<63> 
DDR3_CS_N<0> DDR3_CS_N<1> DDR3_CS_N<2> DDR3_CS_N<3> DDR3_CS_N<4> DDR3_CS_N<5> DDR3_CS_N<6> 
DDR3_CS_N<7> 
DDR3_CLK_DP<0> DDR3_CLK_DP<1> DDR3_CLK_DP<2> DDR3_CLK_DP<3> 
DDR3_CLK_DN<0> DDR3_CLK_DN<1> 
DDR3_CLK_DN<2> DDR3_CLK_DN<3> 
DDR3_CKE<0> DDR3_CKE<1> DDR3_CKE<2> DDR3_CKE<3> 
DDR3_CID<2> 
DDR3_BG<0> DDR3_BG<1> 
DDR3_BA<0> DDR3_BA<1> 
DDR3_ALERT_N DDR3_ACT_N 
CPU SYMBOLS 1-30 ARE PRELIMINARY AND SUBJECT TO CHANGE 
SKYLAKE - SKT1 - 6 OF 21 
SKX_EXT_B 
INA
ILER
RY
P
M
ROOM=CPU1 
BOM_COST=PROC_SOCKET 
WIWYNN CORPORATION 
6/30 



M_L_DQ<63:0> 
ED71 
37 
M_L_ACT_N 
M_L_ALERT_N 
M_L_PAR M_L_C<2> 
M_L_ECC<7:0> 
M_L_CLK_DP<3:0> 
M_L_CLK_DN<3:0> 
M_L_ODT<3:0> 
M_L_CS_N<7:0> 
M_L_CKE<3:0> 
M_L_BG<1:0> 
M_L_BA<1:0> 
M_L_MA<17:0> 
M_L_DQS_DN<17:0> 
M_L_DQS_DP<17:0> 
0
7
6
5
3
4
0
1
2
11
0
0
1
63 
62 
61 
60 
59 
58 
57 
2
56 
55 
54 
53 
52 
51 
50 
49 
48 
3
47 
46 
45 
44 
43 
42 
41 
40 
39 
38 
1
35 
36 
34 
33 
32 
30 
31 
29 
28 
0
27 
25 
26 
24 
23 
22 
21 
20 
19 
18 
17 
16 
15 
14 
13 
12 
11 
10 
9
7
8
6
5
4
3
2
1
0
7
6
5
EA74 
DR62 
DT61 
DM53 
DV55 
DJ62 
DM61 
DT47 
DM63 
DN64 
DL64 
DR64 
DM55 
DR54 
DM57 
DT57 
DN54 
DT53 
DN56 
DR56 DV51 
DN50 
DR46 
DK47 
DW50 
DM49 
DT45 
DN46 
CM79 
CK81 
CT81 
CR82 
CK79 
CJ80 
CR80 
CN82 
DB79 
CY81 
DE80 
DF81 
CY79 
CW80 
DC82 
DE82 
DW80 
EC80 
DY77 
EB77 
DY81 
EB81 
DW78 
EC78 
ED75 
EE74 
EB71 
EB75 
EA72 
EE72 
DU42 
DW42 
DP39 
DT39 
DL42 
DN42 
DN40 
DU40 
EC34 
ED33 
EA30 
EC30 
DY33 
EA34 
DY31 
ED31 
EC28 
ED27 
EA24 
EC24 
DY27 
EA28 
DY25 
ED25 
DF27 
DK27 
DD25 
DJ24 
DG28 
DJ28 
DF25 
DK25 
CL82 
DA82 
ED79 
EF73 
DV41 
EE32 
EE26 
DL26 
EB67 
CN80 
DC80 
DY79 
EB73 
DP41 
EA32 
EA26 
DG26 
DV67 
CM81 
DB81 
EB79 
ED73 
DT41 
EC32 
EC26 
DJ26 
DY67 
CP79 
DD79 
DV79 
DY73 
DM41 
DW32 
DW26 
DE26 
DT67 
DY69 
EA68 
DV65 
DY65 
DU68 
DV69 
DU66 
EA66 
DW52 
DW58 
DV57 
DR58 
DT59 
DN58 
DM59 
DK61 
DJ60 
DV59 
DT55 
DR60 
DN60 
DT51 
DM51 
DR52 
DN52 
DR48 
DR50 
DN48 
DT49 
DM47 
DV53 
IC 
TBD 
U2D1 
17 
3
16 
15 
12 
13 
14 
11 
10 
9
8
7
4
5
6
4
2
3
2
1
0
17 
16 
13 
1
14 
15 
11 
12 
10 
9
8
7
6
5
0
3
4
0
2
1
17 
16 
15 
14 
13 
3
12 
9
10 
11 
7
8
6
5
4
2
2
3
1
0
3
2
1
0
1
2
3
0
85 86 
85 86 
85 86 
85 86 85 86 
85 86 
85 86 
85 86 
85 86 
85 86 
85 86 
85 86 
85 86 
85 86 
85 86 
85 86 
DESIGN NOTE: 
DO NOT SCALE DRAWING SHEET 
B
AA
B
B
SIZE 
SCALE: 
234
1234
DEPARTMENT CODE 
1
DOCUMENT NUMBER REV 
BI 
BI 
OUT 
OUT 
BI 
BI 
OUT 
OUT 
OUT 
OUT 
OUT 
OUT 
OUT 
IN 
OUT OUT 
61 OF 270 
Wed Feb 08 16:34:45 2017 
DDR4_PAR 
DDR4_ODT<0> DDR4_ODT<1> DDR4_ODT<2> DDR4_ODT<3> 
DDR4_MA<0> 
DDR4_MA<1> DDR4_MA<2> DDR4_MA<3> DDR4_MA<4> DDR4_MA<5> DDR4_MA<6> DDR4_MA<7> DDR4_MA<8> DDR4_MA<9> DDR4_MA<10> DDR4_MA<11> DDR4_MA<12> DDR4_MA<13> 
DDR4_MA<14> DDR4_MA<15> DDR4_MA<16> DDR4_MA<17> 
DDR4_ECC<0> DDR4_ECC<1> DDR4_ECC<2> DDR4_ECC<3> DDR4_ECC<4> 
DDR4_ECC<5> DDR4_ECC<6> DDR4_ECC<7> 
DDR4_DQS_DP<0> DDR4_DQS_DP<1> 
DDR4_DQS_DP<2> DDR4_DQS_DP<3> DDR4_DQS_DP<4> DDR4_DQS_DP<5> DDR4_DQS_DP<6> DDR4_DQS_DP<7> DDR4_DQS_DP<8> DDR4_DQS_DP<9> DDR4_DQS_DP<10> DDR4_DQS_DP<11> DDR4_DQS_DP<12> DDR4_DQS_DP<13> DDR4_DQS_DP<14> 
DDR4_DQS_DP<15> DDR4_DQS_DP<16> DDR4_DQS_DP<17> 
DDR4_DQS_DN<0> DDR4_DQS_DN<1> DDR4_DQS_DN<2> DDR4_DQS_DN<3> DDR4_DQS_DN<4> DDR4_DQS_DN<5> DDR4_DQS_DN<6> DDR4_DQS_DN<7> 
DDR4_DQS_DN<8> DDR4_DQS_DN<9> DDR4_DQS_DN<10> DDR4_DQS_DN<11> DDR4_DQS_DN<12> DDR4_DQS_DN<13> DDR4_DQS_DN<14> DDR4_DQS_DN<15> DDR4_DQS_DN<16> DDR4_DQS_DN<17> 
DDR4_DQ<0> DDR4_DQ<1> DDR4_DQ<2> DDR4_DQ<3> DDR4_DQ<4> DDR4_DQ<5> DDR4_DQ<6> DDR4_DQ<7> DDR4_DQ<8> 
DDR4_DQ<9> DDR4_DQ<10> DDR4_DQ<11> DDR4_DQ<12> DDR4_DQ<13> DDR4_DQ<14> DDR4_DQ<15> DDR4_DQ<16> DDR4_DQ<17> DDR4_DQ<18> DDR4_DQ<19> DDR4_DQ<20> DDR4_DQ<21> 
DDR4_DQ<22> DDR4_DQ<23> DDR4_DQ<24> DDR4_DQ<25> DDR4_DQ<26> DDR4_DQ<27> DDR4_DQ<28> DDR4_DQ<29> DDR4_DQ<30> DDR4_DQ<31> DDR4_DQ<32> DDR4_DQ<33> DDR4_DQ<34> 
DDR4_DQ<35> DDR4_DQ<36> DDR4_DQ<37> DDR4_DQ<38> DDR4_DQ<39> DDR4_DQ<40> DDR4_DQ<41> DDR4_DQ<42> DDR4_DQ<43> DDR4_DQ<44> DDR4_DQ<45> DDR4_DQ<46> DDR4_DQ<47> 
DDR4_DQ<48> DDR4_DQ<49> DDR4_DQ<50> DDR4_DQ<51> DDR4_DQ<52> DDR4_DQ<53> DDR4_DQ<54> DDR4_DQ<55> DDR4_DQ<56> DDR4_DQ<57> DDR4_DQ<58> DDR4_DQ<59> DDR4_DQ<60> 
DDR4_DQ<61> DDR4_DQ<62> DDR4_DQ<63> 
DDR4_CS_N<0> DDR4_CS_N<1> DDR4_CS_N<2> DDR4_CS_N<3> DDR4_CS_N<4> DDR4_CS_N<5> DDR4_CS_N<6> 
DDR4_CS_N<7> 
DDR4_CLK_DP<0> DDR4_CLK_DP<1> DDR4_CLK_DP<2> DDR4_CLK_DP<3> 
DDR4_CLK_DN<0> DDR4_CLK_DN<1> 
DDR4_CLK_DN<2> DDR4_CLK_DN<3> 
DDR4_CKE<0> DDR4_CKE<1> DDR4_CKE<2> DDR4_CKE<3> 
DDR4_CID<2> 
DDR4_BG<0> DDR4_BG<1> 
DDR4_BA<0> DDR4_BA<1> 
DDR4_ALERT_N DDR4_ACT_N 
CPU SYMBOLS 1-30 ARE PRELIMINARY AND SUBJECT TO CHANGE 
SKYLAKE - SKT1 - 7 OF 21 
SKX_EXT_B 
INA
ILER
RY
P
M
ROOM=CPU1 
BOM_COST=PROC_SOCKET 
WIWYNN CORPORATION 
7/30 



M_M_DQ<63:0> 
CP67 
48 
M_M_C<2> M_M_PAR 
M_M_ACT_N 
M_M_ALERT_N 
M_M_BA<1:0> 
M_M_BG<1:0> 
M_M_CKE<3:0> 
M_M_CS_N<7:0> 
M_M_ODT<3:0> 
M_M_CLK_DN<3:0> 
M_M_CLK_DP<3:0> 
M_M_ECC<7:0> 
M_M_MA<17:0> 
M_M_DQS_DN<17:0> 
M_M_DQS_DP<17:0> 
0
7
6
5
3
4
0
1
2
11
0
0
1
63 
62 
61 
60 
59 
58 
57 
2
56 
55 
54 
53 
52 
51 
50 
49 
3
47 
46 
45 
44 
43 
42 
41 
40 
39 
38 
1
37 
35 
36 
34 
33 
32 
30 
31 
29 
28 
0
27 
25 
26 
24 
23 
22 
21 
20 
19 
18 
17 
16 
15 
14 
13 
12 
11 
10 
9
7
8
6
5
4
3
2
1
0
7
6
5
DB29 
U2D1 
TBD 
IC 
DK53 
DF47 
DK49 
DG48 
DG50 
DE46 
DG52 
DC54 
DJ50 
DD53 
DG60 
DA60 
DD55 
DA58 
DD59 
DC60 
DK59 
DF59 
DJ58 
DG58 
DD57 
DC58 
DF53 
CM69 
CH69 
CL72 
CJ72 
CL68 
CJ68 
CM71 
CH71 
CG70 
CV29 
CV35 
DC40 
CM65 
DH69 
DG74 
CU74 
CL70 
DB35 
DJ32 
DJ40 
CT65 
DK71 
CR76 
CJ70 
CY29 
CY35 
DE40 
CP65 
DJ70 
DF75 
CT75 
CN70 
DD29 
DD35 
DL32 
DG40 
DL72 
CP77 
DC28 
CW28 
DB31 
CY31 
DB27 
CY27 
DC30 
CW30 
DC34 
CW34 
DB37 
CY37 
DB33 
CY33 
DC36 
CW36 
DK31 
DF31 
DJ34 
DG34 
DJ30 
DG30 
DK33 
DF33 
DH39 
DD39 
DE42 
DA42 
DG38 
DE38 
DG42 
DD41 
CU64 
CN64 
CT63 
CP63 
CU66 
CN66 
DM71 
DK69 
DG72 
DF71 
DN70 
DM69 
DJ72 
DG70 
DH77 
DF77 
DB75 
DC74 
DJ76 
DH75 
DC76 
DE74 
CT77 
CV75 
CM75 
CW76 
DK45 
DM45 
DJ48 
DF51 
DG46 
DJ46 
DF49 
DK51 DG56 
DJ56 
DG54 
DJ54 
DF57 
DK57 
DF55 
DK55 
DF63 
DK63 
DD63 
DG62 
DF45 
DF61 
DA62 
DC56 
DJ52 
DD61 
DC62 
CT67 
DE32 
DE76 
DG32 
DD77 
CV65 
CN74 
CV77 
CN76 
CR74 
17 
3
16 
15 
12 
13 
14 
11 
10 
9
8
7
4
5
6
4
2
3
2
1
0
17 
16 
13 
1
14 
15 
11 
12 
10 
9
8
7
6
5
0
3
4
0
2
1
17 
16 
15 
14 
13 
3
12 
9
10 
11 
7
8
6
5
4
2
2
3
1
0
3
2
1
0
1
2
3
0
87 88 
87 88 87 88 
87 88 
87 88 
87 88 
87 88 
87 88 
87 88 
87 88 
87 88 
87 88 
87 88 
87 88 
87 88 
87 88 
DESIGN NOTE: 
DO NOT SCALE DRAWING SHEET 
B
AA
B
B
SIZE 
SCALE: 
234
1234
DEPARTMENT CODE 
1
DOCUMENT NUMBER REV 
BI 
BI 
OUT 
OUT 
BI 
BI 
OUT 
OUT 
OUT 
OUT 
OUT 
OUT 
IN 
OUT 
OUT OUT 
62 OF 270 
Wed Feb 08 16:34:46 2017 
DDR5_PAR 
DDR5_ODT<0> DDR5_ODT<1> DDR5_ODT<2> DDR5_ODT<3> 
DDR5_MA<0> DDR5_MA<1> 
DDR5_MA<2> DDR5_MA<3> DDR5_MA<4> DDR5_MA<5> DDR5_MA<6> DDR5_MA<7> DDR5_MA<8> DDR5_MA<9> DDR5_MA<10> DDR5_MA<11> DDR5_MA<12> DDR5_MA<13> DDR5_MA<14> 
DDR5_MA<15> DDR5_MA<16> DDR5_MA<17> 
DDR5_ECC<0> DDR5_ECC<1> DDR5_ECC<2> DDR5_ECC<3> DDR5_ECC<4> DDR5_ECC<5> 
DDR5_ECC<6> DDR5_ECC<7> 
DDR5_DQS_DP<0> DDR5_DQS_DP<1> 
DDR5_DQS_DP<2> DDR5_DQS_DP<3> DDR5_DQS_DP<4> DDR5_DQS_DP<5> DDR5_DQS_DP<6> DDR5_DQS_DP<7> DDR5_DQS_DP<8> DDR5_DQS_DP<9> DDR5_DQS_DP<10> DDR5_DQS_DP<11> DDR5_DQS_DP<12> DDR5_DQS_DP<13> DDR5_DQS_DP<14> 
DDR5_DQS_DP<15> DDR5_DQS_DP<16> DDR5_DQS_DP<17> 
DDR5_DQS_DN<0> DDR5_DQS_DN<1> DDR5_DQS_DN<2> DDR5_DQS_DN<3> DDR5_DQS_DN<4> DDR5_DQS_DN<5> DDR5_DQS_DN<6> DDR5_DQS_DN<7> DDR5_DQS_DN<8> 
DDR5_DQS_DN<9> DDR5_DQS_DN<10> DDR5_DQS_DN<11> DDR5_DQS_DN<12> DDR5_DQS_DN<13> DDR5_DQS_DN<14> DDR5_DQS_DN<15> DDR5_DQS_DN<16> DDR5_DQS_DN<17> 
DDR5_DQ<0> DDR5_DQ<1> DDR5_DQ<2> DDR5_DQ<3> DDR5_DQ<4> DDR5_DQ<5> DDR5_DQ<6> DDR5_DQ<7> DDR5_DQ<8> DDR5_DQ<9> 
DDR5_DQ<10> DDR5_DQ<11> DDR5_DQ<12> DDR5_DQ<13> DDR5_DQ<14> DDR5_DQ<15> DDR5_DQ<16> DDR5_DQ<17> DDR5_DQ<18> DDR5_DQ<19> DDR5_DQ<20> DDR5_DQ<21> DDR5_DQ<22> 
DDR5_DQ<23> DDR5_DQ<24> DDR5_DQ<25> DDR5_DQ<26> DDR5_DQ<27> DDR5_DQ<28> DDR5_DQ<29> DDR5_DQ<30> DDR5_DQ<31> DDR5_DQ<32> DDR5_DQ<33> DDR5_DQ<34> DDR5_DQ<35> 
DDR5_DQ<36> DDR5_DQ<37> DDR5_DQ<38> DDR5_DQ<39> DDR5_DQ<40> DDR5_DQ<41> DDR5_DQ<42> DDR5_DQ<43> DDR5_DQ<44> DDR5_DQ<45> DDR5_DQ<46> DDR5_DQ<47> 
DDR5_DQ<48> DDR5_DQ<49> DDR5_DQ<50> DDR5_DQ<51> DDR5_DQ<52> DDR5_DQ<53> DDR5_DQ<54> DDR5_DQ<55> DDR5_DQ<56> DDR5_DQ<57> DDR5_DQ<58> DDR5_DQ<59> DDR5_DQ<60> 
DDR5_DQ<61> DDR5_DQ<62> DDR5_DQ<63> 
DDR5_CS_N<0> DDR5_CS_N<1> DDR5_CS_N<2> DDR5_CS_N<3> DDR5_CS_N<4> DDR5_CS_N<5> DDR5_CS_N<6> DDR5_CS_N<7> 
DDR5_CLK_DP<0> DDR5_CLK_DP<1> DDR5_CLK_DP<2> DDR5_CLK_DP<3> 
DDR5_CLK_DN<0> DDR5_CLK_DN<1> 
DDR5_CLK_DN<2> DDR5_CLK_DN<3> 
DDR5_CKE<0> DDR5_CKE<1> DDR5_CKE<2> DDR5_CKE<3> 
DDR5_CID<2> 
DDR5_BG<0> DDR5_BG<1> 
DDR5_BA<0> DDR5_BA<1> 
DDR5_ALERT_N DDR5_ACT_N 
CPU SYMBOLS 1-30 ARE PRELIMINARY AND SUBJECT TO CHANGE 
SKYLAKE - SKT1 - 8 OF 21 
SKX_EXT_B 
INA
ILER
RY
P
M
ROOM=CPU1 
BOM_COST=PROC_SOCKET 
WIWYNN CORPORATION 
8/30 



BG16 
TP_CPU1_DMI_RX_DP0 
TP_CPU1_DMI_TX_DN0 
TP_CPU1_DMI_TX_DN1 
TP_CPU1_DMI_TX_DN2 
TP_CPU1_DMI_TX_DN3 
TP_CPU1_DMI_TX_DP0 
TP_CPU1_DMI_TX_DP1 
TP_CPU1_DMI_TX_DP2 
TP_CPU1_DMI_TX_DP3 
CLK_100M_CPU1_PE_REFCLK_DN 
CLK_100M_CPU1_PE_REFCLK_DP 
TP_CD_HFI1_CPU1_RESET_N 
TP_CD_HFI1_CPU1_MODPRST_N 
TP_CD_HFI1_CPU1_LED_N 
TP_CD_HFI1_CPU1_INT_N 
TP_CD_HFI1_CPU1_I2CLK 
TP_CD_HFI1_CPU1_I2CDAT 
RST_CD_CPU1_POR_N 
JTAG_MCP_CPU1_TDO 
TP_CPU1_RSVD_190 
TP_CPU1_RSVD_189 
TP_CPU1_RSVD_186 
TP_CPU1_RSVD_184 
TP_CPU1_RSVD_173 
TP_CPU1_RSVD_172 
TP_FM_CPU1_CD_HFI0_MODPRST_N 
TP_RST_CPU1_CD_HFI0_N 
TP_LED_CPU1_CD_HFI0_N 
TP_SMB_CPU1_CD_HFI0_I2CCLK 
TP_SMB_CPU1_CD_HFI0_I2CDAT 
TP_CPU1_DMI_RX_DP2 
TP_CPU1_DMI_RX_DP3 
TP_CPU1_DMI_RX_DN2 
TP_CPU1_DMI_RX_DN1 
CLK_156M_OSC_CPU1_HFI_DN 
CLK_156M_OSC_CPU1_HFI_DP 
TP_CPU1_RSVD_181 
TP_CPU1_RSVD_178 
TP_CPU1_RSVD_182 
TP_CPU1_RSVD_176 
TP_CPU1_RSVD_174 
TP_CPU1_RSVD_175 
TP_CPU1_RSVD_177 
TP_CPU1_RSVD_179 
TP_CPU1_RSVD_180 
TP_CPU1_RSVD_183 
JTAG_MCP_TRST_N 
JTAG_MCP_TMS 
JTAG_MCP_CPU1_TDI 
JTAG_MCP_TCK 
TP_IRQ_CPU1_CD_HFI0_N 
TP_CPU1_DMI_RX_DN0 
TP_CPU1_DMI_RX_DN3 
TP_CPU1_DMI_RX_DP1 
PVCCMCP_CPU1 
BN22 
BP23 
BP19 
BK21 
BR20 
BN24 
BJ22 
BH23 
BM21 
BM23 
BT19 
BK23 
BE16 BU24 
BW24 
CF25 
CB23 
BY21 
CC22 
CE24 
CD23 
CK9 
CM11 
CR12 
CT11 
CL10 
CN10 
CP11 
CV11 
CG4 
CJ4 
CN4 
CP5 
CH5 
CL4 
CM3 
CR4 
BA76 
BA66 BA64 
BA22 
BA18 
BA16 
BA14 
AY77 
AY75 
AY67 
AY65 
AW76 
AW64 
AV77 
AT23 
AT13 
AR62 
AR26 
AR22 
AR20 
IC 
TBD 
U2D1 
AT25 
103 
103 
190 
192 
113 
104 
104 
113 29 
113 29 
113 
113 29 
DESIGN NOTE: 
DO NOT SCALE DRAWING SHEET 
B
AA
B
B
SIZE 
SCALE: 
234
1234
DEPARTMENT CODE 
1
DOCUMENT NUMBER REV 
IN 
OUT IN 
IN 
IN 
IN 
IN 
IN 
IN 
IN 
63 OF 270 
Wed Feb 08 16:34:46 2017 
RSVD<172> RSVD<173> RSVD<174> RSVD<175> RSVD<176> RSVD<177> RSVD<178> RSVD<179> RSVD<180> RSVD<181> 
RSVD<182> RSVD<183> 
RSVD<184> RSVD<186> RSVD<187> RSVD<188> RSVD<189> RSVD<190> RSVD<191> 
RSVD<192> RSVD<193> 
DMI_TX_DP<0> 
DMI_TX_DP<1> DMI_TX_DP<2> DMI_TX_DP<3> 
DMI_TX_DN<0> DMI_TX_DN<1> DMI_TX_DN<2> DMI_TX_DN<3> 
DMI_RX_DP<0> 
DMI_RX_DP<1> DMI_RX_DP<2> DMI_RX_DP<3> 
DMI_RX_DN<0> DMI_RX_DN<1> DMI_RX_DN<2> DMI_RX_DN<3> 
CD_TRST_N CD_TMS CD_TDO 
CD_TDI CD_TCLK CD_POR_N 
CD_PE_REFCLK_DP CD_PE_REFCLK_DN CD_HFI_REFCLK_DP 
CD_HFI_REFCLK_DN 
CD_HFI1_RESET_N CD_HFI1_MODPRST_N CD_HFI1_LED_N 
CD_HFI1_INT_N 
CD_HFI1_I2CDAT CD_HFI1_I2CCLK 
CD_HFI0_RESET_N 
CD_HFI0_MODPRST_N 
CD_HFI0_LED_N 
CD_HFI0_INT_N 
CD_HFI0_I2CDAT CD_HFI0_I2CCLK 
CPU SYMBOLS 1-30 ARE PRELIMINARY AND SUBJECT TO CHANGE 
SKYLAKE - SKT1 - 9 OF 21 
SKX_EXT_B 
INA
ILER
RY
P
M
ROOM=CPU1 
BOM_COST=PROC_SOCKET 
WIWYNN CORPORATION 
9/30 



15 
TP_P3E_CPU1_PE1_MP_RXP<7:0> 
TP_P3E_CPU1_PE1_RSR3_RXP<15:8> 
TP_P3E_CPU1_PE1_MP_RXN<7:0> 
TP_P3E_CPU1_PE1_RSR3_RXN<15:8> 
TP_P3E_CPU1_PE1_MP_TXP<7:0> 
TP_P3E_CPU1_PE1_RSR3_TXP<15:8> 
TP_P3E_CPU1_PE1_MP_TXN<7:0> 
TP_P3E_CPU1_PE1_RSR3_TXN<15:8> 
1
0
CW8 
DA8 
DC8 
DC10 
DE10 
DH9 
DK9 
DM9 
DM11 
DP11 
DT11 
DT13 
DV13 
DW14 
DY15 
DU16 
CU8 
CY7 
DB9 
DA10 
DD9 
DF9 
DJ8 
DL10 
DK11 
DN10 
DR12 
DP13 
DU12 
DY13 
DV15 
DT15 
DA2 
DC2 
DE2 
DE4 
DG4 
DK3 
DM3 
DN4 
DT5 
DV3 
DW4 
DU6 
DV7 
DY7 
EA8 
ED9 
CW2 
DB1 
DD3 
DC4 
DF3 
DH3 
DL2 
DP3 
DR4 
DU2 
DU4 
DV5 
DT7 
DW6 
EB7 
EC8 
IC 
TBD 
U2D1 
15 
15 
14 
13 
12 
14 
13 
12 
3
11 
11 
10 
9
8
9
10 
8
7
7
2
6
5
4
6
5
4
2
3
2
3
1
0
1
1
0
14 
13 
12 
11 
15 
0
12 
13 
14 
10 
9
8
7
11 
10 
9
8
6
4
5
3
2
6
7
5
4
DESIGN NOTE: 
DO NOT SCALE DRAWING SHEET 
B
AA
B
B
SIZE 
SCALE: 
234
1234
DEPARTMENT CODE 
1
DOCUMENT NUMBER REV 
64 OF 270 
Wed Feb 08 16:34:46 2017 
PE1_TX_DP<0> PE1_TX_DP<1> 
PE1_TX_DP<2> PE1_TX_DP<3> 
PE1_TX_DP<4> PE1_TX_DP<5> PE1_TX_DP<6> PE1_TX_DP<7> 
PE1_TX_DP<8> PE1_TX_DP<9> PE1_TX_DP<10> PE1_TX_DP<11> 
PE1_TX_DP<12> PE1_TX_DP<13> PE1_TX_DP<14> PE1_TX_DP<15> 
PE1_TX_DN<0> PE1_TX_DN<1> PE1_TX_DN<2> PE1_TX_DN<3> 
PE1_TX_DN<4> PE1_TX_DN<5> PE1_TX_DN<6> PE1_TX_DN<7> 
PE1_TX_DN<8> PE1_TX_DN<9> PE1_TX_DN<10> PE1_TX_DN<11> 
PE1_TX_DN<12> PE1_TX_DN<13> PE1_TX_DN<14> 
PE1_TX_DN<15> 
PE1_RX_DP<0> PE1_RX_DP<1> 
PE1_RX_DP<2> PE1_RX_DP<3> 
PE1_RX_DP<4> PE1_RX_DP<5> PE1_RX_DP<6> PE1_RX_DP<7> 
PE1_RX_DP<8> PE1_RX_DP<9> PE1_RX_DP<10> PE1_RX_DP<11> 
PE1_RX_DP<12> PE1_RX_DP<13> PE1_RX_DP<14> PE1_RX_DP<15> 
PE1_RX_DN<0> PE1_RX_DN<1> PE1_RX_DN<2> PE1_RX_DN<3> 
PE1_RX_DN<4> PE1_RX_DN<5> PE1_RX_DN<6> PE1_RX_DN<7> 
PE1_RX_DN<8> PE1_RX_DN<9> PE1_RX_DN<10> PE1_RX_DN<11> 
PE1_RX_DN<12> PE1_RX_DN<13> PE1_RX_DN<14> 
PE1_RX_DN<15> 
CPU SYMBOLS 1-30 ARE PRELIMINARY AND SUBJECT TO CHANGE 
SKYLAKE - SKT1 - 10 OF 21 
SKX_EXT_B 
INA
ILER
RY
P
M
BOM_COST=PROC_SOCKET 
ROOM=CPU1 
WIWYNN CORPORATION 
10/30 



TP_P3E_CPU1_PE2_RSR_RXP<15:0> 
TP_P3E_CPU1_PE2_RSR_RXN<15:0> TP_P3E_CPU1_PE2_RSR_TXP<15:0> 
TP_P3E_CPU1_PE2_RSR_TXN<15:0> 
0
1
2
CT9 
CP9 
CP7 
CM7 
CK7 
CG8 
CE6 
CE8 
BY9 
BY7 
BV7 
BT7 
BR8 
BN8 
BL8 
BK9 
CR8 
CM9 
CN8 
CL6 
CH7 
CF7 
CD7 
CC8 
BV9 
BW8 
BU6 
BP7 
BP9 
BM7 
BJ8 
BJ10 
CY3 
CV3 
CT1 
CT3 
CM1 
CL2 
CG2 
CF3 
CC2 
CB3 
CA4 
BW4 
BU4 
BP5 
BL4 
BM5 
CW4 
CU2 
CR2 
CP3 
CK1 
CK3 
CE2 
CE4 
CD3 
BY3 
BY5 
BV3 
BR4 
BN4 
BM3 
BK5 
IC 
TBD 
U2D1 
14 
15 
13 
12 
11 
12 
13 
14 
3
15 
11 
9
10 
8
7
8
9
10 
7
0
6
5
4
3
4
5
6
3
2
0
1 1
1
0
2
15 
13 
14 
12 
11 
15 
2
13 
14 
12 
10 
9
8
7
11 
9
10 
8
6
5
4
3
7
5
6
4
DESIGN NOTE: 
DO NOT SCALE DRAWING SHEET 
B
AA
B
B
SIZE 
SCALE: 
234
1234
DEPARTMENT CODE 
1
DOCUMENT NUMBER REV 
65 OF 270 
Wed Feb 08 16:34:46 2017 
PE2_TX_DP<0> PE2_TX_DP<1> 
PE2_TX_DP<2> PE2_TX_DP<3> 
PE2_TX_DP<4> PE2_TX_DP<5> PE2_TX_DP<6> PE2_TX_DP<7> 
PE2_TX_DP<8> PE2_TX_DP<9> PE2_TX_DP<10> PE2_TX_DP<11> 
PE2_TX_DP<12> PE2_TX_DP<13> PE2_TX_DP<14> PE2_TX_DP<15> 
PE2_TX_DN<0> PE2_TX_DN<1> PE2_TX_DN<2> PE2_TX_DN<3> 
PE2_TX_DN<4> PE2_TX_DN<5> PE2_TX_DN<6> PE2_TX_DN<7> 
PE2_TX_DN<8> PE2_TX_DN<9> PE2_TX_DN<10> PE2_TX_DN<11> 
PE2_TX_DN<12> PE2_TX_DN<13> PE2_TX_DN<14> 
PE2_TX_DN<15> 
PE2_RX_DP<0> PE2_RX_DP<1> 
PE2_RX_DP<2> PE2_RX_DP<3> 
PE2_RX_DP<4> PE2_RX_DP<5> PE2_RX_DP<6> PE2_RX_DP<7> 
PE2_RX_DP<8> PE2_RX_DP<9> PE2_RX_DP<10> PE2_RX_DP<11> 
PE2_RX_DP<12> PE2_RX_DP<13> PE2_RX_DP<14> PE2_RX_DP<15> 
PE2_RX_DN<0> PE2_RX_DN<1> PE2_RX_DN<2> PE2_RX_DN<3> 
PE2_RX_DN<4> PE2_RX_DN<5> PE2_RX_DN<6> PE2_RX_DN<7> 
PE2_RX_DN<8> PE2_RX_DN<9> PE2_RX_DN<10> PE2_RX_DN<11> 
PE2_RX_DN<12> PE2_RX_DN<13> PE2_RX_DN<14> 
PE2_RX_DN<15> 
CPU SYMBOLS 1-30 ARE PRELIMINARY AND SUBJECT TO CHANGE 
SKYLAKE - SKT1 - 11 OF 21 
SKX_EXT_B 
INA
ILER
RY
P
M
BOM_COST=PROC_SOCKET 
ROOM=CPU1 
WIWYNN CORPORATION 
11/30 



P3E_CPU1_PE3_MP_RXP<15:8> 
15 
14 
P3E_CPU1_PE3_MP_RXP<7:0> 
P3E_CPU1_PE3_MP_RXN<7:0> 
P3E_CPU1_PE3_MP_RXN<15:8> 
P3E_CPU1_PE3_MP_TXP<7:0> 
P3E_CPU1_PE3_MP_TXP<15:8> 
P3E_CPU1_PE3_MP_TXN<7:0> 
P3E_CPU1_PE3_MP_TXN<15:8> 
EA18 
DW18 
DW16 
DT19 
DR16 
DR14 
DN14 
DL14 
DL12 
DJ12 
DG12 
DG10 
DD13 
DB11 
CY11 
CV9 
DY17 
DU18 
DV17 
DR18 
DN16 
DP15 
DM13 
DJ14 
DK13 
DH11 
DE12 
DF11 
DC12 
DA12 
CW10 
CU10 
EE14 
EE12 
EC12 
DY11 
EB9 
DW10 
DU8 
DR8 
DM7 
DP5 
DL6 
DJ4 
DJ6 
DD5 
DB5 
CY5 
EC14 
ED13 
EB11 
EA10 
DY9 
DV9 
DT9 
DP7 
DN6 
DM5 
DK5 
DH5 
DG6 
DC6 
DA4 
CV5 
IC 
TBD 
U2D1 
15 
14 
12 
13 
15 
14 
13 
12 
10 
11 
8
9
11 
9
10 
8
7
6
4
5
7
6
5
4
3
1
2
0
3
2
0
1
14 
13 
12 
15 
12 
13 
11 
10 
9
8
11 
10 
8
9
7
6
5
4
7
6
4
5
3
2
1
0
3
2
1
0
181 
181 
182 
182 
181 
182 
181 
182 
DESIGN NOTE: 
DO NOT SCALE DRAWING SHEET 
B
AA
B
B
SIZE 
SCALE: 
234
1234
DEPARTMENT CODE 
1
DOCUMENT NUMBER REV 
IN 
IN 
OUT 
OUT 
OUT 
OUT 
IN 
IN 
66 OF 270 
Wed Feb 08 16:34:47 2017 
PE3_TX_DP<0> PE3_TX_DP<1> 
PE3_TX_DP<2> PE3_TX_DP<3> 
PE3_TX_DP<4> PE3_TX_DP<5> PE3_TX_DP<6> PE3_TX_DP<7> 
PE3_TX_DP<8> PE3_TX_DP<9> PE3_TX_DP<10> PE3_TX_DP<11> 
PE3_TX_DP<12> PE3_TX_DP<13> PE3_TX_DP<14> PE3_TX_DP<15> 
PE3_TX_DN<0> PE3_TX_DN<1> PE3_TX_DN<2> PE3_TX_DN<3> 
PE3_TX_DN<4> PE3_TX_DN<5> PE3_TX_DN<6> PE3_TX_DN<7> 
PE3_TX_DN<8> PE3_TX_DN<9> PE3_TX_DN<10> PE3_TX_DN<11> 
PE3_TX_DN<12> PE3_TX_DN<13> PE3_TX_DN<14> 
PE3_TX_DN<15> 
PE3_RX_DP<0> PE3_RX_DP<1> 
PE3_RX_DP<2> PE3_RX_DP<3> 
PE3_RX_DP<4> PE3_RX_DP<5> PE3_RX_DP<6> PE3_RX_DP<7> 
PE3_RX_DP<8> PE3_RX_DP<9> PE3_RX_DP<10> PE3_RX_DP<11> 
PE3_RX_DP<12> PE3_RX_DP<13> PE3_RX_DP<14> PE3_RX_DP<15> 
PE3_RX_DN<0> PE3_RX_DN<1> PE3_RX_DN<2> PE3_RX_DN<3> 
PE3_RX_DN<4> PE3_RX_DN<5> PE3_RX_DN<6> PE3_RX_DN<7> 
PE3_RX_DN<8> PE3_RX_DN<9> PE3_RX_DN<10> PE3_RX_DN<11> 
PE3_RX_DN<12> PE3_RX_DN<13> PE3_RX_DN<14> 
PE3_RX_DN<15> 
DE NOTE: 
POLARITY SWAPED P3E_CPU1_PE3_MP_RX*<12> 
CPU SYMBOLS 1-30 ARE PRELIMINARY AND SUBJECT TO CHANGE 
SKYLAKE - SKT1 - 12 OF 21 
SKX_EXT_B 
INA
ILER
RY
P
M
ROOM=CPU1 
BOM_COST=PROC_SOCKET 
WIWYNN CORPORATION 
12/30 



UPI_CPU0_CPU1_P0P0_DP<19..0> 
UPI_CPU0_CPU1_P0P0_DN<19..0> UPI_CPU1_CPU0_P0P0_DN<19..0> 
UPI_CPU1_CPU0_P0P0_DP<19..0> 
14 
15 
11 
15 
14 
13 
9
8
7
6
5
0
19 
18 18 
17 
14 
10 
9
7
3
5
3
2
18 
17 
4
14 
9
10 
7
2
5
3
2
19 
18 
17 
16 
12 
10 
4
3
2
17 
16 
12 
10 
AC10 
AA8 
AB7 
AD5 
AE6 
AG8 
AJ6 
AL6 
AK7 
AM9 
AP7 
AR8 
AU10 
BA8 
BC6 
BD7 
AW8 
AY9 
BD9 
BB11 
AB9 
AC8 
AA6 
AC6 
AG6 
AF7 
AH7 
AK5 
AM7 
AL8 
AN8 
AU8 
AT9 
AY7 
BB7 
BF7 
AV9 
BB9 
BC10 
BA10 
N2 
P1 
V3 
Y1 
AB3 
AC2 
AG4 
AE2 
AH3 
AL2 
AM3 
AN4 
AT1 
AT3 
AU4 
AV5 
BA4 
BB3 
BF3 
BG4 
M1 
T1 
Y3 
W2 
AA2 
AD1 
AF3 
AG2 
AJ2 
AK1 
AK3 
AP3 
AP1 
AR2 
AR4 
AW4 
AY3 
BC2 
BD3 
BH3 
IC 
TBD 
U2D1 
1
0
1
4
6
8
11 
12 
13 
15 
16 
19 
0
1
4
6
8
11 
12 
13 
15 
16 
19 
13 
0
1
5
6
7
8
9
11 
33 
33 
33 
33 
DESIGN NOTE: 
DO NOT SCALE DRAWING SHEET 
B
AA
B
B
SIZE 
SCALE: 
234
1234
DEPARTMENT CODE 
1
DOCUMENT NUMBER REV 
OUT 
OUT 
IN 
IN 
67 OF 270 
Wed Feb 08 16:34:47 2017 
UPI0_TX_DP<0> UPI0_TX_DP<1> UPI0_TX_DP<2> UPI0_TX_DP<3> UPI0_TX_DP<4> UPI0_TX_DP<5> UPI0_TX_DP<6> UPI0_TX_DP<7> UPI0_TX_DP<8> UPI0_TX_DP<9> UPI0_TX_DP<10> UPI0_TX_DP<11> UPI0_TX_DP<12> 
UPI0_TX_DP<13> UPI0_TX_DP<14> UPI0_TX_DP<15> UPI0_TX_DP<16> UPI0_TX_DP<17> UPI0_TX_DP<18> UPI0_TX_DP<19> 
UPI0_TX_DN<0> UPI0_TX_DN<1> UPI0_TX_DN<2> UPI0_TX_DN<3> UPI0_TX_DN<4> UPI0_TX_DN<5> UPI0_TX_DN<6> UPI0_TX_DN<7> 
UPI0_TX_DN<8> UPI0_TX_DN<9> UPI0_TX_DN<10> UPI0_TX_DN<11> UPI0_TX_DN<12> UPI0_TX_DN<13> UPI0_TX_DN<14> UPI0_TX_DN<15> UPI0_TX_DN<16> UPI0_TX_DN<17> UPI0_TX_DN<18> UPI0_TX_DN<19> 
UPI0_RX_DP<0> UPI0_RX_DP<1> UPI0_RX_DP<2> UPI0_RX_DP<3> UPI0_RX_DP<4> UPI0_RX_DP<5> UPI0_RX_DP<6> UPI0_RX_DP<7> UPI0_RX_DP<8> UPI0_RX_DP<9> UPI0_RX_DP<10> UPI0_RX_DP<11> UPI0_RX_DP<12> 
UPI0_RX_DP<13> UPI0_RX_DP<14> UPI0_RX_DP<15> UPI0_RX_DP<16> UPI0_RX_DP<17> UPI0_RX_DP<18> UPI0_RX_DP<19> 
UPI0_RX_DN<0> UPI0_RX_DN<1> UPI0_RX_DN<2> UPI0_RX_DN<3> UPI0_RX_DN<4> UPI0_RX_DN<5> UPI0_RX_DN<6> UPI0_RX_DN<7> 
UPI0_RX_DN<8> UPI0_RX_DN<9> UPI0_RX_DN<10> UPI0_RX_DN<11> UPI0_RX_DN<12> UPI0_RX_DN<13> UPI0_RX_DN<14> UPI0_RX_DN<15> UPI0_RX_DN<16> UPI0_RX_DN<17> UPI0_RX_DN<18> UPI0_RX_DN<19> 
CPU SYMBOLS 1-30 ARE PRELIMINARY AND SUBJECT TO CHANGE 
SKYLAKE - SKT1 - 13 OF 21 
SKX_EXT_B 
INA
ILER
RY
P
M
BOM_COST=PROC_SOCKET 
ROOM=CPU1 
WIWYNN CORPORATION 
13/30 



UPI_CPU0_CPU1_P1P1_DN<19..0> 
T11 
UPI_CPU0_CPU1_P1P1_DP<19..0> 
UPI_CPU1_CPU0_P1P1_DN<19..0> 
UPI_CPU1_CPU0_P1P1_DP<19..0> 
0
19 
16 
15 
13 
12 
11 
8
6
4
1
0
1
0
17 
16 
12 
10 
4
3
2
16 
17 
2
12 
10 
3
4
2
3
19 
18 
17 
16 
15 
14 
13 
12 
11 
10 
9
8
7
6
5
4
3
2
18 
17 
14 
10 
9
T5 
P7 
V7 
T9 
P9 
R10 
U12 
L12 
N14 
R12 
R16 
P17 
U16 
W18 
R20 
U18 
P21 
V19 
Y21 
AB19 
R6 
T7 
U8 
R8 
N10 
U10 
N12 
M13 
P13 
T15 
N16 
W16 
V17 
P19 
T19 
T21 
Y19 
W20 
AA20 
M3 
L4 
K5 
J6 
G6 
H7 
K9 
D9 
F11 
G10 
E12 
G14 
D15 
F15 
H17 
K19 
G18 
J20 
F21 
H21 
P3 
K3 
M5 
H5 
F7 
K7 
J8 
F9 
E10 
H9 
G12 
F13 
E14 
H15 
G16 
L18 
J18 
H19 
G20 
K21 
IC 
TBD 
U2D1 
19 
18 
15 
14 
13 
11 
9
8
7
6
5
1
0
19 
18 
7
15 
14 
13 
11 
9
8
7
6
5
1
5
34 
34 
34 
34 
DESIGN NOTE: 
DO NOT SCALE DRAWING SHEET 
B
AA
B
B
SIZE 
SCALE: 
234
1234
DEPARTMENT CODE 
1
DOCUMENT NUMBER REV 
OUT 
OUT 
IN 
IN 
68 OF 270 
Wed Feb 08 16:34:47 2017 
UPI1_TX_DP<0> UPI1_TX_DP<1> UPI1_TX_DP<2> UPI1_TX_DP<3> UPI1_TX_DP<4> UPI1_TX_DP<5> UPI1_TX_DP<6> UPI1_TX_DP<7> UPI1_TX_DP<8> UPI1_TX_DP<9> UPI1_TX_DP<10> UPI1_TX_DP<11> 
UPI1_TX_DP<12> UPI1_TX_DP<13> UPI1_TX_DP<14> UPI1_TX_DP<15> UPI1_TX_DP<16> UPI1_TX_DP<17> UPI1_TX_DP<18> UPI1_TX_DP<19> 
UPI1_TX_DN<0> UPI1_TX_DN<1> UPI1_TX_DN<2> UPI1_TX_DN<3> UPI1_TX_DN<4> UPI1_TX_DN<5> UPI1_TX_DN<6> 
UPI1_TX_DN<7> UPI1_TX_DN<8> UPI1_TX_DN<9> UPI1_TX_DN<10> UPI1_TX_DN<11> UPI1_TX_DN<12> UPI1_TX_DN<13> UPI1_TX_DN<14> UPI1_TX_DN<15> UPI1_TX_DN<16> UPI1_TX_DN<17> UPI1_TX_DN<18> UPI1_TX_DN<19> 
UPI1_RX_DP<0> UPI1_RX_DP<1> UPI1_RX_DP<2> UPI1_RX_DP<3> UPI1_RX_DP<4> UPI1_RX_DP<5> UPI1_RX_DP<6> UPI1_RX_DP<7> UPI1_RX_DP<8> UPI1_RX_DP<9> UPI1_RX_DP<10> UPI1_RX_DP<11> 
UPI1_RX_DP<12> UPI1_RX_DP<13> UPI1_RX_DP<14> UPI1_RX_DP<15> UPI1_RX_DP<16> UPI1_RX_DP<17> UPI1_RX_DP<18> UPI1_RX_DP<19> 
UPI1_RX_DN<0> UPI1_RX_DN<1> UPI1_RX_DN<2> UPI1_RX_DN<3> UPI1_RX_DN<4> UPI1_RX_DN<5> UPI1_RX_DN<6> 
UPI1_RX_DN<7> UPI1_RX_DN<8> UPI1_RX_DN<9> UPI1_RX_DN<10> UPI1_RX_DN<11> UPI1_RX_DN<12> UPI1_RX_DN<13> UPI1_RX_DN<14> UPI1_RX_DN<15> UPI1_RX_DN<16> UPI1_RX_DN<17> UPI1_RX_DN<18> UPI1_RX_DN<19> 
CPU SYMBOLS 1-30 ARE PRELIMINARY AND SUBJECT TO CHANGE 
SKYLAKE - SKT1 - 14 OF 21 
SKX_EXT_B 
INA
ILER
RY
P
M
BOM_COST=PROC_SOCKET 
ROOM=CPU1 
WIWYNN CORPORATION 
14/30 



DF17 
TP_CPU1_UPI2_RSVD_DE16 
DC20 
TP_CPU1_UPI2_RSVD_DT21 
TP_CPU1_UPI2_RSVD_DM21 
TP_CPU1_UPI2_RSVD_DL20 
TP_CPU1_UPI2_RSVD_DG20 
TP_CPU1_UPI2_RSVD_DH19 
TP_CPU1_UPI2_RSVD_DK17 
TP_CPU1_UPI2_RSVD_DG18 
TP_CPU1_UPI2_RSVD_DD17 
TP_CPU1_UPI2_RSVD_DF15 
TP_CPU1_UPI2_RSVD_DC16 
TP_CPU1_UPI2_RSVD_DA16 
TP_CPU1_UPI2_RSVD_CW14 
TP_CPU1_UPI2_RSVD_CU14 
TP_CPU1_UPI2_RSVD_DP21 
TP_CPU1_UPI2_RSVD_DN20 
TP_CPU1_UPI2_RSVD_DK19 
TP_CPU1_UPI2_RSVD_DJ20 
TP_CPU1_UPI2_RSVD_DJ18 
TP_CPU1_UPI2_RSVD_DH17 
TP_CPU1_UPI2_RSVD_DF17 
TP_CPU1_UPI2_RSVD_DD15 
TP_CPU1_UPI2_RSVD_DB15 
TP_CPU1_UPI2_RSVD_CW16 
TP_CPU1_UPI2_RSVD_CV13 
TP_CPU1_UPI2_RSVD_CK13 
TP_CPU1_UPI2_RSVD_CH13 
TP_CPU1_UPI2_RSVD_CG12 
TP_CPU1_UPI2_RSVD_CF11 
TP_CPU1_UPI2_RSVD_CD11 
TP_CPU1_UPI2_RSVD_CB11 
TP_CPU1_UPI2_RSVD_CA12 
TP_CPU1_UPI2_RSVD_CM13 
TP_CPU1_UPI2_RSVD_CJ14 
TP_CPU1_UPI2_RSVD_CF13 
TP_CPU1_UPI2_RSVD_CH11 
TP_CPU1_UPI2_RSVD_CE12 
TP_CPU1_UPI2_RSVD_CC10 
TP_CPU1_UPI2_RSVD_CC12 
TP_CPU1_UPI2_RSVD_CR14 
DB19 
DF23 
DE22 
DC22 
DB21 
DD19 
DA20 
CW20 
CV19 
CT21 
CR18 
CN20 
CP21 
CL16 
CJ18 
CH17 
CE16 
CD15 
CF17 
CB15 
BY17 
DG22 
DD21 
DA22 
CY19 
CU20 
CW18 
CR20 
CN18 
CP19 
CM21 
CJ16 
CK17 
CG16 
CF15 
CC14 
CD17 
BY15 
CA16 
DT21 
DM21 
DL20 
DG20 
DH19 
DK17 
DG18 
DD17 
DF15 
DC16 
DA16 
CW14 
CU14 
CM13 
CJ14 
CF13 
CH11 
CE12 
CC10 
CC12 
DP21 
DN20 
DK19 
DJ20 
DJ18 
DH17 
DE16 
DD15 
DB15 
CW16 
CV13 
CR14 
CK13 
CH13 
CG12 
CF11 
CD11 
CB11 
CA12 
IC 
TBD 
U2D1 
DESIGN NOTE: 
DO NOT SCALE DRAWING SHEET 
B
AA
B
B
SIZE 
SCALE: 
234
1234
DEPARTMENT CODE 
1
DOCUMENT NUMBER REV 
69 OF 270 
Wed Feb 08 16:34:47 2017 
UPI2_TX_DP<0> UPI2_TX_DP<1> UPI2_TX_DP<2> UPI2_TX_DP<3> UPI2_TX_DP<4> UPI2_TX_DP<5> UPI2_TX_DP<6> UPI2_TX_DP<7> UPI2_TX_DP<8> UPI2_TX_DP<9> UPI2_TX_DP<10> 
UPI2_TX_DP<11> UPI2_TX_DP<12> UPI2_TX_DP<13> UPI2_TX_DP<14> UPI2_TX_DP<15> UPI2_TX_DP<16> UPI2_TX_DP<17> UPI2_TX_DP<18> UPI2_TX_DP<19> 
UPI2_TX_DN<0> UPI2_TX_DN<1> UPI2_TX_DN<2> UPI2_TX_DN<3> UPI2_TX_DN<4> UPI2_TX_DN<5> 
UPI2_TX_DN<6> UPI2_TX_DN<7> UPI2_TX_DN<8> UPI2_TX_DN<9> UPI2_TX_DN<10> UPI2_TX_DN<11> UPI2_TX_DN<12> UPI2_TX_DN<13> UPI2_TX_DN<14> UPI2_TX_DN<15> UPI2_TX_DN<16> UPI2_TX_DN<17> UPI2_TX_DN<18> 
UPI2_TX_DN<19> 
UPI2_RX_DP<0> UPI2_RX_DP<1> UPI2_RX_DP<2> UPI2_RX_DP<3> UPI2_RX_DP<4> UPI2_RX_DP<5> UPI2_RX_DP<6> UPI2_RX_DP<7> UPI2_RX_DP<8> UPI2_RX_DP<9> UPI2_RX_DP<10> 
UPI2_RX_DP<11> UPI2_RX_DP<12> UPI2_RX_DP<13> UPI2_RX_DP<14> UPI2_RX_DP<15> UPI2_RX_DP<16> UPI2_RX_DP<17> UPI2_RX_DP<18> UPI2_RX_DP<19> 
UPI2_RX_DN<0> UPI2_RX_DN<1> UPI2_RX_DN<2> UPI2_RX_DN<3> UPI2_RX_DN<4> UPI2_RX_DN<5> 
UPI2_RX_DN<6> UPI2_RX_DN<7> UPI2_RX_DN<8> UPI2_RX_DN<9> UPI2_RX_DN<10> UPI2_RX_DN<11> UPI2_RX_DN<12> UPI2_RX_DN<13> UPI2_RX_DN<14> UPI2_RX_DN<15> UPI2_RX_DN<16> UPI2_RX_DN<17> UPI2_RX_DN<18> 
UPI2_RX_DN<19> 
CPU SYMBOLS 1-30 ARE PRELIMINARY AND SUBJECT TO CHANGE 
SKYLAKE - SKT1 - 15 OF 21 
SKX_EXT_B 
INA
ILER
RY
P
M
BOM_COST=PROC_SOCKET 
ROOM=CPU1 
WIWYNN CORPORATION 
15/30 



TP_CPU1_RSVD_111 
TP_CPU1_RSVD_108 TP_CPU1_RSVD_91 
TP_CPU1_RSVD_90 
TP_CPU1_RSVD_85 
TP_CPU1_RSVD_82 
TP_CPU1_TEST_10 
TP_CPU1_TEST_6 
TP_CPU1_TEST_7 
TP_CPU1_TEST_8 
TP_CPU1_TEST_9 
TP_CPU1_RSVD_94 
TP_CPU1_RSVD_95 
TP_CPU1_RSVD_97 
TP_CPU1_RSVD_99 
TP_CPU1_RSVD_100 
TP_CPU1_RSVD_101 
TP_CPU1_RSVD_105 
TP_CPU1_RSVD_106 
TP_CPU1_RSVD_113 
TP_CPU1_RSVD_114 
TP_CPU1_RSVD_117 
TP_CPU1_RSVD_119 
TP_CPU1_RSVD_121 
TP_CPU1_RSVD_123 
TP_CPU1_RSVD_124 
TP_CPU1_RSVD_155 
TP_CPU1_RSVD_156 
TP_CPU1_RSVD_157 
TP_CPU1_RSVD_158 
TP_CPU1_RSVD_159 
TP_CPU1_RSVD_160 
TP_CPU1_RSVD_161 
TP_CPU1_RSVD_162 
TP_CPU1_RSVD_163 
TP_CPU1_RSVD_164 
CLK_100M_CPU1_RC_REFCLK1_DN 
TP_CPU1_RSVD_166 
TP_CPU1_RSVD_167 
TP_CPU1_RSVD_168 
TP_CPU1_RSVD_169 
TP_CPU1_RSVD_170 
TP_CPU1_RSVD_171 
TP_CPU1_RSVD_255 
TP_CPU1_RSVD_154 
TP_CPU1_RSVD_151 
TP_CPU1_RSVD_152 
CLK_100M_CPU1_RC_REFCLK1_DP 
TP_CPU1_RSVD_150 
TP_CPU1_RSVD_147 
TP_CPU1_RSVD_146 
TP_CPU1_RSVD_145 
TP_CPU1_RSVD_144 
TP_CPU1_RSVD_148 
TP_CPU1_RSVD_149 
BU20 
BJ20 
BJ18 
BU18 
BP21 
BP17 
BN18 
BM17 
BM19 
BL20 
BL18 
BK17 
BH19 
BJ16 
BD69 
BE18 
BE20 
BE22 
BF21 
BG18 
BG20 
BD25 
BR24 
BD65 
CH23 
CH21 
CG82 
CG78 
CG26 
CG24 
CG20 
CG10 
CF81 
CF79 
CF23 
CF21 
CF19 
CE80 
CE78 
CE22 
CD25 
CD21 
CD19 
CC6 
CC20 
CB5 
CB25 
CB21 
CB19 
CA24 
CA22 
BY25 
BY19 
BW22 
BW20 
BW10 
BV23 
BV21 
BV19 
BU22 
BR22 
BD67 
BD19 
BD17 
BC68 
BC66 
BC64 
BC22 
BC20 
BC18 
BC14 
BB67 
BB65 
BB25 
BB21 
BB17 
BB15 
BB13 
BA82 
BA78 
AY83 
IC 
TBD 
U2D1 
PVCCIOMCP_CPU1 
PVCCMCP_CPU1 
PVCCMCP_CPU1 
PVCCMCP_CPU1 
TBD 
U2D1 
IC 
AW22 
AW20 
AW16 
AU18 
AR16 
CH25 
CH77 
CJ20 
CJ22 
CJ24 
CJ26 
CK19 
CK23 
CK25 
CK77 
CL24 
103 
103 
DESIGN NOTE: 
DESIGN NOTE: 
DO NOT SCALE DRAWING SHEET 
B
AA
B
B
SIZE 
SCALE: 
234
1234
DEPARTMENT CODE 
1
DOCUMENT NUMBER REV 
IN 
IN 
70 OF 270 
Wed Feb 08 16:34:48 2017 
RSVD<92> 
RSVD<93> RSVD<94> RSVD<95> RSVD<96> RSVD<97> RSVD<98> RSVD<99> RSVD<100> RSVD<101> RSVD<102> RSVD<103> RSVD<104> RSVD<105> 
RSVD<106> RSVD<107> RSVD<108> RSVD<109> RSVD<110> RSVD<111> RSVD<112> RSVD<113> RSVD<114> RSVD<115> RSVD<116> RSVD<117> RSVD<118> 
RSVD<119> RSVD<120> RSVD<121> RSVD<122> RSVD<123> RSVD<124> RSVD<125> RSVD<126> 
RSVD<127> RSVD<128> RSVD<129> RSVD<130> RSVD<131> RSVD<132> RSVD<133> RSVD<134> RSVD<135> RSVD<136> RSVD<137> 
RSVD<138> RSVD<139> RSVD<140> RSVD<141> RSVD<142> RSVD<143> RSVD<144> RSVD<145> RSVD<146> RSVD<147> RSVD<148> RSVD<149> RSVD<150> 
RSVD<151> RSVD<152> RSVD<153> RSVD<154> RSVD<155> RSVD<156> RSVD<157> RSVD<158> RSVD<159> RSVD<160> RSVD<161> RSVD<162> RSVD<163> 
RSVD<164> RSVD<165> RSVD<166> RSVD<167> RSVD<168> RSVD<169> RSVD<170> RSVD<171> 
RSVD<255> 
TEST_9 TEST_8 TEST_7 TEST_6 
TEST_10 
RSVD<81> RSVD<82> RSVD<83> RSVD<84> RSVD<85> RSVD<86> RSVD<87> RSVD<88> 
RSVD<89> 
RSVD<90> RSVD<91> 
CPU SYMBOLS 1-30 ARE PRELIMINARY AND SUBJECT TO CHANGE 
MCP CLK IS USED FOR DEBUG ONLY 
SKYLAKE - SKT1 - 16 OF 21 
SKX_EXT_B 
SKX_EXT_B 
INA
ILER
RY
P
M INA
ILER
RY
P
M
BOM_COST=PROC_SOCKET 
ROOM=CPU1 
WIWYNN CORPORATION 
16/30 
17/30 



CL58 
BT73 
AT59 
CR34 
IC 
BG84 
VSENSE_VCCINR2PMAX_CPU1 
VSENSE_PVCCIN_CPU1_SKT_VRTN 
VSENSE_PVCCIN_CPU1_SKT_VSEN 
VSENSE_PMAX_CPU1 
G21796-066 
R3D32 
10.0 1
EMPTY 
0402 
1/16W 
1% 
2
CA60 
CA62 
CA72 
U2D1 
IC 
BN80 
BN82 
BN84 
BP61 CA74 
CA82 
CA80 
CA78 
CA76 
CA84 
CB79 
CB77 
CB75 
CB73 
CB61 
CC84 
CC62 
CC60 
CB83 
CB81 
CE84 
CE60 
CD85 
CD83 
CD61 
CH61 
CG84 
CG60 
CF85 
CF61 
CK61 
CK59 
CJ60 
CH85 
CL60 
CN58 
CN56 
CM59 
CM57 
CP33 
CR54 
CP57 
CP55 
CR56 
CT53 
CT41 
CT39 
CT37 
CT55 
CU52 
CU42 
CU40 
CU38 
CU54 
CY47 
CW50 
CW48 
CW46 
CV51 
AV85 
AW86 
CY49 
AY85 
AD41 
BA86 
BP63 
BP65 
BP67 
BP69 
BP71 
BP79 
BP81 
BP77 
BP73 
BP75 
BP83 
BR60 
BR62 
BR84 
BT61 
BT63 
BT65 
BT67 
BT69 
BT71 
BT75 
BT77 
BT81 
BT79 
BU64 
BU66 
BU62 
BT83 
BU60 
BU68 
BU70 
BU72 
BU76 
BU74 
BU78 
BU84 
BV61 
BU80 
BU82 
BV63 
BV65 
BV67 
BV71 
BV69 
BV73 
BV79 
BV81 
BV75 
BV77 
BV83 
BW60 
BW62 
BW64 
BW66 
BW68 
BW70 
BW84 
BY61 
BY73 
BY75 
TBD 
BY77 
BY79 
BY81 
BY83 
BG60 
BG62 
BG64 
U2D1 
AF43 
AG38 
AG40 
AG42 BG66 
BG68 
BG70 
BH61 
BH63 
BH65 
BH67 
BH69 
BH71 
BH73 
BH75 
BH77 
BH79 
BH81 
BH83 
BJ60 
BJ62 
BJ64 
BJ66 
BJ68 
BJ70 
BJ72 
BJ74 
BJ76 
BJ78 
BJ80 
BJ82 
BJ84 
BK61 
BK63 
BK65 
BK67 
BK69 
BK71 
BK73 
BK75 
BK77 
BK79 
BK81 
BK83 
BL60 
BL62 
BL84 
BM61 
BM63 
BM65 
BM67 
BM69 
BM71 
BM73 
BM75 
BM77 
BM79 
BM81 
BM83 
BN60 
BN62 
BN64 
BN66 
BN68 
BN70 
BN72 
BN74 
BN76 
BN78 
AH37 
AH39 
AH41 
AJ36 
AK35 
AK45 
AK47 
AK49 
AK51 
AK53 
AL34 
AL46 
AL48 
AL50 
AL52 
AL54 
AM33 
AM53 
AM55 
AN32 
AN54 
AN56 
AP55 
AP57 
AR56 
AR58 
AT57 
AU58 
AU60 
AV59 
AV61 
AW60 
AY61 
BA60 
BB61 
BB85 
BC60 
BC62 
BC84 
BD61 
TBD 
BD73 
BD75 
BD77 
BD79 
BD81 
BD83 
BD85 
BE60 
BE62 
BE72 
BE74 
BE76 
BE78 
BE80 
BE82 
BE84 
BF61 
BF73 
BF75 
BF77 
BF79 
BF81 
BF83 
BF85 
RT8P1 
G22026-050 
100.0K 
1% 
0603 
CHIP 
1/10W 
1
2
G85996-031 
0.1% 
249 
R3D27 
1
1/16W 
CHIP 
0402 
2
209 
209 
DESIGN NOTE: 
DO NOT SCALE DRAWING SHEET 
B
AA
B
B
SIZE 
SCALE: 
234
1234
DEPARTMENT CODE 
1
DOCUMENT NUMBER REV 
PVCCIO_CPU1 
PVCCIN_CPU1 
PVCCIN_CPU1 PVCCIN_CPU1 
OUT 
OUT 
PVCCIN_CPU1 PVCCIN_CPU1 
71 OF 270 
Wed Feb 08 16:34:48 2017 
VSS_VCCIN_SENSE 
VSENSEPMAX 
VCCIN_SENSE 
VCCINPMAX<0> 
VCCINPMAX<1> 
VCCIN<0> VCCIN<1> 
VCCIN<2> VCCIN<3> VCCIN<4> VCCIN<5> VCCIN<6> VCCIN<7> VCCIN<8> VCCIN<9> VCCIN<10> VCCIN<11> VCCIN<12> VCCIN<13> VCCIN<14> 
VCCIN<15> VCCIN<16> VCCIN<17> VCCIN<18> VCCIN<19> VCCIN<20> VCCIN<21> VCCIN<22> VCCIN<23> VCCIN<24> VCCIN<25> VCCIN<26> VCCIN<27> 
VCCIN<28> VCCIN<29> VCCIN<30> VCCIN<31> VCCIN<32> VCCIN<33> VCCIN<34> VCCIN<35> VCCIN<36> VCCIN<37> VCCIN<38> VCCIN<39> VCCIN<40> 
VCCIN<41> VCCIN<42> VCCIN<43> VCCIN<44> VCCIN<45> VCCIN<46> VCCIN<47> VCCIN<48> VCCIN<49> VCCIN<50> VCCIN<51> VCCIN<52> VCCIN<53> 
VCCIN<54> VCCIN<55> VCCIN<56> VCCIN<57> VCCIN<58> VCCIN<59> VCCIN<60> 
VCCIN<61> VCCIN<62> VCCIN<63> VCCIN<64> VCCIN<65> VCCIN<66> VCCIN<67> VCCIN<68> VCCIN<69> VCCIN<70> 
VCCIN<71> VCCIN<72> VCCIN<73> VCCIN<74> VCCIN<75> VCCIN<76> VCCIN<77> VCCIN<78> VCCIN<79> VCCIN<80> VCCIN<81> VCCIN<82> VCCIN<83> 
VCCIN<84> VCCIN<85> VCCIN<86> VCCIN<87> VCCIN<88> VCCIN<89> VCCIN<90> VCCIN<91> VCCIN<92> VCCIN<93> VCCIN<94> VCCIN<95> VCCIN<96> 
VCCIN<97> VCCIN<98> VCCIN<99> VCCIN<100> VCCIN<101> VCCIN<102> VCCIN<103> VCCIN<104> VCCIN<105> VCCIN<106> VCCIN<107> VCCIN<108> VCCIN<109> 
VCCIN<110> VCCIN<111> VCCIN<112> VCCIN<113> VCCIN<114> VCCIN<115> VCCIN<116> VCCIN<117> VCCIN<118> VCCIN<119> VCCIN<120> VCCIN<121> VCCIN<122> 
VCCIN<123> VCCIN<124> VCCIN<125> VCCIN<126> VCCIN<127> VCCIN<128> VCCIN<129> 
VCCIN<130> VCCIN<131> VCCIN<132> VCCIN<133> VCCIN<134> VCCIN<135> VCCIN<136> VCCIN<137> VCCIN<138> VCCIN<139> 
VCCIN<140> VCCIN<141> VCCIN<142> VCCIN<143> VCCIN<144> VCCIN<145> VCCIN<146> VCCIN<147> VCCIN<148> VCCIN<149> VCCIN<150> VCCIN<151> VCCIN<152> 
VCCIN<153> VCCIN<154> VCCIN<155> VCCIN<156> VCCIN<157> VCCIN<158> VCCIN<159> VCCIN<160> VCCIN<161> VCCIN<162> VCCIN<163> VCCIN<164> VCCIN<165> 
VCCIN<166> VCCIN<167> VCCIN<168> VCCIN<169> VCCIN<170> VCCIN<171> VCCIN<172> VCCIN<173> VCCIN<174> VCCIN<175> VCCIN<176> VCCIN<177> VCCIN<178> 
VCCIN<179> VCCIN<180> VCCIN<181> VCCIN<182> VCCIN<183> VCCIN<184> VCCIN<185> VCCIN<186> VCCIN<187> VCCIN<188> VCCIN<189> VCCIN<190> VCCIN<191> 
VCCIN<192> VCCIN<193> VCCIN<194> VCCIN<195> VCCIN<196> VCCIN<197> VCCIN<198> 
VCCIN<199> VCCIN<200> VCCIN<201> VCCIN<202> VCCIN<203> VCCIN<204> VCCIN<205> VCCIN<206> VCCIN<207> VCCIN<208> 
VCCIN<209> VCCIN<210> VCCIN<211> VCCIN<212> VCCIN<213> VCCIN<214> VCCIN<215> VCCIN<216> VCCIN<217> VCCIN<218> VCCIN<219> VCCIN<220> VCCIN<221> 
VCCIN<222> VCCIN<223> VCCIN<224> VCCIN<225> VCCIN<226> VCCIN<227> VCCIN<228> VCCIN<229> VCCIN<230> VCCIN<231> VCCIN<232> VCCIN<233> VCCIN<234> 
VCCIN<235> VCCIN<236> VCCIN<237> VCCIN<238> VCCIN<239> VCCIN<240> VCCIN<241> VCCIN<242> VCCIN<243> VCCIN<244> VCCIN<245> VCCIN<246> VCCIN<247> 
VCCIN<248> VCCIN<249> VCCIN<250> VCCIN<251> VCCIN<252> VCCIN<253> VCCIN<254> VCCIN<255> VCCIN<256> VCCIN<257> VCCIN<258> VCCIN<259> VCCIN<260> 
VCCIN<261> VCCIN<262> VCCIN<263> VCCIN<264> VCCIN<265> VCCIN<266> VCCIN<267> 
CPU SYMBOLS 1-30 ARE PRELIMINARY AND SUBJECT TO CHANGE 
SKYLAKE - SKT1 - 17 OF 21 
SKX_EXT_B SKX_EXT_B 
INA
ILER
RY
P
M
ROOM=CPU1 
BOM_COST=PROC_SOCKET 
WIWYNN CORPORATION 
19/30 18/30 



DB61 
H13 
P1V8_MCP_CPU1 
BL14 
BK15 
BK13 
BJ14 
BJ12 
BH13 
BG14 
BG12 
BF13 
BF11 
BE14 
BE12 
BD13 
BT27 
BU26 
BV27 
BY27 
BV15 
BV13 
BV11 
BU14 
BU12 
BT15 
BT13 
BT11 
BR14 
BR12 
BP15 
BP13 
BP11 
BN14 
BN12 
BM11 
B11 
A12 
A10 
A8 
CY55 
CM15 
CL12 
CK5 
CV7 
CH9 
D7 
CE18 
CD9 
CB17 
CB13 
BP25 
BJ24 
BF23 
DA14 
BB5 
BA24 
AY11 
AW6 
AT11 
DD7 
AN10 
DF13 
AH9 
AC4 
AC20 
AA10 
W6 
W4 
DF21 
U14 
T3 
P5 
M21 
M11 
DG8 
DH7 
L16 
L14 
J10 
DJ16 
DM17 
DN8 
DP19 
DR10 
DR2 
DU20 
EA12 
EB15 
J2 
K15 
M7 
M9 
N18 
W10 
BC26 
BB27 
BA26 
AY27 
AW26 
AV27 
CF27 
CD27 
CC26 
CJ28 
CH27 
BM27 
BL26 
BK27 
BK25 
BJ26 
BH27 
BH25 
BG26 
BF27 
AE36 
AD37 
AC36 
AF35 
AD35 
AE34 
AG34 
AM29 
AL28 
AR28 
CJ66 
CJ64 
CH75 
CH65 
CG74 
CG66 
CG64 
CF75 
CF73 
CF67 
CF65 
CE74 
CE72 
CE68 
CE66 
CE64 
CD71 
CD69 
CD67 
CD65 
CC70 
CC68 
CC66 
CB69 
CB67 
CB65 
IC 
TBD 
U2D1 
B49 
B53 
B59 
E46 
E48 
E50 
E52 
E54 
E56 
E58 
E60 
E62 
E64 
L46 
L48 
L50 
L52 
L54 
L56 
L58 
L60 
L62 
N64 
U46 
U48 
U50 
U52 
U54 
U56 
U58 
U60 
U62 
W64 
Y45 
Y47 
Y49 
Y51 
Y53 
Y55 
Y57 
Y59 
Y61 
Y63 
AD45 
AF55 
AF57 
AF59 
AF61 
AF63 
D45 
C46 
B47 
EF59 
EF53 
EF49 
EC62 
EC60 
EC58 
EC56 
EC54 
EC52 
EC50 
EC48 
EC46 
DU64 
DU62 
DU60 
DU58 
DU56 
DU54 
DU52 
DU50 
DU48 
DU46 
DL62 
DL60 
DL58 
DL56 
DL54 
DL52 
DL50 
DL48 
DL46 
DJ64 
DH63 
DH61 
DH59 
DH57 
DH55 
DH53 
DH51 
DH49 
DH47 
DH45 
DD45 
DB63 
DB59 
DB57 
DB55 
DB53 
EF45 
EE44 
IC 
TBD 
U2D1 
PVCCIOMCP_CPU1 
PVCCMCP_CPU1 
1
2 X6S 
4V 
0603LF 
20% 
10UF 
E15431-001 
C3D3 
DESIGN NOTE: 
DO NOT SCALE DRAWING SHEET 
B
AA
B
B
SIZE 
SCALE: 
234
1234
DEPARTMENT CODE 
1
DOCUMENT NUMBER REV 
P3V3_STBY 
PVPP_GHJ 
PVSA_CPU1 
PVCCIO_CPU1 
PVCCIO_CPU1 
PVDDQ_KLM PVDDQ_GHJ 
72 OF 270 
Wed Feb 08 16:34:48 2017 
VCCSA<0> VCCSA<1> VCCSA<2> VCCSA<3> VCCSA<4> VCCSA<5> VCCSA<6> VCCSA<7> VCCSA<8> VCCSA<9> VCCSA<10> VCCSA<11> 
VCCSA<12> VCCSA<13> VCCSA<14> VCCSA<15> VCCSA<16> VCCSA<17> VCCSA<18> VCCSA<19> VCCSA<20> VCCSA<21> VCCSA<22> VCCSA<23> VCCSA<24> 
VCCSA<25> 
VCCIO<20> VCCIO<21> VCCIO<22> VCCIO<23> 
VCCIO<24> VCCIO<25> VCCIO<26> VCCIO<27> VCCIO<28> VCCIO<29> 
VCCIO<30> VCCIO<31> VCCIO<32> VCCIO<33> VCCIO<34> VCCIO<35> VCCIO<36> VCCIO<37> VCCIO<38> 
VCCIO<39> VCCIO<40> VCCIO<41> VCCIO<42> VCCIO<43> VCCIO<44> VCCIO<45> VCCIO<46> VCCIO<47> VCCIO<48> VCCIO<49> VCCIO<50> VCCIO<51> 
VCCIO<52> VCCIO<53> VCCIO<54> VCCIO<55> VCCIO<56> VCCIO<57> VCCIO<58> VCCIO<59> VCCIO<60> VCCIO<61> VCCIO<62> VCCIO<63> VCCIO<64> 
VCCIO<65> VCCIO<66> VCCIO<67> VCCIO<68> VCCIO<69> VCCIO<70> VCCIO<71> VCCIO<72> VCCIO<73> VCCIO<74> VCCIO<75> VCCIO<76> VCCIO<77> 
VCCIO<78> VCCIO<79> VCCIO<80> VCCIO<81> VCCIO<82> VCCIO<83> VCCIO<84> VCCIO<85> VCCIO<86> VCCIO<87> VCCIO<88> VCCIO<89> VCCIO<90> 
VCCIO<91> VCCIO<92> VCCIO<93> VCCIO<94> VCCIO<95> VCCIO<96> VCCIO<97> VCCIO<98> VCCIO<99> VCCIO<100> VCCIO<101> VCCIO<102> VCCIO<103> 
VCCIO<104> 
VCC33 
CD_VPP<0> CD_VPP<1> CD_VPP<2> CD_VPP<3> 
CD_VCC_CORE<0> CD_VCC_CORE<1> CD_VCC_CORE<2> CD_VCC_CORE<3> CD_VCC_CORE<4> CD_VCC_CORE<5> CD_VCC_CORE<6> CD_VCC_CORE<7> CD_VCC_CORE<8> CD_VCC_CORE<9> CD_VCC_CORE<10> CD_VCC_CORE<11> CD_VCC_CORE<12> 
CD_VCCP<0> CD_VCCP<1> CD_VCCP<2> CD_VCCP<3> CD_VCCP<4> 
CD_VCCP<5> CD_VCCP<6> CD_VCCP<7> CD_VCCP<8> CD_VCCP<9> 
CD_VCCP<10> CD_VCCP<11> CD_VCCP<12> CD_VCCP<13> CD_VCCP<14> CD_VCCP<15> 
CD_VCCIN<0> CD_VCCIN<1> 
CD_VCCIN<2> CD_VCCIN<3> 
VCCD345<0> 
VCCD345<1> 
VCCD345<2> VCCD345<3> VCCD345<4> VCCD345<5> VCCD345<6> VCCD345<7> VCCD345<8> VCCD345<9> VCCD345<10> VCCD345<11> VCCD345<12> 
VCCD345<13> VCCD345<14> VCCD345<15> VCCD345<16> VCCD345<17> VCCD345<18> VCCD345<19> VCCD345<20> VCCD345<21> VCCD345<22> VCCD345<23> VCCD345<24> VCCD345<25> 
VCCD345<26> VCCD345<27> VCCD345<28> VCCD345<29> VCCD345<30> VCCD345<31> VCCD345<32> VCCD345<33> VCCD345<34> VCCD345<35> VCCD345<36> VCCD345<37> VCCD345<38> 
VCCD345<39> VCCD345<40> VCCD345<41> VCCD345<42> VCCD345<43> VCCD345<44> VCCD345<45> VCCD345<46> VCCD345<47> VCCD345<48> VCCD345<49> VCCD345<50> 
VCCD012<0> VCCD012<1> 
VCCD012<2> 
VCCD012<3> VCCD012<4> VCCD012<5> VCCD012<6> VCCD012<7> VCCD012<8> VCCD012<9> VCCD012<10> VCCD012<11> VCCD012<12> VCCD012<13> 
VCCD012<14> VCCD012<15> VCCD012<16> VCCD012<17> VCCD012<18> VCCD012<19> VCCD012<20> VCCD012<21> VCCD012<22> VCCD012<23> VCCD012<24> VCCD012<25> VCCD012<26> 
VCCD012<27> VCCD012<28> VCCD012<29> VCCD012<30> VCCD012<31> VCCD012<32> VCCD012<33> VCCD012<34> VCCD012<35> VCCD012<36> VCCD012<37> VCCD012<38> VCCD012<39> 
VCCD012<40> VCCD012<41> VCCD012<42> VCCD012<43> VCCD012<44> VCCD012<45> VCCD012<46> VCCD012<47> VCCD012<48> VCCD012<49> VCCD012<50> VCCD012<51> 
CPU SYMBOLS 1-30 ARE PRELIMINARY AND SUBJECT TO CHANGE 
SKYLAKE - SKT1 - 18 OF 21 
SKX_EXT_B 
SKX_EXT_B 
INA
ILER
RY
P
M
ROOM=CPU1 
BOM_COST=PROC_SOCKET 
WIWYNN CORPORATION 
21/30 
20/30 



TP_CPU1_RSVD_48 
EE10 
TP_CPU1_RSVD_60 
TP_CPU1_RSVD_59 
TP_CPU1_RSVD_57 
TP_CPU1_RSVD_56 
TP_CPU1_RSVD_55 
TP_CPU1_RSVD_54 
TP_CPU1_RSVD_53 
TP_CPU1_RSVD_51 
TP_CPU1_RSVD_50 
TP_CPU1_RSVD_49 
TP_CPU1_RSVD_47 
TP_CPU1_RSVD_46 
TP_CPU1_RSVD_45 
TP_CPU1_RSVD_44 
TP_CPU1_RSVD_42 
TP_CPU1_RSVD_41 
TP_CPU1_RSVD_40 
TP_CPU1_RSVD_39 
TP_CPU1_RSVD_38 
TP_CPU1_RSVD_37 
TP_CPU1_RSVD_36 
TP_CPU1_RSVD_35 
TP_CPU1_RSVD_34 
TP_CPU1_RSVD_33 
TP_CPU1_RSVD_32 
TP_CPU1_RSVD_31 
TP_CPU1_RSVD_30 
TP_CPU1_RSVD_29 
TP_CPU1_RSVD_28 
TP_CPU1_RSVD_27 
TP_CPU1_RSVD_26 
TP_CPU1_RSVD_25 
TP_CPU1_RSVD_24 
TP_CPU1_RSVD_23 
TP_CPU1_RSVD_22 
TP_CPU1_RSVD_21 
TP_CPU1_RSVD_20 
TP_CPU1_RSVD_19 
TP_CPU1_RSVD_18 
TP_CPU1_RSVD_17 
TP_CPU1_RSVD_16 
TP_CPU1_RSVD_15 
TP_CPU1_RSVD_14 
TP_CPU1_RSVD_13 
TP_CPU1_RSVD_12 
TP_CPU1_RSVD_11 
TP_CPU1_RSVD_10 
TP_CPU1_RSVD_9 
TP_CPU1_RSVD_8 
TP_CPU1_RSVD_7 
TP_CPU1_RSVD_6 
TP_CPU1_RSVD_5 
TP_CPU1_RSVD_4 
TP_CPU1_RSVD_3 
TP_CPU1_RSVD_2 
TP_CPU1_RSVD_1 
TP_CPU1_RSVD_0 
VSENSE_PVCCIO_CPU1_SKT_VSEN 
VSENSE_PVCCIOMCP_CPU1_SKT_VRTN 
VSENSE_PVCCIOMCP_CPU1_SKT_VSEN 
VSENSE_PVCCIO_CPU1_SKT_VRTN 
PD_CPU1_MCP01_DMON 
TP_CPU1_RSVD_73 
TP_CPU1_RSVD_72 
TP_CPU1_RSVD_70 
TP_CPU1_RSVD_69 
TP_CPU1_RSVD_67 
TP_CPU1_RSVD_66 
TP_CPU1_RSVD_64 
TP_CPU1_KTI2_DFX_DN 
TP_CPU1_RSVD_61 
TP_CPU1_RSVD_43 
VSENSE_PVCCMCP_CPU1_SKT_VRTN 
VSENSE_PVSA_CPU1_SKT_VSEN 
VSENSE_PVSA_CPU1_SKT_VRTN 
VSENSE_PVCCMCP_CPU1_SKT_VSEN 
TP_CPU1_KTI2_AMONV 
PVCCMCP_CPU1 
AE10 
CM23 
DV11 
U2D1 
TBD 
IC 
CG76 
BF5 
CE76 
BH5 
CN6 
CU12 
CV21 
CU18 
CY17 
DC18 
DE14 
CP13 
CL20 
CG14 
CF5 
DK21 
BE24 
AT7 
AT5 
AM5 
AF5 
CL26 
CM25 
CN22 
CN28 
CP23 
CP31 
CR60 
CT23 
CT5 
CT69 
CU24 
CU6 
CU60 
CV23 
CV69 
CW22 
CW24 
CW60 
CW62 
CY23 
CY25 
CY39 
CY53 
CY57 
CY63 
CY73 
DA24 
DA40 
DA52 
DA54 
DA56 
DC46 
DC52 
DD51 
DG36 
DG64 
DH65 
DJ36 
DJ66 
DK15 
DK37 
DK65 
DK67 
DL66 
DM67 
DN62 
DN66 
DP17 
DP65 
DR44 
DT71 
DU44 
DV61 
DV71 
DW44 
DW46 
DY3 
EA4 
EA44 
EB3 
EB5 
EB85 
EC16 
EC4 
EC44 
EC84 
ED45 
ED5 
ED83 
EE16 
EE46 
EE6 
EE82 
EE84 
EF47 
EF77 
EF81 
EF83 
BT17 
BU16 
BN16 
DL38 
CN24 
BL16 
PVCCMCP_CPU1 
PVCCMCP_CPU1 
214 
193 
193 
214 
97 
193 
210 
210 
193 
DESIGN NOTE: 
DO NOT SCALE DRAWING SHEET 
B
AA
B
B
SIZE 
SCALE: 
234
1234
DEPARTMENT CODE 
1
DOCUMENT NUMBER REV 
OUT 
OUT 
OUT 
OUT 
OUT 
OUT 
OUT 
OUT 
PVCCIO_CPU1 
IN 
73 OF 270 
Wed Feb 08 16:34:48 2017 
VSS_VCCSA_SENSE 
VSS_VCCIO_SENSE 
VCCSA_SENSE 
VCCIO_SENSE 
VCCIO<0> VCCIO<1> VCCIO<2> VCCIO<3> VCCIO<4> VCCIO<5> VCCIO<6> VCCIO<7> 
VCCIO<8> VCCIO<9> 
VCCIO<10> VCCIO<11> VCCIO<12> VCCIO<13> VCCIO<14> VCCIO<15> VCCIO<16> VCCIO<17> 
VCCIO<18> VCCIO<19> 
RSVD<0> RSVD<1> RSVD<2> RSVD<3> RSVD<4> RSVD<5> RSVD<6> RSVD<7> 
RSVD<8> RSVD<9> RSVD<10> RSVD<11> RSVD<12> RSVD<13> RSVD<14> RSVD<15> RSVD<16> RSVD<17> RSVD<18> RSVD<19> RSVD<20> 
RSVD<21> RSVD<22> RSVD<23> RSVD<24> RSVD<25> RSVD<26> RSVD<27> RSVD<28> RSVD<29> RSVD<30> RSVD<31> RSVD<32> RSVD<33> 
RSVD<34> RSVD<35> RSVD<36> RSVD<37> RSVD<38> RSVD<39> RSVD<40> RSVD<41> RSVD<42> RSVD<43> RSVD<44> RSVD<45> RSVD<46> 
RSVD<47> RSVD<48> RSVD<49> RSVD<50> RSVD<51> RSVD<52> RSVD<53> RSVD<54> RSVD<55> RSVD<56> RSVD<57> RSVD<58> 
RSVD<59> RSVD<60> 
RSVD<61> RSVD<62> RSVD<63> 
RSVD<64> RSVD<65> RSVD<66> RSVD<67> RSVD<68> RSVD<69> RSVD<70> RSVD<71> RSVD<72> RSVD<73> RSVD<74> RSVD<75> 
RSVD<76> 
RSVD<77> RSVD<78> RSVD<79> RSVD<80> 
CD_VSS_VCC_CORE_SENSE CD_VCC_CORE_SENSE 
CD_VCCP_SENSE<0> CD_VCCP_SENSE<1> 
CPU SYMBOLS 1-30 ARE PRELIMINARY AND SUBJECT TO CHANGE 
SKYLAKE - SKT1 - 19 OF 21 
SKX_EXT_B 
INA
ILER
RY
P
M
BOM_COST=PROC_SOCKET 
ROOM=CPU1 
WIWYNN CORPORATION 
22/30 



D43 
AC48 
AU62 
AF31 
BA74 
U2 
K69 
C80 
AT63 
BG72 
BG24 
BG22 
BG10 
BG8 
BG6 
BF71 
BF69 
BF67 
BF65 
BF63 
BF25 
BF19 
BF17 
BF15 
BF9 
BE70 
BE68 
BE66 
BE64 
BE26 
BE10 
BE8 
BE6 
BE4 
BD71 
BD63 
BD27 
BD21 
BD15 
BD11 
BD5 
BC82 
BC80 
BC78 
BC76 
BC74 
BC72 
BC70 
BC16 
BC12 
BC8 
BC4 
BB83 
BB81 
BB79 
BB77 
BB75 
BB73 
BB69 
BB63 
BB23 
BB19 
BA84 
BA80 
BA68 
BA62 
BA12 
BA6 
BA2 
AY81 
AY79 
AY63 
AY25 
AY23 
AY21 
AY17 
AY15 
AY5 
AW84 
AW82 
AW78 
AW74 
AW72 
AW70 
AW68 
AW66 
AW62 
AW10 
AW2 
AV83 
AV75 
AV67 
AV65 
AV63 
AV25 
AV23 
AV19 
AV13 
AV11 
AV7 
AV3 
AV1 
AU86 
AU84 
AU80 
AU78 
AU76 
AU74 
AU68 
AU64 
AU28 
AU26 
AU6 
AU2 
AT85 
AT83 
AT77 
AT73 
AT69 
AT61 
AT27 
AT21 
AT17 
AT15 
P63 
AR78 
AR72 
AR60 
AR30 
AR24 
AR10 
AP85 
AP83 
AP81 
AP75 
AP73 
AP69 
AP67 
AP65 
AP63 
AP59 
AP31 
AP19 
AP13 
AP9 
AP5 
AN78 
AN58 
AN28 
AN6 
AN2 
AM83 
AM79 
AM73 
AM69 
AM63 
AM57 
AM31 
AC50 
AM1 
AL86 
AL82 
AL80 
AL78 
AL76 
IC 
TBD 
U2D1 
AL68 
AL64 
AL56 
AL32 
AL30 
AL24 
AL10 
AL4 
AK85 
AK83 
AK81 
AK79 
AK73 
AK67 
AK65 
AK55 
AK33 
AK31 
AK29 
AK25 
AK23 
AK19 
AK13 
AK9 
AJ86 
AJ82 
AJ78 
AJ74 
AJ68 
AJ66 
AJ54 
AJ52 
AJ50 
AJ48 
AJ46 
AJ34 
AJ32 
AJ28 
AJ26 
AJ22 
AJ8 
AH83 
AH77 
AH75 
AH69 
AH65 
AH61 
AH59 
AH53 
AH51 
AH49 
AH47 
AH45 
AH35 
AH33 
AH27 
AH21 
AH5 
AH1 
AG80 
AG78 
AG76 
AG74 
AG70 
AG64 
AG36 
AG18 
AG14 
AG12 
AF85 
AF83 
AF77 
AF73 
AF41 
AF39 
AF37 
AF33 
AF29 
AF27 
AF25 
AF23 
AF21 
AF9 
AC52 
AF1 
AE78 
AE70 
AE68 
AE66 
AE64 
AE42 
AE40 
AE38 
AE16 
AC54 
AE8 
AE4 
AD85 
AD83 
AD81 
AD75 
AD73 
AD71 
AD43 
AD39 
AD33 
AD27 
AD21 
AD19 
AD15 
AD13 
AD11 
AD9 
AD7 
AD3 
AC86 
AC84 
AC78 
AC72 
AC70 
AC64 
AC40 
AC38 
AC34 
AC32 
AC28 
AC26 
AC22 
AC18 
AB85 
AB83 
AB79 
AB73 
AB69 
AB65 
AB41 
AB37 
AB35 
AB31 
AB29 
AB25 
AB23 
AB21 
AB11 
AB5 
AB1 
AA82 
AA80 
AA78 
AA76 
AA68 
AA66 
AA64 
AA42 
AA36 
AA30 
AA24 
AA22 
AA18 
IC 
TBD 
U2D1 
K11 
AA16 
AA4 
Y85 
Y83 
Y81 
Y79 
Y73 
Y71 
Y9 
Y7 
Y67 
Y5 
Y17 
Y15 
W82 
W78 
W74 
W68 
W42 
W40 
W38 
W36 
W34 
W32 
W30 
W28 
W26 
W24 
W22 
W12 
AC56 
W8 
V83 
V77 
V75 
V73 
V43 
V23 
V21 
V15 
V13 
V9 
V5 
V1 
U86 
U80 
U78 
U76 
U74 
U70 
U68 
U42 
U36 
U30 
U24 
U22 
U20 
U6 
U4 
T85 
T83 
T77 
T73 
T65 
T41 
T37 
T35 
T31 
T29 
T25 
T17 
T13 
R86 
R78 
R72 
R68 
R40 
R38 
R34 
R32 
R28 
R26 
R22 
R4 
R2 
R18 
R14 
P83 
P81 
P71 
P69 
P67 
P39 
P33 
P27 
P15 
P11 
N8 
N4 
N78 
N76 
N74 
N72 
N70 
N66 
N6 
N22 
N20 
DM19 
M85 
M83 
M79 
M71 
M65 
M43 
M41 
M39 
M37 
M35 
M33 
M31 
M29 
M27 
M25 
M23 
M19 
M17 
M15 
CT7 
BT9 
L82 
L80 
L78 
L72 
L22 
L20 
L6 
L2 
L10 
K85 
K83 
K81 
K77 
K73 
K71 
K67 
K65 
K39 
K33 
K27 
DB7 
K17 
K13 
K1 
J84 
J82 
J76 
IC 
TBD 
U2D1 
B9 
J74 
J72 
J40 
J38 
J34 
J32 
J28 
J26 
J22 
J14 
J12 
J4 
DN44 
H75 
H71 
H65 
H41 
H39 
H37 
H35 
H33 
H31 
H29 
H27 
H25 
H11 
H3 
G82 
G80 
G78 
G76 
G70 
G66 
G42 
G38 
G36 
G32 
G30 
G26 
G24 
G22 
G8 
G4 
F69 
F67 
F43 
F37 
F31 
F25 
F19 
F17 
F5 
E76 
E74 
E72 
E22 
E20 
E18 
E16 
E8 
E6 
D77 
D41 
D39 
D37 
D35 
D33 
D31 
D29 
D27 
D25 
D13 
D11 
CM27 
C78 
C76 
C16 
C14 
C12 
C10 
C8 
B75 
B71 
B37 
B31 
B25 
A38 
A36 
A32 
A30 
A26 
AC58 
AC60 
AC62 
AJ4 
AR6 
CG6 
CW6 
DE48 
DE50 
DE52 
DE54 
DE56 
DE58 
DE60 
DE62 
DL8 
DN18 
DP45 
DP47 
DP49 
DP51 
DP53 
DP55 
DP57 
DP59 
DP61 
DP63 
DP9 
DV19 
DY45 
DY47 
DY49 
DY51 
DY53 
DY55 
DY57 
DY59 
DY61 
DY63 
EA14 
L8 
V11 
E66 
ED69 
EE80 
EE8 
EE40 
ED81 
ED7 
ED41 
EC82 
EC6 
EC42 
DW2 
EB83 
EA84 
DY85 
J86 
E82 
D81 
D3 
C4 
B79 
B5 
B43 
A42 
IC 
TBD 
U2D1 
DESIGN NOTE: 
DO NOT SCALE DRAWING SHEET 
B
AA
B
B
SIZE 
SCALE: 
234
1234
DEPARTMENT CODE 
1
DOCUMENT NUMBER REV 
74 OF 270 
Wed Feb 08 16:34:49 2017 
VSS<614> VSS<615> 
VSS<616> VSS<617> VSS<618> VSS<619> VSS<620> VSS<621> VSS<622> VSS<623> VSS<624> VSS<625> VSS<626> VSS<627> VSS<628> 
VSS<629> VSS<630> VSS<631> VSS<632> VSS<633> VSS<634> VSS<635> VSS<636> VSS<637> VSS<638> VSS<639> VSS<640> VSS<641> 
VSS<642> VSS<643> VSS<644> VSS<645> VSS<646> VSS<647> VSS<648> VSS<649> VSS<650> VSS<651> VSS<652> VSS<653> VSS<654> 
VSS<655> VSS<656> VSS<657> VSS<658> VSS<659> VSS<660> VSS<661> VSS<662> VSS<663> VSS<664> VSS<665> VSS<666> VSS<667> 
VSS<668> VSS<669> VSS<670> VSS<671> VSS<672> VSS<673> VSS<674> VSS<675> VSS<676> VSS<677> VSS<678> VSS<679> 
VSS<680> VSS<681> VSS<682> VSS<683> VSS<684> VSS<685> VSS<686> VSS<687> VSS<688> VSS<689> VSS<690> VSS<691> VSS<692> 
VSS<693> 
VSS<694> VSS<695> 
VSS<696> VSS<697> VSS<698> VSS<699> VSS<700> VSS<701> VSS<702> VSS<703> VSS<704> VSS<705> VSS<706> VSS<707> VSS<708> 
VSS<709> VSS<710> VSS<711> VSS<712> VSS<713> VSS<714> VSS<715> VSS<716> VSS<717> VSS<718> VSS<719> VSS<720> VSS<721> 
VSS<722> VSS<723> VSS<724> VSS<725> VSS<726> VSS<727> VSS<728> VSS<729> VSS<730> VSS<731> VSS<732> VSS<733> VSS<734> 
VSS<735> VSS<736> VSS<737> VSS<738> VSS<739> VSS<740> VSS<741> VSS<742> VSS<743> VSS<744> VSS<745> VSS<746> VSS<747> 
VSS<748> VSS<749> VSS<750> VSS<751> VSS<752> VSS<753> VSS<754> VSS<755> VSS<756> VSS<757> VSS<758> VSS<759> 
VSS<760> VSS<761> VSS<762> VSS<763> VSS<764> VSS<765> VSS<766> VSS<767> VSS<768> VSS<769> VSS<770> VSS<771> VSS<772> 
VSS<773> 
VSS<774> VSS<775> 
VSS<776> VSS<777> VSS<778> VSS<779> VSS<780> VSS<781> VSS<782> VSS<783> VSS<784> VSS<785> VSS<786> VSS<787> 
VSS<788> VSS<789> VSS<790> VSS<791> VSS<792> VSS<793> VSS<794> VSS<795> VSS<796> VSS<797> VSS<798> VSS<799> VSS<800> 
VSS<801> VSS<802> VSS<803> VSS<804> VSS<805> VSS<806> VSS<807> VSS<808> VSS<809> VSS<810> VSS<811> VSS<812> VSS<813> 
VSS<814> VSS<815> VSS<816> VSS<817> VSS<818> VSS<819> VSS<820> VSS<821> VSS<822> VSS<823> VSS<824> VSS<825> VSS<826> 
VSS<827> VSS<828> VSS<829> VSS<830> VSS<831> VSS<832> VSS<833> VSS<834> VSS<835> VSS<836> VSS<837> VSS<838> VSS<839> 
VSS<840> VSS<841> VSS<842> VSS<843> VSS<844> VSS<845> VSS<846> VSS<847> VSS<848> VSS<849> VSS<850> VSS<851> VSS<852> 
VSS<853> 
VSS<854> VSS<855> 
VSS<856> VSS<857> VSS<858> VSS<859> VSS<860> VSS<861> VSS<862> VSS<863> VSS<864> VSS<865> VSS<866> VSS<867> 
VSS<868> VSS<869> VSS<870> VSS<871> VSS<872> VSS<873> VSS<874> VSS<875> VSS<876> VSS<877> VSS<878> VSS<879> VSS<880> 
VSS<881> VSS<882> VSS<883> VSS<884> VSS<885> VSS<886> VSS<887> VSS<888> VSS<889> VSS<890> VSS<891> VSS<892> VSS<893> 
VSS<894> VSS<895> VSS<896> VSS<897> VSS<898> VSS<899> VSS<900> VSS<901> VSS<902> VSS<903> VSS<904> VSS<905> VSS<906> 
VSS<907> VSS<908> VSS<909> VSS<910> VSS<911> VSS<912> VSS<913> VSS<914> VSS<915> VSS<916> VSS<917> VSS<918> VSS<919> 
VSS<920> VSS<921> VSS<922> VSS<923> VSS<924> VSS<925> VSS<926> VSS<927> VSS<928> VSS<929> VSS<930> VSS<931> VSS<932> 
VSS<933> 
VSS<934> VSS<935> 
VSS<936> VSS<937> VSS<938> VSS<939> VSS<940> VSS<941> VSS<942> VSS<943> VSS<944> VSS<945> VSS<946> VSS<947> 
VSS<948> VSS<949> VSS<950> VSS<951> VSS<952> VSS<953> VSS<954> VSS<955> VSS<956> VSS<957> VSS<958> VSS<959> VSS<960> 
VSS<961> VSS<962> VSS<963> VSS<964> VSS<965> VSS<966> VSS<967> VSS<968> VSS<969> VSS<970> VSS<971> VSS<972> VSS<973> 
VSS<974> VSS<975> VSS<976> VSS<977> VSS<978> VSS<979> VSS<980> VSS<981> VSS<982> VSS<983> VSS<984> VSS<985> VSS<986> 
VSS<987> VSS<988> VSS<989> VSS<990> VSS<991> VSS<992> VSS<993> VSS<994> VSS<995> VSS<996> VSS<997> VSS<998> VSS<999> 
VSS<1000> VSS<1001> VSS<1002> VSS<1003> VSS<1004> VSS<1005> VSS<1006> VSS<1007> VSS<1008> VSS<1009> VSS<1010> VSS<1011> VSS<1012> 
VSS<1013> 
VSS<1014> VSS<1015> 
VSS<1016> VSS<1017> VSS<1018> VSS<1019> VSS<1020> VSS<1021> VSS<1022> VSS<1023> VSS<1024> VSS<1025> VSS<1026> VSS<1027> 
VSS<1028> VSS<1029> VSS<1030> VSS<1031> VSS<1032> VSS<1033> VSS<1034> VSS<1035> VSS<1036> VSS<1037> VSS<1038> VSS<1039> VSS<1040> 
VSS<1041> VSS<1042> VSS<1043> VSS<1044> VSS<1045> VSS<1046> VSS<1047> VSS<1048> VSS<1049> VSS<1050> VSS<1051> VSS<1052> VSS<1053> 
VSS<1054> VSS<1055> VSS<1056> VSS<1057> VSS<1058> VSS<1059> VSS<1060> VSS<1061> VSS<1062> VSS<1063> VSS<1064> VSS<1065> VSS<1066> 
VSS<1067> VSS<1068> VSS<1069> VSS<1070> VSS<1071> VSS<1072> VSS<1073> VSS<1074> VSS<1075> VSS<1076> VSS<1077> VSS<1078> VSS<1079> 
VSS<1080> VSS<1081> VSS<1082> VSS<1083> VSS<1084> VSS<1085> VSS<1086> VSS<1087> VSS<1088> VSS<1089> VSS<1090> VSS<1091> VSS<1092> 
VSS<1093> 
VSS<1094> VSS<1095> 
VSS<1096> VSS<1097> VSS<1098> VSS<1099> VSS<1100> VSS<1101> VSS<1102> VSS<1103> VSS<1104> VSS<1105> VSS<1106> VSS<1107> VSS<1108> 
VSS<1109> VSS<1110> VSS<1111> VSS<1112> VSS<1113> VSS<1114> VSS<1115> VSS<1116> VSS<1117> VSS<1118> VSS<1119> VSS<1120> VSS<1121> 
VSS<1122> VSS<1123> VSS<1124> VSS<1125> VSS<1126> VSS<1127> VSS<1128> VSS<1129> VSS<1130> VSS<1131> VSS<1132> VSS<1133> VSS<1134> 
VSS<1135> VSS<1136> VSS<1137> VSS<1138> VSS<1139> VSS<1140> VSS<1141> VSS<1142> VSS<1143> VSS<1144> VSS<1145> VSS<1146> VSS<1147> 
VSS<1148> VSS<1149> VSS<1150> VSS<1151> VSS<1152> VSS<1153> VSS<1154> VSS<1155> VSS<1156> VSS<1157> VSS<1158> VSS<1159> 
VSS<1160> VSS<1161> VSS<1162> VSS<1163> VSS<1164> VSS<1165> VSS<1166> VSS<1167> VSS<1168> VSS<1169> VSS<1170> VSS<1171> VSS<1172> 
VSS<1173> 
VSS<1174> VSS<1175> 
VSS<1176> VSS<1177> VSS<1178> VSS<1179> VSS<1180> VSS<1181> VSS<1182> VSS<1183> VSS<1184> VSS<1185> VSS<1186> VSS<1187> VSS<1188> 
VSS<1189> VSS<1190> VSS<1191> VSS<1192> VSS<1193> VSS<1194> VSS<1195> VSS<1196> VSS<1197> VSS<1198> VSS<1199> VSS<1200> VSS<1201> 
VSS<1202> VSS<1203> VSS<1204> VSS<1205> VSS<1206> VSS<1207> VSS<1208> VSS<1209> VSS<1210> VSS<1211> VSS<1212> VSS<1213> VSS<1214> 
VSS<1215> VSS<1216> VSS<1217> VSS<1218> VSS<1219> VSS<1220> VSS<1221> VSS<1222> VSS<1223> VSS<1224> VSS<1225> VSS<1226> VSS<1227> 
VSS<1228> VSS<1229> VSS<1230> VSS<1231> VSS<1232> VSS<1233> VSS<1234> VSS<1235> VSS<1236> VSS<1237> VSS<1238> VSS<1239> 
VSS<1240> VSS<1241> VSS<1242> VSS<1243> VSS<1244> VSS<1245> VSS<1246> VSS<1247> VSS<1248> VSS<1249> VSS<1250> VSS<1251> VSS<1252> 
VSS<1253> 
CPU SYMBOLS 1-30 ARE PRELIMINARY AND SUBJECT TO CHANGE 
SKYLAKE - SKT1 - 20 OF 21 
SKX_EXT_B SKX_EXT_B SKX_EXT_B SKX_EXT_B 
INA
ILER
RY
P
MINA
ILER
RY
P
M
INA
ILER
RY
P
MINA
ILER
RY
P
M
ROOM=CPU1 
BOM_COST=PROC_SOCKET 
WIWYNN CORPORATION 
26/30 25/30 24/30 23/30 



DU22 
DG78 
CU86 
CK63 
BH9 
DU80 
EF79 
EF75 
EF71 
EE78 
EE76 
EE70 
EE36 
EE34 
EE30 
EE28 
EE24 
ED77 
ED35 
ED29 
ED23 
ED15 
ED11 
EC76 
EC74 
EC72 
EC70 
EC10 
EB69 
EB65 
EB41 
EB39 
EB37 
EB35 
EB33 
EB31 
EB29 
EB27 
EB25 
EB23 
BR18 
EB13 
EA82 
EA80 
EA78 
EA76 
EA70 
EA64 
EA42 
EA22 
EA20 
EA16 
J16 
EA6 
DY75 
DY71 
DY41 
DY35 
DY29 
DY23 
DY19 
DY5 
DW84 
DW82 
DW8 
DW76 
DW74 
DW72 
DW70 
DW68 
DW66 
DW64 
DW40 
DW36 
DW34 
DW30 
DW28 
DW24 
DW20 
DW12 
DV81 
DV77 
DV73 
DV39 
DV37 
DV33 
DV31 
DV27 
DV25 
DV21 
DU84 
DU82 
DU78 
DU72 
DU70 
DU38 
DU32 
DU26 
CN14 
DU14 
DU10 
DT85 
DT83 
DT79 
DT69 
DT65 
DH21 
DT17 
DT3 
DR78 
DR76 
DR74 
DR72 
DR70 
DR68 
DR66 
DR42 
DR40 
DR38 
DR36 
DR34 
DR32 
DR30 
DR28 
DR26 
DR24 
DR22 
DR20 
CL22 
CA20 
DR6 
BR26 
DP83 
DP81 
DP71 
DP69 
DP67 
DN78 
IC 
TBD 
U2D1 
DH79 
DN72 
DN68 
DN38 
DN32 
DN26 
DN22 
DN12 
BH17 
DN2 
DM83 
DM77 
DM73 
DM65 
DM39 
DM37 
DM33 
DM31 
DM27 
DM25 
H45 
DM15 
DL80 
DL78 
DL76 
DL74 
DL70 
DL68 
DL40 
DL36 
DL34 
DL30 
DL28 
DL24 
DL22 
DL4 
DL18 
DL16 
DK85 
DK83 
DK77 
DK75 
DK73 
DK41 
DK39 
DK35 
DK29 
DK23 
DK7 
DJ84 
DJ82 
DJ78 
DJ74 
DJ68 
DJ42 
DJ38 
DJ22 
H47 
DJ10 
DJ2 
DH83 
DH81 
DH73 
DH71 
DH67 
DH41 
DH37 
DH35 
DH33 
DH31 
DH29 
DH27 
DH25 
DH23 
DH15 
DH13 
DG82 
DG80 
DG76 
DG68 
DG66 
DG24 
DG16 
DG14 
H49 
DG2 
DF85 
DF83 
DF79 
DF73 
DF69 
DF65 
DF41 
DF39 
DF37 
DF35 
DF29 
DF19 
H51 
DF7 
DF5 
DE78 
DE72 
DE70 
DE64 
DE36 
DE34 
DE30 
DE28 
DE24 
DE20 
DE18 
DE8 
DE6 
DD83 
DD81 
DD75 
DD73 
DD71 
DD37 
DD33 
DD31 
DD27 
DD23 
DD11 
DC86 
DC84 
DC78 
DC70 
DC68 
DC66 
DC64 
DC42 
DC38 
DC32 
DC26 
DC24 
DC14 
DB85 
DB83 
DB77 
DB73 
DB49 
DB47 
DB41 
DB39 
DB25 
DB23 
DB17 
DB13 
DB3 
DA80 
DA78 
DA76 
DA74 
DA70 
DA64 
DA50 
DA48 
IC 
TBD 
U2D1 
CJ76 
DA46 
DA44 
DA38 
DA36 
DA34 
DA32 
DA30 
DA28 
DA26 
DA18 
H53 
DA6 
CY85 
CY83 
CY77 
CY75 
CY69 
CY65 
CY61 
CY59 
CY51 
CY45 
CY41 
CY21 
CY15 
CY13 
CY9 
CY1 
CW82 
CW78 
CW74 
CW68 
CW66 
CW64 
CW54 
CW52 
CW42 
CW40 
CW38 
CW32 
CW26 
CW12 
CV83 
CV81 
CV79 
CV73 
CV67 
CV63 
CV55 
CV53 
CV41 
CV39 
CV37 
CV33 
CV31 
CV27 
CV25 
CV17 
H55 
CV1 
CU82 
CU80 
CU78 
CU76 
CU68 
CU62 
CU56 
CU36 
CU34 
CU30 
CU28 
CU22 
CU4 
CT85 
CT83 
CT79 
CT73 
CT57 
CT35 
CT33 
CT29 
CT27 
CT19 
CT13 
H57 
CR86 
CR78 
CR68 
CR66 
CR64 
CR62 
CR58 
CR32 
CR24 
CR22 
CR10 
CR6 
CP83 
CP81 
CP75 
CP73 
CP69 
CP59 
CP25 
H59 
CP1 
CN78 
CN68 
CN62 
CN60 
CN32 
CN26 
H61 
CN12 
CN2 
CM85 
CM83 
CM77 
CM73 
CM67 
CM63 
CM61 
CM31 
CM5 
CM29 
CM19 
CL80 
CL78 
CL76 
CL74 
CL66 
CL64 
CL62 
H63 
P45 
CL18 
CL14 
CL8 
CK85 
CK83 
CK75 
CK73 
CK71 
CK69 
CK67 
CK65 
CK27 
CK21 
CK15 
CK11 
CJ86 
CJ84 
CJ82 
CJ78 
CJ74 
CJ62 
P47 
IC 
TBD 
U2D1 
BG78 
BG82 
BG76 
BG74 
CD13 
P49 
CJ12 
CJ10 
CJ8 
CJ6 
CJ2 
CH83 
CH81 
CH79 
CH73 
CH67 
CH63 
CH19 
CH15 
CH3 
CH1 
CG80 
CG72 
CG68 
CG62 
CG22 
CG18 
P51 
CF83 
CF77 
CF71 
CF69 
CF63 
CF9 
P53 
CE82 
CE70 
CE62 
CE26 
CE20 
CE14 
CE10 
CD81 
CD79 
CD77 
CD75 
CD73 
CD63 
CD5 
CC82 
CC80 
CC78 
CC76 
CC74 
CC72 
CC64 
CC24 
CC18 
CC16 
CC4 
CB71 
CB63 
CB27 
CB9 
CB7 
CA70 
CA68 
CA66 
CA64 
CA26 
CA18 
CA14 
CA10 
CA8 
CA6 
CA2 
BY71 
BY69 
BY67 
BY65 
BY63 
BY23 
BY13 
BY11 
BW82 
BW80 
BW78 
BW76 
BW74 
BW72 
BW26 
BW18 
BW16 
BW14 
BW12 
P55 
BW6 
BV25 
BV17 
BU10 
BV5 
BU8 
BT25 
BT23 
BT21 
BT5 
BT3 
BR82 
BR80 
BR78 
BR76 
BR74 
BR72 
BR70 
BR68 
BR66 
BR64 
P57 
BR16 
BR10 
BR6 
BP27 
BP3 
BN26 
BN20 
BN10 
BN6 
BM25 
P59 
BM15 
BM13 
BM9 
BL82 
BL80 
BL78 
BL76 
BL74 
BL72 
BL70 
BL68 
BL66 
BL64 
BL24 
BL22 
P61 
BL12 
BL10 
BL6 
BK19 
BK11 
BK7 
BK3 
BJ6 
BJ4 
BH21 
BH15 
BH11 
BH7 
BG80 
IC 
TBD 
U2D1 
DESIGN NOTE: 
DO NOT SCALE DRAWING SHEET 
B
AA
B
B
SIZE 
SCALE: 
234
1234
DEPARTMENT CODE 
1
DOCUMENT NUMBER REV 
75 OF 270 
Wed Feb 08 16:34:49 2017 
VSS<0> VSS<1> 
VSS<2> VSS<3> VSS<4> VSS<5> VSS<6> VSS<7> VSS<8> VSS<9> VSS<10> VSS<11> VSS<12> VSS<13> VSS<14> 
VSS<15> VSS<16> VSS<17> VSS<18> VSS<19> VSS<20> VSS<21> VSS<22> VSS<23> VSS<24> VSS<25> VSS<26> VSS<27> 
VSS<28> VSS<29> VSS<30> VSS<31> VSS<32> VSS<33> VSS<34> VSS<35> VSS<36> VSS<37> VSS<38> VSS<39> 
VSS<40> VSS<41> VSS<42> VSS<43> VSS<44> VSS<45> VSS<46> VSS<47> VSS<48> VSS<49> VSS<50> VSS<51> VSS<52> 
VSS<53> 
VSS<54> VSS<55> 
VSS<56> VSS<57> VSS<58> VSS<59> VSS<60> VSS<61> VSS<62> VSS<63> VSS<64> VSS<65> VSS<66> VSS<67> VSS<68> 
VSS<69> VSS<70> VSS<71> VSS<72> VSS<73> VSS<74> VSS<75> VSS<76> VSS<77> VSS<78> VSS<79> VSS<80> VSS<81> 
VSS<82> VSS<83> VSS<84> VSS<85> VSS<86> VSS<87> VSS<88> VSS<89> VSS<90> VSS<91> VSS<92> VSS<93> VSS<94> 
VSS<95> VSS<96> VSS<97> VSS<98> VSS<99> VSS<100> VSS<101> VSS<102> VSS<103> VSS<104> VSS<105> VSS<106> VSS<107> 
VSS<108> VSS<109> VSS<110> VSS<111> VSS<112> VSS<113> VSS<114> VSS<115> VSS<116> VSS<117> VSS<118> VSS<119> 
VSS<120> VSS<121> VSS<122> VSS<123> VSS<124> VSS<125> VSS<126> VSS<127> VSS<128> VSS<129> VSS<130> VSS<131> VSS<132> 
VSS<133> 
VSS<134> VSS<135> VSS<136> 
VSS<137> VSS<138> VSS<139> VSS<140> VSS<141> VSS<142> VSS<143> VSS<144> VSS<145> VSS<146> VSS<147> VSS<148> 
VSS<149> VSS<150> VSS<151> VSS<152> VSS<153> VSS<154> VSS<155> VSS<156> VSS<157> VSS<158> VSS<159> VSS<160> VSS<161> 
VSS<162> VSS<163> VSS<164> VSS<165> VSS<166> VSS<167> VSS<168> VSS<169> VSS<170> VSS<171> VSS<172> VSS<173> VSS<174> 
VSS<175> VSS<176> VSS<177> VSS<178> VSS<179> VSS<180> VSS<181> VSS<182> VSS<183> VSS<184> VSS<185> VSS<186> VSS<187> 
VSS<188> VSS<189> VSS<190> VSS<191> VSS<192> VSS<193> VSS<194> VSS<195> VSS<196> VSS<197> VSS<198> VSS<199> VSS<200> 
VSS<201> VSS<202> VSS<203> VSS<204> VSS<205> VSS<206> VSS<207> VSS<208> VSS<209> VSS<210> VSS<211> VSS<212> VSS<213> 
VSS<214> VSS<215> VSS<216> 
VSS<217> VSS<218> VSS<219> VSS<220> VSS<221> VSS<222> VSS<223> VSS<224> VSS<225> VSS<226> VSS<227> VSS<228> 
VSS<229> VSS<230> VSS<231> VSS<232> VSS<233> VSS<234> VSS<235> VSS<236> VSS<237> VSS<238> VSS<239> VSS<240> VSS<241> 
VSS<242> VSS<243> VSS<244> VSS<245> VSS<246> VSS<247> VSS<248> VSS<249> VSS<250> VSS<251> VSS<252> VSS<253> VSS<254> 
VSS<255> VSS<256> VSS<257> VSS<258> VSS<259> VSS<260> VSS<261> VSS<262> VSS<263> VSS<264> VSS<265> VSS<266> VSS<267> 
VSS<268> VSS<269> VSS<270> VSS<271> VSS<272> VSS<273> VSS<274> VSS<275> VSS<276> VSS<277> VSS<278> VSS<279> VSS<280> 
VSS<281> VSS<282> VSS<283> VSS<284> VSS<285> VSS<286> VSS<287> VSS<288> VSS<289> VSS<290> VSS<291> VSS<292> VSS<293> 
VSS<294> VSS<295> VSS<296> 
VSS<297> VSS<298> VSS<299> VSS<300> VSS<301> VSS<302> VSS<303> VSS<304> VSS<305> VSS<306> VSS<307> VSS<308> 
VSS<309> VSS<310> VSS<311> VSS<312> VSS<313> VSS<314> VSS<315> VSS<316> VSS<317> VSS<318> VSS<319> VSS<320> VSS<321> 
VSS<322> VSS<323> VSS<324> VSS<325> VSS<326> VSS<327> VSS<328> VSS<329> VSS<330> VSS<331> VSS<332> VSS<333> VSS<334> 
VSS<335> VSS<336> VSS<337> VSS<338> VSS<339> VSS<340> VSS<341> VSS<342> VSS<343> VSS<344> VSS<345> VSS<346> VSS<347> 
VSS<348> VSS<349> VSS<350> VSS<351> VSS<352> VSS<353> VSS<354> VSS<355> VSS<356> VSS<357> VSS<358> VSS<359> VSS<360> 
VSS<361> VSS<362> VSS<363> VSS<364> VSS<365> VSS<366> VSS<367> VSS<368> VSS<369> VSS<370> VSS<371> VSS<372> VSS<373> 
VSS<374> VSS<375> VSS<376> 
VSS<377> VSS<378> VSS<379> VSS<380> VSS<381> VSS<382> VSS<383> VSS<384> VSS<385> VSS<386> VSS<387> VSS<388> 
VSS<389> VSS<390> VSS<391> VSS<392> VSS<393> VSS<394> VSS<395> VSS<396> VSS<397> VSS<398> VSS<399> VSS<400> VSS<401> 
VSS<402> VSS<403> VSS<404> VSS<405> VSS<406> VSS<407> VSS<408> VSS<409> VSS<410> VSS<411> VSS<412> VSS<413> VSS<414> 
VSS<415> VSS<416> VSS<417> VSS<418> VSS<419> VSS<420> VSS<421> VSS<422> VSS<423> VSS<424> VSS<425> VSS<426> VSS<427> 
VSS<428> VSS<429> VSS<430> VSS<431> VSS<432> VSS<433> VSS<434> VSS<435> VSS<436> VSS<437> VSS<438> VSS<439> VSS<440> 
VSS<441> VSS<442> VSS<443> VSS<444> VSS<445> VSS<446> VSS<447> VSS<448> VSS<449> VSS<450> VSS<451> VSS<452> VSS<453> 
VSS<454> VSS<455> VSS<456> 
VSS<457> VSS<458> VSS<459> VSS<460> VSS<461> VSS<462> VSS<463> VSS<464> VSS<465> VSS<466> VSS<467> VSS<468> 
VSS<469> VSS<470> VSS<471> VSS<472> VSS<473> VSS<474> VSS<475> VSS<476> VSS<477> VSS<478> VSS<479> VSS<480> VSS<481> 
VSS<482> VSS<483> VSS<484> VSS<485> VSS<486> VSS<487> VSS<488> VSS<489> VSS<490> VSS<491> VSS<492> VSS<493> VSS<494> 
VSS<495> VSS<496> VSS<497> VSS<498> VSS<499> VSS<500> VSS<501> VSS<502> VSS<503> VSS<504> VSS<505> VSS<506> VSS<507> 
VSS<508> VSS<509> VSS<510> VSS<511> VSS<512> VSS<513> VSS<514> VSS<515> VSS<516> VSS<517> VSS<518> VSS<519> VSS<520> 
VSS<521> VSS<522> VSS<523> VSS<524> VSS<525> VSS<526> VSS<527> VSS<528> VSS<529> VSS<530> VSS<531> VSS<532> VSS<533> 
VSS<534> VSS<535> VSS<536> 
VSS<537> VSS<538> VSS<539> VSS<540> VSS<541> VSS<542> VSS<543> VSS<544> VSS<545> VSS<546> VSS<547> VSS<548> 
VSS<549> VSS<550> VSS<551> VSS<552> VSS<553> VSS<554> VSS<555> VSS<556> VSS<557> VSS<558> VSS<559> VSS<560> VSS<561> 
VSS<562> VSS<563> VSS<564> VSS<565> VSS<566> VSS<567> VSS<568> VSS<569> VSS<570> VSS<571> VSS<572> VSS<573> VSS<574> 
VSS<575> VSS<576> VSS<577> VSS<578> VSS<579> VSS<580> VSS<581> VSS<582> VSS<583> VSS<584> VSS<585> VSS<586> VSS<587> 
VSS<588> VSS<589> VSS<590> VSS<591> VSS<592> VSS<593> VSS<594> VSS<595> VSS<596> VSS<597> VSS<598> VSS<599> VSS<600> 
VSS<601> VSS<602> VSS<603> VSS<604> VSS<605> VSS<606> VSS<607> VSS<608> VSS<609> VSS<610> VSS<611> VSS<612> VSS<613> 
CPU SYMBOLS 1-30 ARE PRELIMINARY AND SUBJECT TO CHANGE 
SKYLAKE - SKT1 - 21 OF 21 
SKX_EXT_B SKX_EXT_B SKX_EXT_B SKX_EXT_B 
INA
ILER
RY
P
M
INA
ILER
RY
P
M
INA
ILER
RY
P
M INA
ILER
RY
P
M
WIWYNN CORPORATION 
30/30 29/30 28/30 27/30 



C3D2 
0603V 
22.0UF 
C8P8 
1
0805 
100UF 
C8P23 
0603V 
20% 
22.0UF 
PVCCMCP_CPU1 
20% 
22.0UF 
C3W4 
X6S 
20% 
22.0UF 
C2D29 
E15431-004 
22.0UF 
C3D4 
22.0UF 
4V 
20% 
X6S 
E15431-004 
0603V 
PVCCMCP_CPU1 
C3D10 
4V 
20% 
X6S 
E15431-004 
C3D21 
X6S 
E15431-004 
0603V 0603V 
E15431-004 
X6S 
E15431-004 
C3D19 
4V 
22.0UF 
0603V 
20% 
C3D20 
20% 
22.0UF 
4V 
X6S 
0603V 
E15431-004 
20% 
4V 
X6S 
1
2 2
1
X6S 
4V 
0603V 
20% 
C3D5 
0603V 
C3D17 1
4V 
20% 
E15431-004 2
0603V 
2
1
X6S 
4V 
20% 
22.0UF 
E15431-004 
C3D6 C3D12 
22.0UF 
2
1
X6S 
4V 
0603V 
20% 
E15431-004 
0603V 
E15431-004 2
1
X6S 
4V 
20% 
22.0UF 
C3D18 
E15431-004 2
1
X6S 
4V 
0603V 
20% 
22.0UF 
E15431-004 
20% 
X6S 
2
4V 
1
22.0UF 
0603V 
22
0603V 
1 C3D11 
2
1
4V 
C3D14 
X6S 
20% 
22.0UF 
2
1
X6S 
4V 
0603V 
20% 
22.0UF 
C3D13 
E15431-004 
0603V 
E15431-004 
4V 4V 
22.0UF 
0603V 
E15431-004 
X6S 
20% 
C2D28 
20% 
4V 
E15431-004 
X6S X6S 
20% 
22.0UF 
C3D9 
E15431-004 
0603V 0603V 
E15431-004 
0603V 
E15431-004 
0603V 
X6S X6S X6S 
20% 
4V 4V 
22.0UF 22.0UF 
C2D11 
1
C2D10 
E15431-004 
22.0UF 
C3D16 
22.0UF 1
E15431-004 
0603LF 
100UF 
20% 
0805 
PVCCMCP_CPU1 
C7P5 
100UF 1
4V 
0805 20805 
E15431-001 
22.0UF 
4V 
100UF 
2
C8W4 
602433-112 
20% 
0805 
4V 
1
20805 0805 2 0805 
20% 
C7P9 
2
1
4V 
100UF 
2 0805 
1
20% 
4V 4V 
1
2
20% 
0805 
C7P14 
2
C7P13 
20% 
1
4V 
100UF 100UF 
4V 
1
2
20% 
0805 
C7P4 
100UF 
4V 
20% 
1
0805 2
C8P15 
0805 
20% 
2
1
4V 
100UF 
C8P14 
20% 
2
1
4V 
100UF 
C7P15 
0805 
1
20% 
4V 
100UF 
C7P11 
100UF 
4V 
1
2
20% 
0805 
C7P8 
100UF 
4V 
20% 
1
0805 2
C8P22 
0805 
20% 
2
1
4V 
100UF 
C7P7 
2
1
20% 
4V 
100UF 
C7P10 C7P6 
1
20% 
4V 
100UF 
2 0805 
1
20% 
4V 
100UF 
C8P9 
100UF 
4V 
2
20% 
C7P12 
22.0UF 
4V 
20% 
22.0UF 
4V 
20% 
X6S 
E15431-004 
0603V 0603V 
C7P18 
47UF 
20% 20% 
E15431-004 
X6S 
C2D38 
X6S 
0603V 
C2D24 
2 0603V 
2
22.0UF 
C2D14 
E15431-004 
X6S 
20% 20% 20% 
X6S 
E15431-004 
22.0UF 
C2D17 
E15431-004 
20% 
X6S 
20% 
4V 4V 4V 
20% 
X6S X6S 
E15431-004 
E15431-004 
X6S 
20% 20% 
X6S 
20% 20% 
X6S 
E15431-004 
20% 
X6S 
E15431-004 
22.0UF 22.0UF 
C2D13 C2D19 
22.0UF 22.0UF 1
47UF 47UF 
E15431-004 
0603V 
E15431-004 
X6S 
C2D25 
1
4V 
0603V 
4V 
X6S 
20% 
C3D8 
E15431-004 
0603V 
4V 
20% 
4V 
X6S 
C3W3 
22.0UF 
1 1 47UF 
20805 2
1
0805 
20% 
2
X6S 
C95333-006 
0805 
47UF 1
0805 22
47UF 
0805 
20% 
47UF 
C8P17 
47UF 
1
0805 
47UF 
0805 
C8P27 
47UF 
C8P11 
0805 
C8P26 
0805 
22.0UF 
2
C7P19 
47UF 
2
11
X6S 
22.0UF 
2
4V 
1
2
2
1
X6S 
E15431-004 
4V 
2
1
0603V 
22.0UF 
4V 
22.0UF 
C2D22 
1
E15431-004 
22.0UF 
C2D31 
4V 
0603V 
1
2
1
4V 
0603V 
0603V 
X6S 
C2D23 
1
4V 
1
20% 
22.0UF 
C2D16 
4V 
X6S 
0603V 
1
2
E15431-004 
0603V 
X6S 
2
2
X6S 
0603V 
E15431-004 
1
C2D27 
2
1
C2D34 
22.0UF 
4V 
20% 
0603V 
2
1
0603V 
20% 
4V 
22.0UF 
C2D37 
1
2
4V 
22.0UF 
C2D26 
E15431-004 
1
2
1
2
C2D12 
22.0UF 
4V E15431-004 
0603V 
X6S 
0603V 
X6S 
20% 
4V 
C2D15 
PVCCMCP_CPU1 
E15431-004 
2 2
22.0UF 
C2D30 
1
2 0603V 2
1
E15431-004 
4V 
2
1
20% 
X6S 
4V 
0603V 
1
2
1
4V 
X6S 
0603V 
E15431-004 
22.0UF 
4V 
22.0UF 
4V 
0603V 
20% 
X6S 
0603V 
1 1
1
1
2
4V 
20% 20% 2 2
20% 
2
X6S 
1
20603V 
E15431-004 
X6S 
C3D24 
C8P7 
C95333-002 
0805LF 
22UF 1
22
1 22UF 
2
1 22UF 
C95333-002 
C8P5 
C95333-002 
2
C8P10 
X6S 
2 0805 
C8P29 
47UF 1
1
C8P24 
47UF 
C8P28 
47UF 1
2 2
47UF 
C8P25 
2
1
C8P13 
47UF 
0805 0805 
C8P6 
20% 
0805 2
0805LF 0805LF 
2
1
C8P19 
47UF 
C8P18 
1
20% 
0805 
47UF 
1
C8P12 
2
20% 
C7P16 
C95333-006 
47UF 
20% 
C7P3 
2
22.0UF 
C2D32 
0603V 
4V 
1
4V 
2
1
20% 
4V 
22.0UF 
C2D36 
22.0UF 
E15431-004 C95333-006 
1
C7P17 
C2D9 
0603LF 
C2D18 
0603V 
E15431-001 
20% 
2
20% 
4V 
10UF 1
E15431-001 
0603LF 
X6S 
4V 
2
20% 
10UF 10UF 
2
C2D8 
10UF 
4V 
0603LF 
1
20% 
X6S 
E15431-001 
22.0UF 
C2D21 
22.0UF 
20% 
X6S 
E15431-004 2
C2D33 
22.0UF 
20% 20% 
2
C2D20 
20% 
X6S 
0603V 
20805 
20% 20% 20% 20% 20% 20% 
C8P16 
0805 0805 2
20% 20% 20% 20% 
C8P21 
0805 
20% 20% 20% 20% 20% 
0805 
E15431-004 
20% 
C2D35 
C3D23 
0805 
E15431-004 
4V 
20% 
0603V 
E15431-004 
E15431-004 
X6S 
47UF 
C8P20 
E15431-004 
0603V 0603V 
E15431-004 
X6S 
20% 
4V 4V 
122.0UF 
4V 
122.0UF 
C3D15 
0603V 
E15431-004 
1
20% 
X6S 
C3D7 
4V 
22.0UF 
C2D39 1
0603V 
E15431-004 2 X6S 
22.0UF 
C2D40 
TP FAB3 CHANGE CAP FROM 47UF TO 100UF 1004 
TP FAB1 MOVE TO PAGE 225 0318 
TP FAB1 MOVE TO PAGE 228 0311 
TP FAB1 ADD CAP 0314 
TP FAB1 MOVE TO PAGE 225 0314 
TP FAB1 MOVE TO PAGE 225 0314 
TP FAB1 MOVE TO PAGE 228 0314 
TP FAB1 MOVE TO PAGE 228 0318 
TP FAB1 MOVE TO PAGE 225 0311 
TP FAB1 MOVE TO PAGE 228 0314 
TP FAB1 MOVE TO PAGE 225 0314 
TP FAB1 MOVE TO PAGE 228 0314 
TP FAB1 MOVE TO PAGE 225 0311 
TP FAB1 MOVE TO PAGE 225 0311 
TP FAB1 MOVE TO PAGE 225 0314 
TP FAB1 MOVE TO PAGE 228 0311 
TP FAB3 ADD CAP 0919 
TP FAB1 MOVE TO PAGE 228 0314 
GROUP=PWR_MLCC_CAP GROUP=PWR_MCP_CAP 
GROUP=PWR_MLCC_CAP 
GROUP=PWR_MLCC_CAP 
GROUP=PWR_MLCC_CAP 
NEW_PN=078.1071T.0811
NEW_PN=078.1071T.0811 
NEW_MATERIAL=X6S 
NEW_PN=078.1071T.0811 NEW_PN=078.1071T.0811 
NEW_PN=078.1071T.0811 
NEW_PN=078.1071T.0811 
NEW_PN=078.1071T.0811 
NEW_PN=078.1071T.0811 
NEW_PN=078.1071T.0811 
NEW_PN=078.1071T.0811 
NEW_PN=078.1071T.0811 
NEW_PN=078.1071T.0811 
NEW_PN=078.1071T.0811 
NEW_PN=078.1071T.0811 
NEW_PN=078.1071T.0811 NEW_PN=078.1071T.0811 
NEW_PN=078.1071T.0811 
NEW_PN=078.1071T.0811 
NEW_MATERIAL=X6S 
GROUP=PWR_MLCC_CAP 
GROUP=PWR_MLCC_CAP 
GROUP=PWR_MCP_CAP 
GROUP=PWR_MCP_CAP 
GROUP=PWR_MCP_CAP GROUP=PWR_MCP_CAP 
GROUP=PWR_MCP_CAP GROUP=PWR_MCP_CAP 
GROUP=PWR_MCP_CAP 
GROUP=PWR_MCP_CAP 
GROUP=PWR_MCP_CAP 
GROUP=PWR_MCP_CAP 
GROUP=PWR_MLCC_CAP 
GROUP=PWR_MCP_CAP 
GROUP=PWR_MCP_CAP 
GROUP=PWR_MLCC_CAP 
GROUP=PWR_MLCC_CAP 
NEW_MATERIAL=X6S 
NEW_MATERIAL=X6S NEW_MATERIAL=X6S NEW_MATERIAL=X6S 
NEW_MATERIAL=X6S NEW_MATERIAL=X6S NEW_MATERIAL=X6S NEW_MATERIAL=X6S NEW _MATERIAL=X6S 
NEW_MATERIAL=X6S 
NEW_MATERIAL=X6S 
GROUP=PWR_MLCC_CAP 
GROUP=PWR_MLCC_CAP 
GROUP=PWR_MLCC_CAP 
NEW_MATERIAL=X6S 
NEW_MATERIAL=X6S 
NEW_MATERIAL=X6S 
NEW_MATERIAL=X6S NEW_MATERIAL=X6S 
GROUP=PWR_MLCC_CAP 
GROUP=PWR_MLCC_CAP 
GROUP=PWR_MLCC_CAP 
4V 
GROUP=PWR_MLCC_CAP 
GROUP=PWR_MLCC_CAP 
GROUP=PWR_MLCC_CAP 
GROUP=PWR_MLCC_CAP GROUP=PWR_MLCC_CAP 
GROUP=PWR_MLCC_CAP 
4V 4V 4V 
GROUP=PWR_MLCC_CAP 
GROUP=PWR_MLCC_CAP 
GROUP=PWR_MLCC_CAP 
GROUP=PWR_MLCC_CAP 
4V 
X6S X6S 
4V 
X6S 
4V 
4V 4V 4V 
4V 
X6S 
4V 
X6S 
4V 
X6S X6S 
4V 4V 
4V 
X6S 
4V 
X6S 
X6S 
4V 
X6S 
X6S 
4V 
X6S X6S X6S X6S 
4V 
4V 
GROUP=PWR_MLCC_CAP 
GROUP=PWR_MLCC_CAP 
GROUP=PWR_MLCC_CAP 
GROUP=PWR_MLCC_CAP 
GROUP=PWR_MLCC_CAP 
GROUP=PWR_MLCC_CAP 
GROUP=PWR_MLCC_CAP 
GROUP=PWR_MLCC_CAP 
GROUP=PWR_MLCC_CAP 
GROUP=PWR_MLCC_CAP 
GROUP=PWR_MLCC_CAP 
GROUP=PWR_MLCC_CAP GROUP=PWR_MLCC_CAP 
GROUP=PWR_MLCC_CAP 
GROUP=PWR_MLCC_CAP 
GROUP=PWR_MLCC_CAP GROUP=PWR_MLCC_CAP 
GROUP=PWR_MLCC_CAP 
X6S 
GROUP=PWR_MLCC_CAP 
GROUP=PWR_MLCC_CAP 
GROUP=PWR_MLCC_CAP 
GROUP=PWR_MLCC_CAP 
X6S 
X6S X6S 
GROUP=PWR_MLCC_CAP 
GROUP=PWR_MLCC_CAP 
4V 
GROUP=PWR_MLCC_CAP 
X6S 
GROUP=PWR_MLCC_CAP 
GROUP=PWR_MLCC_CAP 
GROUP=PWR_MLCC_CAP 
X6S 
GROUP=PWR_MLCC_CAP 
GROUP=PWR_MLCC_CAP 
GROUP=PWR_MLCC_CAP 
GROUP=PWR_MLCC_CAP 
GROUP=PWR_MLCC_CAP 
GROUP=PWR_MLCC_CAP 
4V 
GROUP=PWR_MLCC_CAP 
GROUP=PWR_MLCC_CAP 
GROUP=PWR_MCP_CAP 
GROUP=PWR_MCP_CAP 
GROUP=PWR_MCP_CAP 
GROUP=PWR_MCP_CAP GROUP=PWR_MCP_CAP 
GROUP=PWR_MCP_CAP 
GROUP=PWR_MCP_CAP 
GROUP=PWR_MCP_CAP 
602433-112 
602433-112 
602433-112 
602433-112 
602433-112 
602433-112 
602433-112 
602433-112 
602433-112 
602433-112 
602433-112 
602433-112 
602433-112 
602433-112 
602433-112 
602433-112 
602433-112 
C95333-006 C95333-006 
C95333-006 
C95333-006 
C95333-006 
C95333-006 
C95333-006 
C95333-006 
C95333-006 
C95333-006 
C95333-006 
C95333-006 
C95333-006 
C95333-006 
C95333-006 
C95333-006 C95333-006 
DESIGN NOTE: 
DESIGN NOTE: 
2
1
2
1
2
11 1
2
1
2
1
1
22 2
DO NOT SCALE DRAWING SHEET 
B
AA
B
B
SIZE 
SCALE: 
234
1234
DEPARTMENT CODE 
1
DOCUMENT NUMBER REV 
PVCCIN_CPU1 
PVSA_CPU1 PVCCIO_CPU1 
PVSA_CPU1 
PVCCIN_CPU1 
PVCCIN_CPU1 
PVCCIO_CPU1 
PVCCIN_CPU1 PVCCIN_CPU1 
PVCCIN_CPU1 PVCCIN_CPU1 
PVCCIN_CPU1 PVCCIN_CPU1 
PVCCIN_CPU1 
PVCCIN_CPU1 
PVCCIN_CPU1 
PVCCIN_CPU1 
PVCCIN_CPU1 
PVMCP: 100UF, 805, 17X 
FULL CAP CONFIG FOR -P SUPPORT. 
PVCCIN: 22UF/603/25X 
PVCCIN: 47UF, 805, 17X 
PVCCIO: 47UF/805/3X, 22UF/603/2X 
PVCCIO: 22UF, 603, 6X 
PVMCP: 22UF, 603, 21X 
FULL CAP CONFIG FOR -P SUPPORT. 
76 OF 270 
Wed Feb 08 16:34:49 2017 
SKT 0 CAVITY (TOP) * TO BE PLACED IN 
* HIGH TEMPERATURE 
CAPACITORS. 
SKT 0 CAVITY (BOTTOM) * TO BE PLACED IN 
CAPACITORS. 
* HIGH TEMPERATURE 
(DEBUG ONLY) 
(DEBUG ONLY) 
REMOVE DURING MASS PRODUCTION 
CPU1 DECOUPLING CAVITY CAPS 
WIWYNN CORPORATION ROOM = PVCCIN_CPU1_DECAP_VR 



M_G_MA<17:0> 
103 
SCONN 
M_G_DQS_DP<17:0> 
20 
287 
228 
M_G_C<2> 
M_GHJ_RST_N 
M_G_PAR 
FM_DIMM_EVENT_COD_N 
FM_ADR_COMPLETE_GHJ_N 
M_G_ALERT_N 
M_G_ACT_N 
TP_CH_G_DIMM_G0_RFU_0 
TP_CH_G_DIMM_G0_RFU_2 
TP_CH_G_DIMM_G0_RFU_1 
M_G_VREF 
SMB_DDR_GHJ_VPP_SCL 
M_G_ODT<3:0> 
M_G_BG<1:0> 
M_G_CKE<3:0> 
M_G_ECC<7:0> 
M_G_CS_N<7:0> 
M_G_BA<1:0> 
M_G_CLK_DP<3:0> 
M_G_CLK_DN<3:0> 
M_G_DQ<63:0> 
M_G_DQS_DN<17:0> 
10 
12 
13 
15 
14 
17 
16 
19 
18 
21 
12 
23 
22 
24 
25 
26 
29 
27 
28 
31 
14 
32 
33 
30 
34 
35 
39 
36 
37 
41 
38 
13 
42 
43 
40 
266 
152 
153 
163 
164 
174 
175 
185 
186 
244 
245 
255 
256 
267 
277 
278 
196 
197 
8
7
19 
18 
30 
29 
41 
40 
100 
99 
111 
110 
122 
121 
133 
132 
52 
51 
SCONN 
H44441-004 
J1G1 
45 
44 
46 
49 
47 
48 
16 
51 
50 
52 
55 
53 
54 
57 
56 
59 
58 
15 
60 
61 
62 
63 
283 
281 
279 
276 
274 
272 
270 
268 
265 
263 
261 
259 
257 
254 
252 
250 
248 
246 
241 
239 
202 
200 
198 
195 
193 
191 
189 
187 
184 
182 
180 
178 
176 
173 
171 
169 
167 
165 
162 
160 
158 
156 
154 
151 
149 
147 
138 
136 
134 
131 
129 
127 
125 
123 
116 
114 
112 
109 
107 
105 
101 
98 
96 
94 
57 
55 
53 
50 
46 
44 
42 
39 
37 
35 
33 
31 
28 
26 
24 
22 
20 
17 
15 
13 
11 
9
6
4
2
SCONN 
H44441-004 
J1G1 
243 
118 
120 
48 
0
1
17 
0
3
1
2
5
4
3
2
5
4
17 
6
8
7
6
9
10 
7
8
10 
9
11 
X7R 
25V 
0402V 
10% 
0.01UF 
A36096-045 
C1F22 
SMB_DDR_GHJ_VPP_SDA 
145 
1
236 
233 
231 
229 
223 
220 
217 
215 
212 
209 
206 
204 
92 
90 
88 
85 
83 
80 
76 
73 
70 
67 
64 
61 
59 
286 
288 
143 
142 
221 
77 
SCONN 
H44441-004 
J1G1 
226 
0
1
0
1
0
1
2
3
0
1
0
1
13 
1
2
3
0
5
4
12 
7
6
0
1
0
1
11 
0
1
2
3
4
5
7
8
6
9
16 
10 
12 
13 
11 
14 
15 
16 
17 
128 
79 
72 
216 
71 
214 
213 
69 
211 
68 
66 
225 
210 
65 
232 
86 
82 
234 
62 
208 
81 
224 
63 
207 
235 
49 
194 
56 
201 
47 
192 
54 
199 
75 
74 
219 
218 
60 
203 
5
12 
157 
3
148 
10 
155 
16 
161 
23 
168 
14 
159 
21 
166 
27 
172 
34 
179 
25 
170 
32 
177 
38 
183 
45 
190 
36 
181 
43 
188 
97 
242 
104 
249 
95 
240 
102 
247 
108 
253 
115 
260 
106 
251 
113 
258 
119 
264 
126 
271 
117 
262 
124 
269 
130 
275 
137 
282 
273 
135 
280 
78 
87 
91 
222 
58 
205 
227 
144 
84 
89 
93 
237 
139 
140 
238 
230 
141 
285 
284 
146 
H44441-004 
J1G1 
150 
3
15 
1
0
4
5
2
6
7
9
8
11 
14 
57 78 
57 78 
57 78 
55 78 79 80 81 82 
57 78 
43 44 45 46 47 48 49 50 51 52 
53 54 78 79 80 81 82 83 84 85 
86 87 88 94 
89 78 79 80 81 
82 
78 57 
57 78 
100 78 
99 78 79 80 81 82 
57 78 
57 78 
57 78 
57 78 
57 78 
57 78 
57 78 
57 78 
57 78 
57 78 
78 79 80 81 82 99 
BOM NOTE: 
DO NOT SCALE DRAWING 
SCONN288_H44441004 
SCONN288_H44441004 
SCONN288_H44441004 
SCONN288_H44441004 
Wed Feb 08 16:34:50 2017 
SHEET 
B
AA
B
B
SIZE 
SCALE: 
234
1234
DEPARTMENT CODE 
1
DOCUMENT NUMBER REV 
BI 
BI 
P12V_NVDIMM_GHJ 
IN 
PVPP_GHJ 
PVPP_GHJ 
IN 
OUT 
IN 
IN 
BI 
PVTT_GHJ 
IN 
IN 
IN 
PVDDQ_GHJ 
IN 
IN 
BI 
IN 
OUT 
IN 
IN 
IN 
IN 
IN 
BI 
77 OF 270 
DQS9P DQS9N DQS8P DQS8N DQS7P DQS7N DQS6P DQS6N DQS5P DQS5N DQS4P DQS4N DQS3P 
DQS3N DQS2P DQS2N DQS1P DQS1N 
DQS17P DQS17N DQS16P 
DQS16N DQS15P DQS15N DQS14P DQS14N DQS13P DQS13N DQS12P DQS12N DQS11P DQS11N DQS10P DQS10N 
DQS0P DQS0N 
VSS<0> 
VSS<1> VSS<2> VSS<3> VSS<4> VSS<5> VSS<6> VSS<7> VSS<8> VSS<9> VSS<10> VSS<11> VSS<12> 
VSS<13> VSS<14> VSS<15> VSS<16> VSS<17> VSS<18> VSS<19> VSS<20> VSS<21> VSS<22> VSS<23> VSS<24> VSS<25> 
VSS<26> VSS<27> VSS<28> VSS<29> VSS<30> VSS<31> VSS<32> VSS<33> VSS<34> VSS<35> VSS<36> VSS<37> VSS<38> 
VSS<39> VSS<40> VSS<41> VSS<42> VSS<43> VSS<44> 
VSS<47> 
VSS<48> VSS<49> VSS<50> VSS<51> VSS<52> VSS<53> VSS<54> VSS<55> VSS<56> VSS<57> VSS<58> VSS<59> 
VSS<60> VSS<61> VSS<62> VSS<63> VSS<64> VSS<65> VSS<66> VSS<67> 
VSS<84> VSS<85> 
VSS<86> VSS<87> VSS<88> VSS<89> VSS<90> VSS<91> VSS<92> VSS<93> 
VSS<68> VSS<69> VSS<70> VSS<71> VSS<72> 
VSS<73> VSS<74> VSS<75> VSS<76> VSS<77> VSS<78> VSS<79> VSS<80> VSS<81> VSS<82> VSS<83> 
VSS<45> VSS<46> 
12V<0> VPP<2> 
VPP<4> 
VTT<0> VTT<1> 
VPP<0> VPP<1> 
VDD<0> VDD<1> VDD<2> VDD<3> VDD<4> VDD<5> VDD<6> VDD<7> VDD<8> VDD<9> VDD<10> VDD<11> 
VDD<12> VDD<13> VDD<14> VDD<15> VDD<16> VDD<17> VDD<18> VDD<19> VDD<20> VDD<21> VDD<22> VDD<23> VDD<24> 
VDD<25> 
12V<1> VPP<3> 
BA<1> 
BA<0> DQ<42> 
DQ<29> 
CK0N CK0P CK1N CK1P 
BG<0> 
SAVE_N_NC 
RFU<0> RFU<1> 
RESET_N PAR 
EVENT_N 
DQ<0> 
DQ<3> DQ<4> DQ<5> 
DQ<13> DQ<14> DQ<15> DQ<16> DQ<17> 
DQ<20> 
DQ<22> DQ<23> DQ<24> DQ<25> DQ<26> 
DQ<30> 
DQ<39> DQ<40> 
DQ<43> 
DQ<46> DQ<47> 
DQ<48> DQ<49> 
DQ<52> DQ<53> DQ<54> DQ<55> DQ<56> DQ<57> 
DQ<59> 
DQ<61> DQ<62> DQ<63> 
CB<0> CB<1> 
CB<6> 
CB<7> 
C<2> 
BG<1> 
A9 
A5 
A4 
A3 
A14_WE_N 
A13 
A12 
A11 
A10 
A1 
A0 
DQ<38> 
DQ<37> 
DQ<36> 
DQ<35> 
DQ<34> 
DQ<33> 
DQ<32> 
DQ<31> 
RFU<2> 
DQ<2> 
DQ<1> 
VDDSPD 
SA<2> 
SA<1> 
SA<0> 
SDA 
SCL 
VREFCA 
ACT_N ALERT_N 
A2 
DQ<51> 
DQ<41> 
DQ<44> DQ<45> 
A6 A7 A8 
CB<2> CB<3> CB<4> CB<5> 
DQ<28> 
DQ<27> 
DQ<18> DQ<19> 
DQ<21> 
ODT<0> ODT<1> 
CKE<0> CKE<1> 
S0_N S1_N S2_N_C<0> S3_N_C<1> 
DQ<50> 
DQ<58> 
DQ<60> A15_CAS_N A16_RAS_N A17 
DQ<6> DQ<7> DQ<8> 
DQ<9> DQ<10> DQ<11> DQ<12> 
PVDDQ (SINGLE SIDE) CAP: 10UF X1, 22UF X50 
PVDDQ (DOUBLE SIDE) CAP: 100UF X8, 47UF X41 
PVTT CAP: 100UF X2, 47UF X1 PVPP CAP: 10UF X12 
STUFF FOR SKU A & B 
CPU1 DDR4 CH G DIMM0 
CAP BETWEEN DIMM 
WIWYNN CORPORATION 
PLACE CAP NEAR DIMM CONNECTOR 
SMBUS ADDR: 0XA0 
2/4 
3/4 4/4 
1/4 



123 
M_G_MA<17:0> 
115 
101 
SCONN 
M_G_DQ<63:0> 
11 
160 
4
103 
86 
M_G_C<2> 
M_GHJ_RST_N 
M_G_PAR 
SMB_DDR_GHJ_VPP_SCL 
FM_DIMM_EVENT_COD_N 
FM_ADR_COMPLETE_GHJ_N 
TP_CH_G_DIMM0_RFU_1 
TP_CH_G_DIMM0_RFU_0 
TP_CH_G_DIMM0_RFU_2 
M_G_ALERT_N 
M_G_ACT_N 
M_G_VREF 
M_G_ECC<7:0> 
M_G_ODT<3:0> 
M_G_CKE<3:0> 
M_G_CLK_DP<3:0> 
M_G_CS_N<7:0> 
M_G_CLK_DN<3:0> 
M_G_BG<1:0> 
M_G_BA<1:0> 
M_G_DQS_DP<17:0> 
M_G_DQS_DN<17:0> 
38 
36 
34 
35 
31 
33 
32 
30 
29 
26 
27 
28 
24 
25 
21 
22 
23 
20 
19 
18 
16 
17 
145 
1
236 
233 
231 
229 
226 
223 
220 
217 
215 
212 
209 
206 
204 
92 
90 
88 
85 
83 
80 
76 
73 
70 
67 
64 
61 
59 
287 
286 
288 
143 
142 
221 
77 
SCONN 
H44441-003 
J9T1 
15 
14 
12 
11 
13 
10 
9
8
7
6
3
4
5
2
1
0
10 
8
9
7
6
5
3
4
1
2
0
1
1
0
0
3
2
2
3
7
5
6
4
3
2
2
3
6
7
4
5
3
2
1
X7R 
25V 
0402V 
10% 
0.01UF 
A36096-045 
C9T7 
16 
17 
14 
15 
17 
16 
15 
14 
13 
12 
13 
11 
8
10 
9
12 
11 
9
10 
8
6
7
5
3
7
5
6
4
3
2
1
0
2
0
1
J9T1 
SCONN 
283 
281 
279 
276 
274 
272 
270 
268 
265 
263 
261 
259 
257 
254 
252 
250 
248 
246 
243 
241 
239 
202 
200 
198 
195 
193 
191 
189 
187 
184 
182 
180 
178 
176 
173 
171 
169 
167 
165 
162 
158 
156 
154 
151 
149 
147 
138 
136 
134 
131 
129 
127 
125 
120 
118 
116 
114 
112 
109 
107 
105 
98 
96 
94 
57 
55 
53 
50 
48 
46 
44 
42 
39 
37 
35 
33 
31 
28 
26 
24 
22 
20 
17 
15 
13 
9
6
4
2
H44441-003 
63 
62 
60 
61 
59 
57 
58 
J9T1 
79 
72 
216 
71 
214 
213 
69 
211 
68 
66 
225 
210 
65 
232 
228 
82 
234 
62 
208 
81 
224 
63 
207 
235 
49 
194 
56 
201 
47 
192 
54 
199 
75 
74 
219 
218 
60 
203 
5
150 
12 
157 
3
148 
10 
155 
16 
161 
23 
168 
14 
159 
21 
166 
27 
172 
34 
179 
25 
170 
32 
177 
38 
183 
45 
190 
36 
181 
43 
188 
97 
242 
104 
249 
95 
240 
102 
247 
108 
253 
260 
106 
251 
113 
258 
119 
264 
126 
271 
117 
262 
124 
269 
130 
275 
137 
282 
128 
273 
135 
280 
78 
87 
91 
222 
58 
205 
227 
144 
84 
89 
93 
237 
139 
140 
238 
230 
141 
285 
284 
146 
H44441-003 
16 
17 
13 
14 
15 
12 
11 
152 
153 
163 
164 
174 
175 
185 
186 
244 
245 
255 
256 
266 
267 
277 
278 
196 
197 
8
7
19 
18 
30 
29 
41 
40 
100 
99 
111 
110 
122 
121 
133 
132 
52 
51 
SCONN 
H44441-003 
J9T1 
0
56 
55 
52 
53 
54 
51 
50 
49 
47 
48 
46 
45 
44 
43 
42 
40 
39 
41 
37 
SMB_DDR_GHJ_VPP_SDA 
57 77 57 77 
57 77 
55 77 79 80 81 82 
57 77 
99 77 79 80 81 82 
43 44 45 46 47 48 49 50 51 52 
53 54 77 79 80 81 82 83 84 85 
86 87 88 94 
89 77 79 80 81 
82 
77 57 
57 77 
100 77 
57 77 
57 77 
57 77 
57 77 
57 77 
57 77 
57 77 
57 77 
57 77 
57 77 
77 79 80 81 82 99 
BOM NOTE: 
DO NOT SCALE DRAWING 
SCONN288_H44441003 
SCONN288_H44441003 
SCONN288_H44441003 
SCONN288_H44441003 
SHEET 
B
AA
B
B
SIZE 
SCALE: 
234
1234
DEPARTMENT CODE 
1
DOCUMENT NUMBER REV 
PVTT_GHJ 
PVDDQ_GHJ 
IN 
IN 
OUT 
OUT 
PVPP_GHJ 
IN 
IN 
IN 
IN 
IN 
IN 
IN P12V_NVDIMM_GHJ 
BI 
BI 
IN 
IN 
IN 
BI 
BI 
IN 
IN 
PVPP_GHJ 
IN 
BI 
78 OF 270 
Wed Feb 08 16:34:50 2017 
VDD<25> 
VDD<24> 
VDD<23> 
VDD<22> 
VDD<21> 
VDD<20> 
VDD<19> 
VDD<18> 
VDD<17> 
VDD<16> 
VDD<15> 
VDD<14> 
VDD<13> 
VDD<12> 
VDD<11> 
VDD<10> 
VDD<9> 
VDD<8> 
VDD<7> 
VDD<6> 
VDD<5> 
VDD<4> 
VDD<3> 
VDD<2> 
VDD<1> 
VDD<0> 
VPP<1> 
VPP<0> 
VTT<1> 
VTT<0> 
VPP<4> 
VPP<3> 
VPP<2> 12V<0> 12V<1> VSS<83> 
VSS<82> 
VSS<81> 
VSS<80> 
VSS<79> 
VSS<78> 
VSS<77> 
VSS<76> 
VSS<75> 
VSS<74> 
VSS<73> 
VSS<72> 
VSS<71> 
VSS<70> 
VSS<69> 
VSS<68> 
VSS<93> 
VSS<92> 
VSS<91> 
VSS<90> 
VSS<89> 
VSS<88> 
VSS<87> 
VSS<86> 
VSS<85> 
VSS<84> 
VSS<67> 
VSS<66> 
VSS<65> 
VSS<64> 
VSS<63> 
VSS<62> 
VSS<61> 
VSS<60> 
VSS<59> 
VSS<58> 
VSS<57> 
VSS<56> 
VSS<55> 
VSS<54> 
VSS<53> 
VSS<52> 
VSS<51> 
VSS<50> 
VSS<49> 
VSS<48> 
VSS<47> 
VSS<46> 
VSS<45> 
VSS<44> 
VSS<43> 
VSS<42> 
VSS<41> 
VSS<40> 
VSS<39> 
VSS<38> 
VSS<37> 
VSS<36> 
VSS<35> 
VSS<34> 
VSS<33> 
VSS<32> 
VSS<31> 
VSS<30> 
VSS<29> 
VSS<28> 
VSS<27> 
VSS<26> 
VSS<25> 
VSS<24> 
VSS<23> 
VSS<22> 
VSS<21> 
VSS<20> 
VSS<19> 
VSS<18> 
VSS<17> 
VSS<16> 
VSS<15> 
VSS<14> 
VSS<13> 
VSS<12> 
VSS<11> 
VSS<10> VSS<9> 
VSS<8> 
VSS<7> 
VSS<6> 
VSS<5> 
VSS<4> 
VSS<3> 
VSS<2> 
VSS<1> 
VSS<0> 
DQ<12> 
DQ<11> 
DQ<10> DQ<9> 
DQ<8> 
DQ<7> 
DQ<6> 
A17 
A16_RAS_N 
A15_CAS_N 
DQ<60> 
DQ<58> 
DQ<50> 
S3_N_C<1> 
S2_N_C<0> 
S1_N 
S0_N 
CKE<1> 
CKE<0> 
ODT<1> 
ODT<0> 
DQ<21> 
DQ<19> 
DQ<18> 
DQ<27> DQ<28> 
CB<5> 
CB<4> 
CB<3> 
CB<2> 
A8 
A7 
A6 
DQ<45> 
DQ<44> 
DQ<41> 
DQ<51> 
A2 
ALERT_N 
ACT_N 
VREFCA 
SCL SDA SA<0> SA<1> SA<2> VDDSPD 
DQ<1> DQ<2> 
RFU<2> 
DQ<31> DQ<32> DQ<33> DQ<34> 
DQ<35> DQ<36> DQ<37> DQ<38> 
A0 A1 
A10 A11 A12 A13 A14_WE_N 
A3 A4 A5 
A9 
BG<1> 
C<2> 
CB<7> 
CB<6> 
CB<1> 
CB<0> 
DQ<63> 
DQ<62> 
DQ<61> 
DQ<59> 
DQ<57> 
DQ<56> 
DQ<55> 
DQ<54> 
DQ<53> 
DQ<52> 
DQ<49> 
DQ<48> 
DQ<47> 
DQ<46> 
DQ<43> 
DQ<40> 
DQ<39> 
DQ<30> 
DQ<26> 
DQ<25> 
DQ<24> 
DQ<23> 
DQ<22> 
DQ<20> 
DQ<17> 
DQ<16> 
DQ<15> 
DQ<14> 
DQ<13> 
DQ<5> 
DQ<4> 
DQ<3> 
DQ<0> 
EVENT_N 
PAR 
RESET_N 
RFU<1> 
RFU<0> 
SAVE_N_NC 
BG<0> 
CK1P 
CK1N 
CK0P 
CK0N 
DQ<29> 
DQ<42> BA<0> BA<1> 
DQS0N DQS0P 
DQS10N DQS10P DQS11N DQS11P DQS12N DQS12P DQS13N DQS13P DQS14N DQS14P DQS15N DQS15P DQS16N 
DQS16P DQS17N DQS17P 
DQS1N DQS1P DQS2N DQS2P DQS3N DQS3P 
DQS4N DQS4P DQS5N DQS5P DQS6N DQS6P DQS7N DQS7P DQS8N DQS8P DQS9N DQS9P 
PVDDQ (SINGLE SIDE) CAP: 10UF X1, 22UF X50 
PVDDQ (DOUBLE SIDE) CAP: 100UF X8, 47UF X41 
PVPP CAP: 10UF X12 
PVTT CAP: 100UF X2, 47UF X1 
BOM_SS=NOPOP 
BOM_SS=NOPOP 
BOM_SS=NOPOP 
BOM_SS=NOPOP 
UNSTUFF FOR SKU B 
CPU1 DDR4 CH G DIMM1 
CAP BETWEEN DIMM 
SMBUS ADDR: 0XA2 
PLACE CAP NEAR DIMM CONNECTOR 
WIWYNN CORPORATION 
4/4 3/4 1/4 
2/4 



282 
137 
275 
57 
54 
164 
24 
M_H_MA<17:0> 
175 
43 
M_H_C<2> 
M_GHJ_RST_N 
FM_DIMM_EVENT_COD_N 
M_H_PAR 
M_H_ALERT_N 
M_H_ACT_N 
FM_ADR_COMPLETE_GHJ_N 
SMB_DDR_GHJ_VPP_SCL 
TP_CH_H_DIMM_H0_RFU_2 
TP_CH_H_DIMM_H0_RFU_0 
TP_CH_H_DIMM_H0_RFU_1 
M_H_VREF 
M_H_ODT<3:0> 
M_H_ECC<7:0> 
M_H_CKE<3:0> 
M_H_CS_N<7:0> 
M_H_CLK_DN<3:0> 
M_H_CLK_DP<3:0> 
M_H_BG<1:0> 
M_H_BA<1:0> 
M_H_DQ<63:0> 
M_H_DQS_DN<17:0> 
M_H_DQS_DP<17:0> 
14 
15 
13 
12 
10 
21 
18 
19 
16 
17 
17 
25 
24 
20 
22 
23 
31 
28 
27 
29 
26 
16 
35 
34 
30 
33 
32 
38 
41 
37 
36 
39 
13 
44 
45 
40 
43 
42 
256 
152 
153 
163 
174 
185 
186 
244 
245 
255 
266 
267 
277 
278 
196 
197 
8
7
19 
18 
30 
29 
41 
40 
100 
99 
111 
110 
122 
121 
133 
132 
52 
51 
SCONN 
H44441-004 
J1G2 
50 
51 
48 
47 
14 
49 
46 
53 
55 
52 
56 
59 
58 
15 
60 
61 
62 
63 
283 
281 
279 
276 
274 
272 
270 
268 
265 
263 
261 
259 
257 
254 
252 
250 
248 
246 
243 
241 
239 
202 
200 
198 
195 
193 
191 
189 
187 
184 
182 
180 
178 
176 
173 
171 
169 
167 
165 
162 
160 
158 
156 
154 
151 
149 
147 
138 
136 
134 
131 
129 
127 
125 
123 
120 
118 
116 
114 
107 
105 
103 
101 
98 
96 
94 
57 
55 
53 
50 
48 
46 
44 
42 
39 
37 
35 
33 
31 
28 
26 
22 
20 
17 
15 
13 
11 
9
6
4
2
SCONN 
H44441-004 
J1G2 
112 
109 
1
16 
0
2
1
2
3
4
5
6
4
3
17 
5
6
7
7
8
9
10 
11 
9
8
10 
0
11 
X7R 
25V 
0402V 
10% 
0.01UF 
A36096-045 
C9U7 
SMB_DDR_GHJ_VPP_SDA 
12 
145 
1
236 
233 
231 
229 
226 
223 
220 
217 
215 
212 
209 
206 
204 
92 
90 
88 
85 
83 
80 
76 
73 
70 
67 
64 
61 
59 
287 
286 
288 
143 
142 
221 
77 
SCONN 
J1G2 
H44441-004 
0
1
0
1
0
1
2
3
0
1
0
1
1
3
0
2
5
4
6
7
1
0
0
1
12 
1
0
2
4
3
5
7
6
8
9
13 
10 
12 
11 
13 
14 
15 
17 
16 
117 
262 
79 
72 
216 
71 
214 
213 
69 
211 
68 
66 
225 
210 
65 
232 
228 
86 
82 
234 
62 
208 
81 
224 
63 
207 
235 
49 
194 
56 
201 
47 
192 
54 
199 
75 
74 
219 
218 
60 
203 
5
150 
12 
157 
3
148 
10 
155 
16 
161 
23 
168 
14 
159 
21 
166 
27 
172 
34 
179 
25 
170 
32 
177 
38 
183 
45 
190 
36 
181 
188 
97 
242 
104 
249 
95 
240 
102 
247 
108 
253 
115 
260 
106 
251 
113 
258 
119 
264 
126 
271 
124 
269 
130 
128 
273 
135 
280 
78 
87 
91 
222 
58 
205 
227 
144 
84 
89 
93 
237 
139 
140 
238 
230 
141 
285 
146 
SCONN 
H44441-004 
J1G2 
284 
3
14 
1
0
5
2
11 
8
9
7
6
4
15 
58 80 
58 80 
55 77 78 80 81 82 
43 44 45 46 47 48 49 50 51 
52 53 54 77 78 80 81 82 83 
84 85 86 87 88 94 
58 80 
80 58 
58 80 
89 77 78 80 
81 82 
99 77 78 80 81 82 
100 80 
58 80 
58 80 
58 80 
58 80 
58 80 
58 80 
58 80 
58 80 
58 80 
58 80 
58 80 
77 78 80 81 82 99 
BOM NOTE: 
DO NOT SCALE DRAWING 
SCONN288_H44441004 
SCONN288_H44441004 
SCONN288_H44441004 
SCONN288_H44441004 
SHEET 
B
AA
B
B
SIZE 
SCALE: 
234
1234
DEPARTMENT CODE 
1
DOCUMENT NUMBER REV 
BI 
BI 
P12V_NVDIMM_GHJ 
IN 
PVPP_GHJ 
PVPP_GHJ 
OUT 
IN 
BI 
IN 
IN 
IN 
IN 
PVTT_GHJ 
IN 
IN 
BI 
IN 
OUT 
IN 
IN 
PVDDQ_GHJ 
IN 
IN 
IN 
IN 
BI 
79 OF 270 
DQS9P DQS9N DQS8P DQS8N DQS7P DQS7N DQS6P DQS6N DQS5P DQS5N DQS4P DQS4N 
DQS3P DQS3N DQS2P DQS2N DQS1P DQS1N 
DQS17P DQS17N DQS16P 
DQS16N DQS15P DQS15N DQS14P DQS14N DQS13P DQS13N DQS12P DQS12N DQS11P DQS11N DQS10P DQS10N 
DQS0P DQS0N 
VSS<0> VSS<1> VSS<2> VSS<3> VSS<4> VSS<5> VSS<6> VSS<7> VSS<8> VSS<9> VSS<10> VSS<11> 
VSS<12> VSS<13> VSS<14> VSS<15> VSS<16> VSS<17> VSS<18> VSS<19> VSS<20> VSS<21> VSS<22> VSS<23> VSS<24> 
VSS<25> VSS<26> VSS<27> VSS<28> VSS<29> VSS<30> VSS<31> VSS<32> VSS<33> VSS<34> VSS<35> VSS<36> VSS<37> 
VSS<38> VSS<39> VSS<40> VSS<41> VSS<42> VSS<43> VSS<44> 
VSS<47> VSS<48> VSS<49> VSS<50> VSS<51> VSS<52> VSS<53> VSS<54> VSS<55> VSS<56> VSS<57> VSS<58> 
VSS<59> VSS<60> VSS<61> VSS<62> VSS<63> VSS<64> VSS<65> VSS<66> VSS<67> 
VSS<84> 
VSS<85> VSS<86> VSS<87> VSS<88> VSS<89> VSS<90> VSS<91> VSS<92> VSS<93> 
VSS<68> VSS<69> VSS<70> VSS<71> 
VSS<72> VSS<73> VSS<74> VSS<75> VSS<76> VSS<77> VSS<78> VSS<79> VSS<80> VSS<81> VSS<82> VSS<83> 
VSS<45> VSS<46> 
12V<0> VPP<2> 
VPP<4> 
VTT<0> VTT<1> 
VPP<0> VPP<1> 
VDD<0> 
VDD<1> VDD<2> VDD<3> VDD<4> VDD<5> VDD<6> VDD<7> VDD<8> VDD<9> VDD<10> VDD<11> VDD<12> VDD<13> 
VDD<14> VDD<15> VDD<16> VDD<17> VDD<18> VDD<19> VDD<20> VDD<21> VDD<22> VDD<23> VDD<24> VDD<25> 
12V<1> VPP<3> 
BA<1> 
BA<0> DQ<42> 
DQ<29> 
CK0N CK0P CK1N CK1P 
BG<0> 
SAVE_N_NC 
RFU<0> RFU<1> 
RESET_N PAR 
EVENT_N 
DQ<0> 
DQ<3> DQ<4> DQ<5> 
DQ<13> DQ<14> 
DQ<15> DQ<16> DQ<17> 
DQ<20> 
DQ<22> DQ<23> DQ<24> DQ<25> DQ<26> 
DQ<30> 
DQ<39> DQ<40> 
DQ<43> 
DQ<46> DQ<47> DQ<48> DQ<49> 
DQ<52> 
DQ<53> DQ<54> DQ<55> DQ<56> DQ<57> 
DQ<59> 
DQ<61> DQ<62> DQ<63> 
CB<0> CB<1> 
CB<6> CB<7> 
C<2> 
BG<1> 
A9 
A5 
A4 
A3 
A14_WE_N 
A13 
A12 
A11 
A10 
A1 
A0 
DQ<38> 
DQ<37> 
DQ<36> 
DQ<35> 
DQ<34> 
DQ<33> 
DQ<32> 
DQ<31> 
RFU<2> 
DQ<2> 
DQ<1> 
VDDSPD 
SA<2> 
SA<1> 
SA<0> 
SDA 
SCL 
VREFCA 
ACT_N ALERT_N 
A2 
DQ<51> 
DQ<41> 
DQ<44> DQ<45> 
A6 
A7 A8 
CB<2> CB<3> CB<4> CB<5> 
DQ<28> 
DQ<27> 
DQ<18> DQ<19> 
DQ<21> 
ODT<0> ODT<1> 
CKE<0> 
CKE<1> 
S0_N S1_N S2_N_C<0> S3_N_C<1> 
DQ<50> 
DQ<58> 
DQ<60> A15_CAS_N A16_RAS_N A17 
DQ<6> DQ<7> DQ<8> DQ<9> DQ<10> DQ<11> DQ<12> 
PVDDQ (SINGLE SIDE) CAP: 10UF X1, 22UF X50 
PVDDQ (DOUBLE SIDE) CAP: 100UF X8, 47UF X41 
PVTT CAP: 100UF X2, 47UF X1 PVPP CAP: 10UF X12 
Wed Feb 08 16:34:50 2017 
STUFF FOR SKU A & B 
CPU1 DDR4 CH H DIMM0 
CAP BETWEEN DIMM 
PLACE CAP NEAR DIMM CONNECTOR 
WIWYNN CORPORATION SMBUS ADDR: 0XA4 
2/4 
3/4 4/4 
1/4 



277 
103 
TP_CH_H_DIMM0_RFU_2 
128 
59 
58 
6
J9U1 
M_H_DQ<63:0> 
33 
180 
185 
142 
104 
105 
280 
135 
275 
18 
188 
M_H_C<2> 
M_GHJ_RST_N 
M_H_PAR 
M_H_ALERT_N 
SMB_DDR_GHJ_VPP_SCL 
FM_ADR_COMPLETE_GHJ_N 
M_H_ACT_N 
TP_CH_H_DIMM0_RFU_1 
TP_CH_H_DIMM0_RFU_0 
M_H_VREF 
FM_DIMM_EVENT_COD_N 
M_H_ECC<7:0> 
M_H_ODT<3:0> 
M_H_CKE<3:0> 
M_H_CS_N<7:0> 
M_H_BG<1:0> 
M_H_BA<1:0> 
M_H_CLK_DP<3:0> 
M_H_CLK_DN<3:0> 
M_H_MA<17:0> 
M_H_DQS_DN<17:0> 
M_H_DQS_DP<17:0> 
46 
44 
42 
43 
40 
41 
39 
37 
38 
35 
36 
34 
32 
33 
30 
31 
29 
28 
27 
24 
25 
26 
23 
22 
20 
19 
21 
SMB_DDR_GHJ_VPP_SDA 
18 
17 
15 
14 
16 
12 
13 
11 
10 
9
8
6
7
145 
1
236 
233 
231 
229 
226 
223 
220 
217 
215 
212 
209 
206 
204 
92 
90 
88 
85 
83 
80 
76 
73 
70 
67 
64 
61 
59 
287 
286 
288 
143 
221 
77 
SCONN 
H44441-003 
J9U1 
4
5
2
1
3
0
0
1
1
0
0
2
3
6
7
4
5
2
3
3
2
3
2
7
6
4
X7R 
25V 
0402V 
10% 
0.01UF 
A36096-045 
C1G10 
5
2
3
1
0
262 
258 
137 
130 
124 
79 
72 
216 
71 
214 
213 
69 
211 
68 
66 
225 
210 
65 
232 
228 
86 
82 
62 
208 
81 
224 
63 
207 
235 
49 
194 
56 
201 
47 
192 
54 
199 
75 
74 
219 
218 
60 
203 
5
150 
12 
157 
3
148 
10 
155 
16 
161 
23 
168 
14 
159 
21 
166 
27 
172 
34 
179 
25 
170 
32 
177 
38 
183 
45 
190 
36 
181 
43 
97 
242 
249 
95 
240 
102 
247 
108 
253 
115 
260 
106 
251 
113 
119 
264 
126 
271 
117 
269 
282 
273 
78 
87 
91 
222 
58 
205 
227 
144 
84 
89 
93 
237 
139 
140 
238 
230 
141 
285 
284 
146 
SCONN 
H44441-003 
234 
17 
17 
16 
15 
14 
13 
16 
15 
12 
13 
14 
12 
11 
10 
9
7
8
10 
11 
8
7
9
5
4
2
3
4
5
6
3
2
1
0
0
1
149 
171 
11 
191 
283 
281 
279 
276 
274 
272 
270 
268 
265 
263 
261 
259 
257 
254 
252 
250 
248 
246 
243 
241 
239 
202 
200 
198 
195 
193 
189 
187 
184 
182 
178 
176 
173 
169 
167 
165 
162 
160 
158 
156 
154 
151 
147 
138 
136 
134 
131 
129 
127 
125 
123 
120 
118 
116 
114 
112 
109 
107 
101 
98 
96 
94 
57 
55 
53 
50 
48 
46 
44 
42 
39 
37 
35 
31 
28 
26 
24 
22 
20 
17 
15 
13 
9
6
4
2
SCONN 
H44441-003 
J9U1 
63 
61 
60 
62 
56 
55 
57 
54 
53 
51 
50 
52 
49 
48 
47 
17 
16 
14 
15 
13 
12 
11 
9
10 
7
8
6
4
5
3
2
1
163 
244 
152 
153 
164 
174 
175 
186 
245 
255 
256 
266 
267 
278 
196 
197 
8
7
19 
30 
29 
41 
40 
100 
99 
111 
110 
122 
121 
133 
132 
52 
51 
SCONN 
H44441-003 
J9U1 
45 
58 79 
58 79 
55 77 78 79 81 82 
58 79 
79 58 
99 77 78 79 81 82 
89 77 78 79 81 
82 
58 79 
100 79 
43 44 45 46 47 48 49 50 51 52 
53 54 77 78 79 81 82 83 84 85 
86 87 88 94 
58 79 
58 79 
58 79 
58 79 
58 79 
58 79 
58 79 
58 79 
58 79 
58 79 
58 79 
77 78 79 81 82 99 
BOM NOTE: 
DO NOT SCALE DRAWING 
SCONN288_H44441003 
SCONN288_H44441003 
SCONN288_H44441003 
SCONN288_H44441003 
SHEET 
B
AA
B
B
SIZE 
SCALE: 
234
1234
DEPARTMENT CODE 
1
DOCUMENT NUMBER REV 
OUT 
PVPP_GHJ 
PVPP_GHJ 
PVTT_GHJ 
PVDDQ_GHJ 
BI 
IN 
IN 
IN 
IN 
IN 
IN 
IN 
IN 
P12V_NVDIMM_GHJ 
BI 
IN 
BI 
IN 
IN 
IN 
IN 
BI 
BI 
IN 
OUT 
IN 
80 OF 270 
Wed Feb 08 16:34:51 2017 
VDD<25> 
VDD<24> 
VDD<23> 
VDD<22> 
VDD<21> 
VDD<20> 
VDD<19> 
VDD<18> 
VDD<17> 
VDD<16> 
VDD<15> 
VDD<14> 
VDD<13> 
VDD<12> 
VDD<11> 
VDD<10> 
VDD<9> 
VDD<8> 
VDD<7> 
VDD<6> 
VDD<5> 
VDD<4> 
VDD<3> 
VDD<2> 
VDD<1> 
VDD<0> 
VPP<1> 
VPP<0> 
VTT<1> 
VTT<0> 
VPP<4> 
VPP<3> 
VPP<2> 12V<0> 12V<1> 
DQ<12> 
DQ<11> 
DQ<10> DQ<9> 
DQ<8> 
DQ<7> 
DQ<6> 
A17 
A16_RAS_N 
A15_CAS_N DQ<60> 
DQ<58> 
DQ<50> 
S3_N_C<1> 
S2_N_C<0> 
S1_N 
S0_N 
CKE<1> 
CKE<0> 
ODT<1> 
ODT<0> 
DQ<21> 
DQ<19> 
DQ<18> 
DQ<27> DQ<28> 
CB<5> 
CB<4> 
CB<3> 
CB<2> 
A8 
A7 
A6 
DQ<45> 
DQ<44> 
DQ<41> 
DQ<51> 
A2 
ALERT_N 
ACT_N 
VREFCA 
SCL 
SDA SA<0> SA<1> SA<2> VDDSPD 
DQ<1> DQ<2> 
RFU<2> 
DQ<31> DQ<32> DQ<33> DQ<34> DQ<35> DQ<36> DQ<37> DQ<38> 
A0 A1 
A10 A11 A12 A13 A14_WE_N 
A3 A4 A5 
A9 
BG<1> 
C<2> 
CB<7> 
CB<6> 
CB<1> 
CB<0> 
DQ<63> 
DQ<62> 
DQ<61> 
DQ<59> 
DQ<57> 
DQ<56> 
DQ<55> 
DQ<54> 
DQ<53> 
DQ<52> 
DQ<49> 
DQ<48> 
DQ<47> 
DQ<46> 
DQ<43> 
DQ<40> 
DQ<39> 
DQ<30> 
DQ<26> 
DQ<25> 
DQ<24> 
DQ<23> 
DQ<22> 
DQ<20> 
DQ<17> 
DQ<16> 
DQ<15> 
DQ<14> 
DQ<13> 
DQ<5> 
DQ<4> 
DQ<3> 
DQ<0> 
EVENT_N 
PAR 
RESET_N 
RFU<1> 
RFU<0> 
SAVE_N_NC 
BG<0> 
CK1P 
CK1N 
CK0P 
CK0N 
DQ<29> 
DQ<42> BA<0> BA<1> 
VSS<83> 
VSS<82> 
VSS<81> 
VSS<80> 
VSS<79> 
VSS<78> 
VSS<77> 
VSS<76> 
VSS<75> 
VSS<74> 
VSS<73> 
VSS<72> 
VSS<71> 
VSS<70> 
VSS<69> 
VSS<68> 
VSS<93> 
VSS<92> 
VSS<91> 
VSS<90> 
VSS<89> 
VSS<88> 
VSS<87> 
VSS<86> 
VSS<85> 
VSS<84> 
VSS<67> 
VSS<66> 
VSS<65> 
VSS<64> 
VSS<63> 
VSS<62> 
VSS<61> 
VSS<60> 
VSS<59> 
VSS<58> 
VSS<57> 
VSS<56> 
VSS<55> 
VSS<54> 
VSS<53> 
VSS<52> 
VSS<51> 
VSS<50> 
VSS<49> 
VSS<48> 
VSS<47> 
VSS<46> 
VSS<45> 
VSS<44> 
VSS<43> 
VSS<42> 
VSS<41> 
VSS<40> 
VSS<39> 
VSS<38> 
VSS<37> 
VSS<36> 
VSS<35> 
VSS<34> 
VSS<33> 
VSS<32> 
VSS<31> 
VSS<30> 
VSS<29> 
VSS<28> 
VSS<27> 
VSS<26> 
VSS<25> 
VSS<24> 
VSS<23> 
VSS<22> 
VSS<21> 
VSS<20> 
VSS<19> 
VSS<18> 
VSS<17> 
VSS<16> 
VSS<15> 
VSS<14> 
VSS<13> 
VSS<12> 
VSS<11> 
VSS<10> VSS<9> 
VSS<8> 
VSS<7> 
VSS<6> 
VSS<5> 
VSS<4> 
VSS<3> 
VSS<2> 
VSS<1> 
VSS<0> 
DQS0N DQS0P 
DQS10N 
DQS10P DQS11N DQS11P DQS12N DQS12P DQS13N DQS13P DQS14N DQS14P DQS15N DQS15P DQS16N DQS16P 
DQS17N DQS17P 
DQS1N DQS1P DQS2N DQS2P DQS3N DQS3P DQS4N 
DQS4P DQS5N DQS5P DQS6N DQS6P DQS7N DQS7P DQS8N DQS8P DQS9N DQS9P 
PVDDQ (SINGLE SIDE) CAP: 10UF X1, 22UF X50 PVTT CAP: 100UF X2, 47UF X1 PVPP CAP: 10UF X12 
PVDDQ (DOUBLE SIDE) CAP: 100UF X8, 47UF X41 
BOM_SS=NOPOP 
BOM_SS=NOPOP 
BOM_SS=NOPOP 
BOM_SS=NOPOP 
UNSTUFF FOR SKU B 
CPU1 DDR4 CH H DIMM1 
CAP BETWEEN DIMM 
PLACE CAP NEAR DIMM CONNECTOR 
WIWYNN CORPORATION SMBUS ADDR: 0XA6 
4/4 
1/4 
3/4 
2/4 



M_J_DQ<63:0> 
176 
249 
197 
175 
M_J_ALERT_N 
M_J_C<2> 
M_J_PAR 
M_GHJ_RST_N 
FM_ADR_COMPLETE_GHJ_N 
SMB_DDR_GHJ_VPP_SCL 
TP_CH_J_DIMM_J0_RFU_2 
TP_CH_J_DIMM_J0_RFU_0 
TP_CH_J_DIMM_J0_RFU_1 
M_J_VREF 
FM_DIMM_EVENT_COD_N 
M_J_ACT_N 
M_J_ODT<3:0> 
M_J_CKE<3:0> 
M_J_ECC<7:0> 
M_J_BA<1:0> 
M_J_BG<1:0> 
M_J_CS_N<7:0> 
M_J_CLK_DN<3:0> 
M_J_CLK_DP<3:0> 
M_J_MA<17:0> 
M_J_DQS_DN<17:0> 
M_J_DQS_DP<17:0> 
10 
17 
12 
13 
15 
14 
20 
16 
19 
18 
12 
21 
26 
27 
23 
22 
24 
25 
33 
30 
29 
15 
28 
31 
36 
37 
32 
34 
35 
43 
40 
39 
14 
41 
38 
152 
153 
163 
164 
174 
185 
186 
244 
245 
255 
256 
266 
267 
277 
278 
196 
8
7
19 
18 
30 
29 
41 
40 
100 
99 
111 
110 
122 
121 
133 
132 
52 
51 
SCONN 
H44441-004 
J1G3 
46 
47 
42 
45 
44 
53 
49 
16 
48 
51 
50 
56 
52 
55 
54 
57 
63 
61 
17 
60 
58 
59 
62 
0
2
16 
0
1
5
4
3
1
2
3
4
5
17 
6
7
10 
9
8
6
7
8
10 
9
SCONN 
38 
79 
72 
216 
71 
214 
213 
69 
211 
68 
66 
225 
210 
65 
232 
228 
86 
82 
234 
62 
208 
81 
224 
63 
207 
235 
49 
194 
56 
201 
47 
192 
54 
199 
75 
74 
219 
218 
60 
203 
5
150 
12 
157 
3
148 
10 
155 
16 
161 
23 
168 
14 
159 
21 
166 
27 
172 
34 
179 
25 
170 
32 
177 
183 
45 
190 
36 
181 
43 
188 
97 
242 
104 
95 
240 
102 
247 
108 
253 
115 
260 
106 
251 
113 
258 
119 
264 
126 
271 
117 
262 
124 
269 
130 
275 
137 
282 
128 
273 
135 
280 
78 
87 
91 
222 
58 
205 
227 
144 
84 
89 
93 
237 
139 
140 
238 
230 
141 
285 
284 
146 
H44441-004 
J1G3 
22 
162 
283 
281 
279 
276 
274 
272 
270 
268 
265 
263 
261 
259 
257 
254 
252 
250 
248 
246 
243 
241 
239 
202 
200 
198 
195 
193 
191 
189 
187 
184 
182 
180 
178 
173 
171 
169 
167 
165 
160 
158 
156 
154 
151 
149 
147 
138 
136 
134 
131 
129 
127 
125 
123 
120 
118 
116 
114 
112 
109 
107 
105 
103 
101 
98 
96 
94 
57 
55 
53 
50 
48 
46 
44 
42 
39 
37 
35 
33 
31 
28 
26 
24 
20 
17 
15 
13 
11 
9
6
4
2
SCONN 
H44441-004 
J1G3 
X7R 
25V 
0402V 
10% 
0.01UF 
A36096-045 
C9U10 
SMB_DDR_GHJ_VPP_SDA 
145 
1
236 
233 
231 
229 
226 
223 
220 
217 
215 
212 
209 
206 
204 
92 
90 
88 
85 
83 
80 
76 
73 
70 
67 
64 
61 
59 
287 
286 
288 
143 
142 
221 
77 
SCONN 
H44441-004 
J1G3 
0
1
0
1
0
1
11 
2
3
0
1
0
1
12 
0
1
3
2
5
4
7
15 
6
0
1
0
1
0
14 
1
2
3
4
5
6
7
8
9
10 
13 
11 
12 
13 
14 
15 
16 
17 
1
11 
0
4
7
2
5
3
6
9
8
11 
13 
59 82 
82 59 
59 82 
59 82 
55 77 78 79 80 82 
89 77 78 79 80 
82 
99 77 78 79 80 82 
100 82 
43 44 45 46 47 48 49 50 51 
52 53 54 77 78 79 80 82 83 
84 85 86 87 88 94 
59 82 
59 82 
59 82 
59 82 
59 82 
59 82 
59 82 
59 82 
59 82 
59 82 
59 82 
59 82 
77 78 79 80 82 99 
BOM NOTE: 
DO NOT SCALE DRAWING 
SCONN288_H44441004 
SCONN288_H44441004 
SCONN288_H44441004 
SCONN288_H44441004 
SHEET 
B
AA
B
B
SIZE 
SCALE: 
234
1234
DEPARTMENT CODE 
1
DOCUMENT NUMBER REV 
BI 
BI 
P12V_NVDIMM_GHJ 
IN 
PVPP_GHJ 
PVTT_GHJ 
PVPP_GHJ 
OUT 
IN 
BI 
IN 
PVDDQ_GHJ 
IN 
IN 
IN 
IN 
IN 
OUT 
IN 
IN 
IN 
BI 
IN 
IN 
IN 
IN 
BI 
81 OF 270 
Wed Feb 08 16:34:51 2017 
DQS9P DQS9N DQS8P DQS8N DQS7P DQS7N DQS6P DQS6N DQS5P DQS5N DQS4P DQS4N 
DQS3P DQS3N DQS2P DQS2N DQS1P DQS1N 
DQS17P DQS17N DQS16P 
DQS16N DQS15P DQS15N DQS14P DQS14N DQS13P DQS13N DQS12P DQS12N DQS11P DQS11N DQS10P DQS10N 
DQS0P DQS0N 
BA<1> 
BA<0> 
DQ<42> 
DQ<29> 
CK0N CK0P CK1N CK1P 
BG<0> 
SAVE_N_NC 
RFU<0> RFU<1> 
RESET_N PAR 
EVENT_N 
DQ<0> 
DQ<3> 
DQ<4> DQ<5> 
DQ<13> DQ<14> DQ<15> DQ<16> 
DQ<17> 
DQ<20> 
DQ<22> DQ<23> DQ<24> DQ<25> DQ<26> 
DQ<30> 
DQ<39> DQ<40> 
DQ<43> 
DQ<46> DQ<47> DQ<48> DQ<49> 
DQ<52> DQ<53> DQ<54> 
DQ<55> DQ<56> DQ<57> 
DQ<59> 
DQ<61> DQ<62> DQ<63> 
CB<0> CB<1> 
CB<6> CB<7> 
C<2> 
BG<1> 
A9 
A5 
A4 
A3 
A14_WE_N 
A13 
A12 
A11 
A10 
A1 
A0 
DQ<38> 
DQ<37> 
DQ<36> 
DQ<35> 
DQ<34> 
DQ<33> 
DQ<32> 
DQ<31> 
RFU<2> 
DQ<2> 
DQ<1> 
VDDSPD 
SA<2> 
SA<1> 
SA<0> 
SDA 
SCL 
VREFCA 
ACT_N ALERT_N 
A2 
DQ<51> 
DQ<41> 
DQ<44> DQ<45> 
A6 A7 A8 
CB<2> CB<3> CB<4> CB<5> 
DQ<28> 
DQ<27> 
DQ<18> DQ<19> 
DQ<21> 
ODT<0> ODT<1> 
CKE<0> CKE<1> 
S0_N S1_N S2_N_C<0> S3_N_C<1> 
DQ<50> 
DQ<58> 
DQ<60> A15_CAS_N A16_RAS_N A17 
DQ<6> DQ<7> DQ<8> DQ<9> DQ<10> DQ<11> DQ<12> 
VSS<0> VSS<1> VSS<2> VSS<3> VSS<4> VSS<5> VSS<6> VSS<7> VSS<8> VSS<9> VSS<10> VSS<11> 
VSS<12> VSS<13> VSS<14> VSS<15> VSS<16> VSS<17> VSS<18> VSS<19> VSS<20> VSS<21> VSS<22> VSS<23> VSS<24> 
VSS<25> VSS<26> VSS<27> VSS<28> VSS<29> VSS<30> VSS<31> VSS<32> VSS<33> VSS<34> VSS<35> VSS<36> VSS<37> 
VSS<38> VSS<39> VSS<40> VSS<41> VSS<42> VSS<43> VSS<44> 
VSS<47> VSS<48> VSS<49> VSS<50> VSS<51> VSS<52> VSS<53> VSS<54> VSS<55> VSS<56> VSS<57> VSS<58> 
VSS<59> VSS<60> VSS<61> VSS<62> VSS<63> VSS<64> VSS<65> VSS<66> VSS<67> 
VSS<84> 
VSS<85> VSS<86> VSS<87> VSS<88> VSS<89> VSS<90> VSS<91> VSS<92> VSS<93> 
VSS<68> VSS<69> VSS<70> VSS<71> 
VSS<72> VSS<73> VSS<74> VSS<75> VSS<76> VSS<77> VSS<78> VSS<79> VSS<80> VSS<81> VSS<82> VSS<83> 
VSS<45> VSS<46> 
12V<0> VPP<2> 
VPP<4> 
VTT<0> VTT<1> 
VPP<0> VPP<1> 
VDD<0> 
VDD<1> VDD<2> VDD<3> VDD<4> VDD<5> VDD<6> VDD<7> VDD<8> VDD<9> VDD<10> VDD<11> VDD<12> VDD<13> 
VDD<14> VDD<15> VDD<16> VDD<17> VDD<18> VDD<19> VDD<20> VDD<21> VDD<22> VDD<23> VDD<24> VDD<25> 
12V<1> VPP<3> 
PVDDQ (SINGLE SIDE) CAP: 10UF X1, 22UF X50 
PVDDQ (DOUBLE SIDE) CAP: 100UF X8, 47UF X41 
PVTT CAP: 100UF X2, 47UF X1 PVPP CAP: 10UF X12 
STUFF FOR SKU A & B 
CPU1 DDR4 CH J DIMM0 
CAP BETWEEN DIMM 
WIWYNN CORPORATION 
PLACE CAP NEAR DIMM CONNECTOR 
SMBUS ADDR: 0XA8 
2/4 
1/4 
3/4 4/4 



15 
5
7
6
8
9
10 
3
4
1
0
14 
2
16 
17 
15 
14 
13 
11 
12 
10 
13 
9
8
6
7
5
3
4
2
0
1
12 
1
0
0
1
6
7
5
4
3
1
2
0
3
2
3
2
7
6
5
4
3
2
3
2
12 
J9U2 
H44441-003 
SCONN 
77 
221 
142 
143 
288 
286 
287 
59 
61 
64 
67 
70 
73 
76 
80 
83 
85 
88 
90 
92 
204 
206 
209 
212 
215 
217 
220 
223 
226 
229 
231 
233 
236 
1
145 
SMB_DDR_GHJ_VPP_SDA 
11 
C1G19 
A36096-045 
0.01UF 
10% 
0402V 
25V 
X7R 
J9U2 
H44441-003 
146 
284 
285 
141 
230 
238 
140 
139 
237 
93 
89 
84 
144 
227 
205 
58 
222 
91 
87 
78 
280 
128 
282 
275 
124 
262 
117 
271 
126 
264 
119 
258 
113 
251 
106 
260 
115 
253 
108 
247 
102 
240 
95 
104 
242 
97 
188 
43 
181 
36 
190 
45 
183 
38 
177 
32 
170 
25 
179 
34 
172 
27 
166 
21 
159 
14 
168 
23 
161 
16 
155 
10 
148 
3
157 
12 
150 
5
203 
60 
218 
219 
74 
75 
199 
54 
192 
47 
201 
56 
194 
49 
235 
207 
63 
224 
81 
208 
62 
234 
82 
86 
228 
232 
65 
210 
225 
66 
68 
211 
69 
213 
214 
71 
216 
72 
79 
J9U2 
H44441-003 
SCONN 
2
4
6
9
11 
13 
15 
17 
20 
22 
24 
26 
28 
31 
33 
35 
37 
39 
42 
44 
46 
48 
50 
53 
55 
57 
94 
96 
98 
101 
103 
105 
107 
109 
112 
114 
116 
118 
120 
123 
125 
127 
129 
131 
134 
136 
138 
147 
149 
151 
154 
156 
158 
160 
165 
167 
169 
171 
173 
176 
178 
180 
182 
187 
189 
191 
193 
195 
198 
200 
202 
239 
241 
243 
246 
254 
257 
259 
261 
263 
265 
268 
270 
272 
274 
276 
279 
281 
283 
10 
8
9
11 
10 
9
8
7
7
6
5
17 
3
4
6
5
4
3
2
1
2
0
16 
1
0
62 
60 
61 
15 
59 
58 
57 
53 
54 
52 
55 
56 
47 
48 
14 
46 
49 
51 
J9U2 
H44441-003 
SCONN 
51 
52 
132 
133 
121 
122 
110 
111 
99 
100 
40 
41 
29 
30 
18 
19 
7
8
197 
196 
278 
267 
266 
255 
245 
244 
186 
185 
174 
164 
163 
153 
152 
43 
42 
41 
44 
45 
13 
38 
37 
36 
40 
39 
33 
32 
31 
35 
34 
16 
27 
28 
26 
29 
30 
22 
23 
21 
25 
24 
17 
16 
17 
18 
19 
20 
11 
13 
12 
14 
15 
M_J_DQS_DP<17:0> 
M_J_DQS_DN<17:0> 
M_J_MA<17:0> 
M_J_CLK_DN<3:0> 
M_J_CS_N<7:0> 
M_J_CKE<3:0> 
M_J_ODT<3:0> 
M_J_ECC<7:0> 
M_J_BA<1:0> 
M_J_BG<1:0> 
M_J_CLK_DP<3:0> 
M_J_ACT_N 
FM_DIMM_EVENT_COD_N 
M_J_VREF 
TP_CH_J_DIMM_J1_RFU_2 
TP_CH_J_DIMM_J1_RFU_0 
TP_CH_J_DIMM_J1_RFU_1 
SMB_DDR_GHJ_VPP_SCL 
FM_ADR_COMPLETE_GHJ_N 
M_J_PAR 
M_GHJ_RST_N 
M_J_C<2> 
M_J_ALERT_N 
175 
277 
137 
249 
252 
250 
248 
184 
162 
50 
269 
130 
273 
135 
63 
256 
M_J_DQ<63:0> 
SCONN 
77 78 79 80 81 99 
59 81 
59 81 
59 81 
59 81 
59 81 
59 81 
59 81 
59 81 
59 81 
59 81 
59 81 
59 81 
43 44 45 46 47 48 49 50 51 
52 53 54 77 78 79 80 81 83 
84 85 86 87 88 94 
100 81 
99 77 78 79 80 81 
89 77 78 79 80 
81 
59 81 
55 77 78 79 80 81 
59 81 
81 59 
59 81 
BOM NOTE: 
DO NOT SCALE DRAWING 
SCONN288_H44441003 
SCONN288_H44441003 
SCONN288_H44441003 
SCONN288_H44441003 
SHEET 
B
AA
B
B
SIZE 
SCALE: 
234
1234
DEPARTMENT CODE 
1
DOCUMENT NUMBER REV 
BI 
BI 
P12V_NVDIMM_GHJ 
IN 
PVPP_GHJ 
PVPP_GHJ 
OUT 
IN 
BI 
IN 
IN 
IN 
IN 
PVTT_GHJ 
IN 
IN 
BI 
IN 
OUT 
IN 
IN 
PVDDQ_GHJ 
IN 
IN 
IN 
IN 
BI 
82 OF 270 
Wed Feb 08 16:34:52 2017 
DQS0N DQS0P 
DQS10N DQS10P DQS11N DQS11P DQS12N DQS12P DQS13N DQS13P DQS14N DQS14P DQS15N DQS15P DQS16N 
DQS16P DQS17N DQS17P 
DQS1N DQS1P DQS2N DQS2P DQS3N DQS3P 
DQS4N DQS4P DQS5N DQS5P DQS6N DQS6P DQS7N DQS7P DQS8N DQS8P DQS9N DQS9P 
VSS<83> 
VSS<82> 
VSS<81> 
VSS<80> 
VSS<79> 
VSS<78> 
VSS<77> 
VSS<76> 
VSS<75> 
VSS<74> 
VSS<73> 
VSS<72> 
VSS<71> 
VSS<70> 
VSS<69> 
VSS<68> 
VSS<93> 
VSS<92> 
VSS<91> 
VSS<90> 
VSS<89> 
VSS<88> 
VSS<87> 
VSS<86> 
VSS<85> 
VSS<84> 
VSS<67> 
VSS<66> 
VSS<65> 
VSS<64> 
VSS<63> 
VSS<62> 
VSS<61> 
VSS<60> 
VSS<59> 
VSS<58> 
VSS<57> 
VSS<56> 
VSS<55> 
VSS<54> 
VSS<53> 
VSS<52> 
VSS<51> 
VSS<50> 
VSS<49> 
VSS<48> 
VSS<47> 
VSS<46> 
VSS<45> 
VSS<44> 
VSS<43> 
VSS<42> 
VSS<41> 
VSS<40> 
VSS<39> 
VSS<38> 
VSS<37> 
VSS<36> 
VSS<35> 
VSS<34> 
VSS<33> 
VSS<32> 
VSS<31> 
VSS<30> 
VSS<29> 
VSS<28> 
VSS<27> 
VSS<26> 
VSS<25> 
VSS<24> 
VSS<23> 
VSS<22> 
VSS<21> 
VSS<20> 
VSS<19> 
VSS<18> 
VSS<17> 
VSS<16> 
VSS<15> 
VSS<14> 
VSS<13> 
VSS<12> 
VSS<11> 
VSS<10> VSS<9> 
VSS<8> 
VSS<7> 
VSS<6> 
VSS<5> 
VSS<4> 
VSS<3> 
VSS<2> 
VSS<1> 
VSS<0> 
DQ<12> 
DQ<11> 
DQ<10> DQ<9> 
DQ<8> 
DQ<7> 
DQ<6> 
A17 
A16_RAS_N 
A15_CAS_N DQ<60> 
DQ<58> 
DQ<50> 
S3_N_C<1> 
S2_N_C<0> 
S1_N 
S0_N 
CKE<1> 
CKE<0> 
ODT<1> 
ODT<0> 
DQ<21> 
DQ<19> 
DQ<18> 
DQ<27> DQ<28> 
CB<5> 
CB<4> 
CB<3> 
CB<2> 
A8 
A7 
A6 
DQ<45> 
DQ<44> 
DQ<41> 
DQ<51> 
A2 
ALERT_N 
ACT_N 
VREFCA 
SCL SDA 
SA<0> SA<1> SA<2> VDDSPD 
DQ<1> DQ<2> 
RFU<2> 
DQ<31> DQ<32> DQ<33> DQ<34> DQ<35> DQ<36> DQ<37> DQ<38> 
A0 A1 
A10 A11 A12 A13 A14_WE_N 
A3 A4 A5 
A9 
BG<1> 
C<2> 
CB<7> 
CB<6> 
CB<1> 
CB<0> 
DQ<63> 
DQ<62> 
DQ<61> 
DQ<59> 
DQ<57> 
DQ<56> 
DQ<55> 
DQ<54> 
DQ<53> 
DQ<52> 
DQ<49> 
DQ<48> 
DQ<47> 
DQ<46> 
DQ<43> 
DQ<40> 
DQ<39> 
DQ<30> 
DQ<26> 
DQ<25> 
DQ<24> 
DQ<23> 
DQ<22> 
DQ<20> 
DQ<17> 
DQ<16> 
DQ<15> 
DQ<14> 
DQ<13> 
DQ<5> 
DQ<4> 
DQ<3> 
DQ<0> 
EVENT_N 
PAR 
RESET_N 
RFU<1> 
RFU<0> 
SAVE_N_NC 
BG<0> 
CK1P 
CK1N 
CK0P 
CK0N 
DQ<29> 
DQ<42> 
BA<0> BA<1> 
VDD<25> 
VDD<24> 
VDD<23> 
VDD<22> 
VDD<21> 
VDD<20> 
VDD<19> 
VDD<18> 
VDD<17> 
VDD<16> 
VDD<15> 
VDD<14> 
VDD<13> 
VDD<12> 
VDD<11> 
VDD<10> 
VDD<9> 
VDD<8> 
VDD<7> 
VDD<6> 
VDD<5> 
VDD<4> 
VDD<3> 
VDD<2> 
VDD<1> 
VDD<0> 
VPP<1> 
VPP<0> 
VTT<1> 
VTT<0> 
VPP<4> 
VPP<3> 
VPP<2> 12V<0> 12V<1> 
PVDDQ (SINGLE SIDE) CAP: 10UF X1, 22UF X50 PVTT CAP: 100UF X2, 47UF X1 PVPP CAP: 10UF X12 
PVDDQ (DOUBLE SIDE) CAP: 100UF X8, 47UF X41 
BOM_SS=NOPOP 
BOM_SS=NOPOP 
BOM_SS=NOPOP 
BOM_SS=NOPOP 
UNSTUFF FOR SKU B 
CPU1 DDR4 CH J DIMM1 
CAP BETWEEN DIMM 
WIWYNN CORPORATION 
SMBUS ADDR: 0XAA 
PLACE CAP NEAR DIMM CONNECTOR 
2/4 
3/4 
1/4 
4/4 



127 
15 86 
82 
269 
147 
105 
TP_CH_K_DIMM_K0_RFU_2 
107 
196 
M_K_ACT_N 
M_K_C<2> 
M_K_PAR 
M_KLM_RST_N 
FM_DIMM_EVENT_COD_N 
FM_ADR_COMPLETE_KLM_N 
SMB_DDR_KLM_VPP_SCL 
TP_CH_K_DIMM_K0_RFU_0 
TP_CH_K_DIMM_K0_RFU_1 
M_K_VREF 
M_K_ALERT_N 
M_K_ODT<3:0> 
M_K_CKE<3:0> 
M_K_ECC<7:0> 
M_K_CS_N<7:0> 
M_K_BA<1:0> 
M_K_BG<1:0> 
M_K_CLK_DN<3:0> 
M_K_CLK_DP<3:0> 
M_K_MA<17:0> M_K_DQ<63:0> 
M_K_DQS_DP<17:0> 
M_K_DQS_DN<17:0> 
13 
10 
12 
19 
17 
16 
14 
15 
23 
22 
12 
20 
21 
18 
26 
29 
27 
25 
24 
32 
33 
13 
28 
30 
31 
39 
36 
37 
35 
34 
42 
43 
14 
41 
38 
40 
152 
153 
163 
164 
174 
175 
185 
186 
244 
245 
255 
256 
266 
267 
277 
278 
197 
8
7
19 
18 
30 
29 
41 
40 
100 
99 
111 
110 
122 
121 
133 
132 
52 
51 
SCONN 
H44441-004 
J1B1 
48 
46 
49 
47 
44 
45 
15 
52 
55 
53 
50 
51 
58 
56 
59 
57 
54 
16 
62 
63 
61 
60 
283 
281 
279 
276 
274 
272 
270 
268 
265 
263 
261 
259 
257 
254 
252 
250 
248 
246 
243 
241 
239 
202 
200 
198 
195 
193 
191 
189 
187 
184 
182 
180 
178 
176 
173 
171 
169 
167 
165 
162 
160 
158 
156 
154 
151 
149 
138 
136 
134 
131 
129 
125 
123 
120 
118 
116 
114 
112 
109 
103 
101 
98 
96 
94 
57 
55 
53 
50 
48 
46 
44 
42 
39 
37 
35 
33 
31 
28 
26 
24 
22 
20 
17 
15 
13 
11 
9
6
4
2
SCONN 
H44441-004 
J1B1 
0
1
17 
0
3
1
2
4
5
2
3
4
5
17 
6
8
7
6
9
10 
7
8
9
10 
11 
1
1
X7R 
25V 
0402V 
10% 
0.01UF 
A36096-045 
C1B9 
SMB_DDR_KLM_VPP_SDA 
145 
1
236 
233 
231 
229 
226 
223 
220 
217 
215 
212 
209 
206 
204 
92 
90 
88 
85 
83 
80 
76 
73 
70 
67 
64 
61 
59 
287 
286 
288 
143 
142 
221 
77 
SCONN 
H44441-004 
J1B1 
1
1
0
1
0
0
0
0
2
3
13 
1
0
3
2
5
4
12 
7
6
0
1
0
1
11 
0
1
3
2
4
5
6
7
8
9
16 
10 
11 
12 
13 
14 
17 
16 
234 
79 
72 
216 
71 
214 
213 
69 
211 
68 
66 
225 
210 
65 
232 
228 
62 
208 
81 
224 
63 
207 
235 
49 
194 
56 
201 
47 
192 
54 
199 
75 
74 
219 
218 
60 
203 
5
150 
12 
157 
3
148 
10 
155 
16 
161 
23 
168 
14 
159 
21 
166 
27 
172 
34 
179 
25 
170 
32 
177 
38 
183 
45 
190 
36 
181 
43 
188 
97 
242 
104 
249 
95 
240 
102 
247 
108 
253 
115 
260 
106 
251 
113 
258 
119 
264 
126 
271 
117 
262 
124 
130 
275 
137 
282 
128 
273 
135 
280 
78 
87 
91 
222 
58 
205 
227 
144 
84 
89 
93 
237 
139 
140 
238 
230 
141 
285 
284 
146 
SCONN 
H44441-004 
J1B1 
0
15 
3
1
6
9
7
4
2
5
11 
8
14 
60 84 
60 84 
60 84 
55 84 85 86 87 88 
43 44 45 46 47 48 49 50 51 52 
53 54 77 78 79 80 81 82 84 
85 86 87 88 94 
89 84 85 86 87 88 
99 84 85 86 87 88 
100 84 
84 60 
60 84 
60 84 
60 84 
60 84 
60 84 
60 84 
60 84 
60 84 
60 84 60 84 
60 84 
60 84 
84 85 86 87 88 99 
BOM NOTE: 
DO NOT SCALE DRAWING 
SCONN288_H44441004 
SCONN288_H44441004 
SCONN288_H44441004 
SCONN288_H44441004 
SHEET 
B
AA
B
B
SIZE 
SCALE: 
234
1234
DEPARTMENT CODE 
1
DOCUMENT NUMBER REV 
BI 
BI 
P12V_NVDIMM_KLM 
IN 
PVPP_KLM 
PVPP_KLM 
OUT 
IN 
IN 
PVTT_KLM 
BI 
IN 
IN 
IN 
PVDDQ_KLM 
IN 
IN 
BI 
IN 
OUT 
IN 
IN 
IN 
IN 
IN 
IN 
BI 
83 OF 270 
Wed Feb 08 16:34:52 2017 
DQS9P 
DQS9N DQS8P DQS8N DQS7P DQS7N DQS6P DQS6N DQS5P DQS5N DQS4P DQS4N DQS3P 
DQS3N DQS2P DQS2N DQS1P DQS1N 
DQS17P DQS17N DQS16P DQS16N 
DQS15P DQS15N DQS14P DQS14N DQS13P DQS13N DQS12P DQS12N DQS11P DQS11N DQS10P DQS10N 
DQS0P DQS0N 
VSS<0> VSS<1> VSS<2> VSS<3> VSS<4> VSS<5> VSS<6> VSS<7> VSS<8> VSS<9> VSS<10> VSS<11> 
VSS<12> VSS<13> VSS<14> VSS<15> VSS<16> VSS<17> VSS<18> VSS<19> VSS<20> VSS<21> VSS<22> VSS<23> VSS<24> 
VSS<25> VSS<26> VSS<27> VSS<28> VSS<29> VSS<30> VSS<31> VSS<32> VSS<33> VSS<34> VSS<35> VSS<36> VSS<37> 
VSS<38> VSS<39> VSS<40> VSS<41> VSS<42> VSS<43> VSS<44> 
VSS<47> VSS<48> VSS<49> VSS<50> VSS<51> VSS<52> VSS<53> VSS<54> VSS<55> VSS<56> VSS<57> VSS<58> 
VSS<59> VSS<60> VSS<61> VSS<62> VSS<63> VSS<64> VSS<65> VSS<66> VSS<67> 
VSS<84> 
VSS<85> VSS<86> VSS<87> VSS<88> VSS<89> VSS<90> VSS<91> VSS<92> VSS<93> 
VSS<68> VSS<69> VSS<70> VSS<71> 
VSS<72> VSS<73> VSS<74> VSS<75> VSS<76> VSS<77> VSS<78> VSS<79> VSS<80> VSS<81> VSS<82> VSS<83> 
VSS<45> VSS<46> 
12V<0> VPP<2> 
VPP<4> 
VTT<0> VTT<1> 
VPP<0> VPP<1> 
VDD<0> VDD<1> VDD<2> VDD<3> VDD<4> VDD<5> VDD<6> VDD<7> VDD<8> VDD<9> VDD<10> VDD<11> 
VDD<12> VDD<13> VDD<14> VDD<15> VDD<16> VDD<17> VDD<18> VDD<19> VDD<20> VDD<21> VDD<22> VDD<23> VDD<24> 
VDD<25> 
12V<1> VPP<3> 
BA<1> 
BA<0> DQ<42> 
DQ<29> 
CK0N CK0P CK1N CK1P 
BG<0> 
SAVE_N_NC 
RFU<0> RFU<1> 
RESET_N PAR 
EVENT_N 
DQ<0> 
DQ<3> DQ<4> DQ<5> 
DQ<13> DQ<14> DQ<15> 
DQ<16> DQ<17> 
DQ<20> 
DQ<22> DQ<23> DQ<24> DQ<25> DQ<26> 
DQ<30> 
DQ<39> DQ<40> 
DQ<43> 
DQ<46> DQ<47> DQ<48> DQ<49> 
DQ<52> DQ<53> 
DQ<54> DQ<55> DQ<56> DQ<57> 
DQ<59> 
DQ<61> DQ<62> DQ<63> 
CB<0> 
CB<1> 
CB<6> CB<7> 
C<2> 
BG<1> 
A9 
A5 
A4 
A3 
A14_WE_N 
A13 
A12 
A11 
A10 
A1 
A0 
DQ<38> 
DQ<37> 
DQ<36> 
DQ<35> 
DQ<34> 
DQ<33> 
DQ<32> 
DQ<31> 
RFU<2> 
DQ<2> 
DQ<1> 
VDDSPD 
SA<2> 
SA<1> 
SA<0> 
SDA 
SCL 
VREFCA 
ACT_N ALERT_N 
A2 
DQ<51> 
DQ<41> 
DQ<44> DQ<45> 
A6 A7 
A8 
CB<2> CB<3> CB<4> CB<5> 
DQ<28> 
DQ<27> 
DQ<18> DQ<19> 
DQ<21> 
ODT<0> ODT<1> 
CKE<0> CKE<1> 
S0_N S1_N S2_N_C<0> S3_N_C<1> 
DQ<50> 
DQ<58> 
DQ<60> A15_CAS_N A16_RAS_N A17 
DQ<6> DQ<7> DQ<8> DQ<9> DQ<10> DQ<11> DQ<12> 
PVDDQ (SINGLE SIDE) CAP: 10UF X1, 22UF X50 
PVDDQ (DOUBLE SIDE) CAP: 100UF X8, 47UF X41 
PVTT CAP: 100UF X2, 47UF X1 PVPP CAP: 10UF X12 
STUFF FOR SKU A & B 
CPU1 DDR4 CH K DIMM0 
CAP BETWEEN DIMM 
PLACE CAP NEAR DIMM CONNECTOR 
WIWYNN CORPORATION 
SMBUS ADDR: 0XA0 
2/4 
3/4 4/4 
1/4 



57 
103 
M_K_VREF 
J9M1 
SCONN 
M_K_DQ<63:0> 
5
SCONN 
278 
277 
267 
266 
101 
283 
197 
145 
FM_DIMM_EVENT_COD_N 
M_K_C<2> 
M_KLM_RST_N 
M_K_PAR 
M_K_ACT_N 
SMB_DDR_KLM_VPP_SCL 
FM_ADR_COMPLETE_KLM_N 
TP_CH_K_DIMM0_RFU_1 
TP_CH_K_DIMM0_RFU_0 
TP_CH_K_DIMM0_RFU_2 
M_K_ALERT_N 
M_K_CLK_DN<3:0> 
M_K_ODT<3:0> 
M_K_CKE<3:0> 
M_K_CS_N<7:0> 
M_K_ECC<7:0> 
M_K_BA<1:0> 
M_K_BG<1:0> 
M_K_CLK_DP<3:0> 
M_K_MA<17:0> 
M_K_DQS_DP<17:0> 
M_K_DQS_DN<17:0> 
46 
47 
44 
45 
43 
41 
42 
39 
40 
38 
37 
36 
35 
34 
33 
32 
31 
30 
29 
28 
25 
26 
27 
24 
23 
20 
21 
22 
18 
19 
15 
17 
16 
13 
14 
10 
12 
11 
8
7
9
J9M1 
1
236 
233 
231 
229 
226 
223 
220 
217 
215 
212 
209 
206 
204 
92 
90 
88 
85 
83 
80 
76 
73 
70 
67 
64 
61 
59 
287 
286 
288 
143 
142 
221 
77 
SCONN 
H44441-003 
5
6
4
3
2
1
0
1
0
0
1
0
1
7
4
5
6
X7R 
25V 
0402V 
10% 
0.01UF 
A36096-045 
C9M1 
3
3
3
2
2
2
3
2
7
5
6
4
3
2
0
1
17 
17 
15 
16 
13 
12 
14 
16 
15 
14 
13 
12 
10 
11 
8
7
9
10 
11 
9
8
7
6
4
6
3
2
5
4
3
1
2
1
0
0
79 
72 
216 
71 
214 
213 
69 
211 
68 
66 
225 
210 
65 
232 
228 
86 
82 
234 
62 
208 
81 
224 
63 
207 
235 
49 
194 
56 
201 
47 
192 
54 
199 
75 
74 
219 
218 
60 
203 
5
150 
12 
157 
3
148 
10 
155 
16 
161 
23 
168 
14 
159 
21 
166 
27 
172 
34 
179 
25 
170 
32 
177 
38 
183 
45 
190 
36 
181 
43 
188 
97 
242 
104 
249 
95 
240 
102 
247 
108 
253 
115 
260 
106 
251 
113 
258 
119 
264 
126 
271 
117 
262 
124 
269 
130 
275 
137 
282 
128 
273 
135 
280 
78 
87 
91 
222 
58 
205 
227 
144 
84 
89 
93 
237 
139 
140 
238 
230 
141 
285 
284 
146 
SCONN 
H44441-003 
J9M1 
160 
57 
281 
279 
276 
274 
272 
270 
268 
265 
263 
261 
259 
257 
254 
252 
250 
248 
246 
243 
241 
239 
202 
200 
198 
195 
193 
191 
189 
187 
184 
182 
180 
178 
176 
173 
171 
169 
167 
165 
162 
158 
156 
154 
151 
149 
147 
138 
136 
134 
131 
129 
127 
125 
123 
120 
118 
116 
114 
112 
109 
107 
105 
98 
96 
94 
55 
53 
50 
48 
46 
44 
42 
39 
37 
35 
33 
31 
28 
26 
24 
22 
20 
17 
15 
13 
11 
9
6
4
2
H44441-003 
J9M1 
61 
62 
63 
60 
59 
56 
SMB_DDR_KLM_VPP_SDA 
58 
54 
55 
51 
52 
53 
49 
48 
50 
17 
15 
16 
14 
13 
12 
10 
11 
9
8
7
4
5
6
2
3
186 
153 
152 
163 
164 
174 
175 
185 
244 
245 
255 
256 
196 
8
7
19 
18 
30 
29 
41 
40 
100 
99 
111 
110 
122 
121 
133 
132 
52 
51 
H44441-003 
100 83 
60 83 
43 44 45 46 47 48 49 50 51 52 
53 54 77 78 79 80 81 82 83 
85 86 87 88 94 
60 83 
55 83 85 86 87 88 
60 83 
60 83 
99 83 85 86 87 88 
89 83 85 86 87 88 
83 60 
60 83 
60 83 
60 83 
60 83 
60 83 
60 83 
60 83 
60 83 
60 83 
60 83 
60 83 
83 85 86 87 88 99 
BOM NOTE: 
DO NOT SCALE DRAWING 
SCONN288_H44441003 
SCONN288_H44441003 
SCONN288_H44441003 
SCONN288_H44441003 
SHEET 
B
AA
B
B
SIZE 
SCALE: 
234
1234
DEPARTMENT CODE 
1
DOCUMENT NUMBER REV 
IN 
OUT 
PVDDQ_KLM 
IN 
OUT PVPP_KLM 
IN 
IN 
IN 
IN 
IN 
IN 
P12V_NVDIMM_KLM 
BI 
BI 
BI 
IN 
IN 
IN 
BI 
BI 
IN 
IN 
IN 
PVPP_KLM 
PVTT_KLM 
IN 
84 OF 270 
Wed Feb 08 16:34:52 2017 
VDD<25> 
VDD<24> 
VDD<23> 
VDD<22> 
VDD<21> 
VDD<20> 
VDD<19> 
VDD<18> 
VDD<17> 
VDD<16> 
VDD<15> 
VDD<14> 
VDD<13> 
VDD<12> 
VDD<11> 
VDD<10> 
VDD<9> 
VDD<8> 
VDD<7> 
VDD<6> 
VDD<5> 
VDD<4> 
VDD<3> 
VDD<2> 
VDD<1> 
VDD<0> 
VPP<1> 
VPP<0> 
VTT<1> 
VTT<0> 
VPP<4> 
VPP<3> 
VPP<2> 12V<0> 12V<1> 
DQ<12> 
DQ<11> 
DQ<10> DQ<9> 
DQ<8> 
DQ<7> 
DQ<6> 
A17 
A16_RAS_N 
A15_CAS_N DQ<60> 
DQ<58> 
DQ<50> 
S3_N_C<1> 
S2_N_C<0> 
S1_N 
S0_N 
CKE<1> 
CKE<0> 
ODT<1> 
ODT<0> 
DQ<21> 
DQ<19> 
DQ<18> 
DQ<27> DQ<28> 
CB<5> 
CB<4> 
CB<3> 
CB<2> 
A8 
A7 
A6 
DQ<45> 
DQ<44> 
DQ<41> 
DQ<51> 
A2 
ALERT_N 
ACT_N 
VREFCA 
SCL SDA 
SA<0> SA<1> SA<2> VDDSPD 
DQ<1> DQ<2> 
RFU<2> 
DQ<31> DQ<32> DQ<33> DQ<34> DQ<35> DQ<36> DQ<37> DQ<38> 
A0 A1 
A10 A11 A12 A13 A14_WE_N 
A3 A4 A5 
A9 
BG<1> 
C<2> 
CB<7> 
CB<6> 
CB<1> 
CB<0> 
DQ<63> 
DQ<62> 
DQ<61> 
DQ<59> 
DQ<57> 
DQ<56> 
DQ<55> 
DQ<54> 
DQ<53> 
DQ<52> 
DQ<49> 
DQ<48> 
DQ<47> 
DQ<46> 
DQ<43> 
DQ<40> 
DQ<39> 
DQ<30> 
DQ<26> 
DQ<25> 
DQ<24> 
DQ<23> 
DQ<22> 
DQ<20> 
DQ<17> 
DQ<16> 
DQ<15> 
DQ<14> 
DQ<13> 
DQ<5> 
DQ<4> 
DQ<3> 
DQ<0> 
EVENT_N 
PAR 
RESET_N 
RFU<1> 
RFU<0> 
SAVE_N_NC 
BG<0> 
CK1P 
CK1N 
CK0P 
CK0N 
DQ<29> 
DQ<42> 
BA<0> BA<1> 
VSS<83> 
VSS<82> 
VSS<81> 
VSS<80> 
VSS<79> 
VSS<78> 
VSS<77> 
VSS<76> 
VSS<75> 
VSS<74> 
VSS<73> 
VSS<72> 
VSS<71> 
VSS<70> 
VSS<69> 
VSS<68> 
VSS<93> 
VSS<92> 
VSS<91> 
VSS<90> 
VSS<89> 
VSS<88> 
VSS<87> 
VSS<86> 
VSS<85> 
VSS<84> 
VSS<67> 
VSS<66> 
VSS<65> 
VSS<64> 
VSS<63> 
VSS<62> 
VSS<61> 
VSS<60> 
VSS<59> 
VSS<58> 
VSS<57> 
VSS<56> 
VSS<55> 
VSS<54> 
VSS<53> 
VSS<52> 
VSS<51> 
VSS<50> 
VSS<49> 
VSS<48> 
VSS<47> 
VSS<46> 
VSS<45> 
VSS<44> 
VSS<43> 
VSS<42> 
VSS<41> 
VSS<40> 
VSS<39> 
VSS<38> 
VSS<37> 
VSS<36> 
VSS<35> 
VSS<34> 
VSS<33> 
VSS<32> 
VSS<31> 
VSS<30> 
VSS<29> 
VSS<28> 
VSS<27> 
VSS<26> 
VSS<25> 
VSS<24> 
VSS<23> 
VSS<22> 
VSS<21> 
VSS<20> 
VSS<19> 
VSS<18> 
VSS<17> 
VSS<16> 
VSS<15> 
VSS<14> 
VSS<13> 
VSS<12> 
VSS<11> 
VSS<10> VSS<9> 
VSS<8> 
VSS<7> 
VSS<6> 
VSS<5> 
VSS<4> 
VSS<3> 
VSS<2> 
VSS<1> 
VSS<0> 
DQS0N DQS0P 
DQS10N 
DQS10P DQS11N DQS11P DQS12N DQS12P DQS13N DQS13P DQS14N DQS14P DQS15N DQS15P DQS16N DQS16P 
DQS17N DQS17P 
DQS1N DQS1P DQS2N DQS2P DQS3N DQS3P 
DQS4N DQS4P DQS5N DQS5P DQS6N DQS6P DQS7N DQS7P DQS8N DQS8P DQS9N DQS9P 
PVDDQ (SINGLE SIDE) CAP: 10UF X1, 22UF X50 PVTT CAP: 100UF X2, 47UF X1 
PVDDQ (DOUBLE SIDE) CAP: 100UF X8, 47UF X41 
PVPP CAP: 10UF X12 
BOM_SS=NOPOP 
BOM_SS=NOPOP 
BOM_SS=NOPOP 
BOM_SS=NOPOP 
UNSTUFF FOR SKU B 
CPU1 DDR4 CH K DIMM1 
CAP BETWEEN DIMM 
PLACE CAP NEAR DIMM CONNECTOR 
WIWYNN CORPORATION 
SMBUS ADDR: 0XA2 4/4 
1/4 
3/4 
2/4 



127 
M_L_DQ<63:0> 
105 
M_L_MA<17:0> 
242 
107 
256 
M_L_ALERT_N 
M_L_C<2> 
M_KLM_RST_N 
M_L_PAR 
FM_DIMM_EVENT_COD_N 
FM_ADR_COMPLETE_KLM_N 
SMB_DDR_KLM_VPP_SCL 
TP_CH_L_DIMM_L0_RFU_1 
TP_CH_L_DIMM_L0_RFU_0 
TP_CH_L_DIMM_L0_RFU_2 
M_L_VREF 
M_L_ACT_N 
M_L_BG<1:0> 
M_L_BA<1:0> 
M_L_CLK_DP<3:0> 
M_L_CLK_DN<3:0> 
M_L_ECC<7:0> 
M_L_ODT<3:0> 
M_L_CKE<3:0> 
M_L_CS_N<7:0> 
M_L_DQS_DN<17:0> 
M_L_DQS_DP<17:0> 
13 
10 
12 
19 
17 
16 
14 
15 
23 
22 
12 
20 
21 
18 
26 
29 
27 
25 
24 
32 
33 
13 
28 
30 
31 
39 
36 
37 
35 
34 
42 
43 
14 
41 
38 
40 
185 
152 
153 
163 
164 
174 
175 
186 
244 
245 
255 
266 
267 
277 
278 
196 
197 
8
7
19 
18 
30 
29 
41 
40 
100 
99 
111 
110 
122 
121 
133 
132 
52 
51 
SCONN 
H44441-004 
J1A2 
48 
46 
49 
47 
44 
45 
15 
52 
55 
53 
50 
51 
58 
56 
59 
57 
54 
16 
62 
63 
61 
60 
281 
279 
276 
274 
272 
270 
268 
265 
263 
261 
259 
257 
254 
252 
250 
248 
246 
243 
241 
239 
202 
200 
198 
195 
193 
191 
189 
187 
184 
182 
180 
178 
176 
173 
171 
169 
167 
165 
162 
160 
158 
156 
154 
151 
149 
147 
138 
136 
134 
131 
129 
125 
123 
120 
118 
116 
114 
101 
98 
96 
94 
57 
55 
53 
50 
48 
46 
44 
42 
39 
37 
35 
33 
31 
28 
26 
24 
22 
20 
17 
15 
13 
11 
9
6
4
2
SCONN 
J1A2 
283 
H44441-004 
112 
109 
103 
0
1
17 
0
3
1
2
4
5
2
3
4
5
17 
6
8
7
6
9
10 
7
8
9
10 
11 
X7R 
25V 
0402V 
10% 
0.01UF 
A36096-045 
C9L7 
SMB_DDR_KLM_VPP_SDA 
145 
1
236 
233 
231 
229 
226 
223 
220 
217 
215 
212 
209 
206 
204 
92 
90 
88 
85 
83 
80 
76 
73 
70 
67 
64 
61 
59 
287 
286 
288 
143 
142 
221 
77 
SCONN 
H44441-004 
J1A2 
0
1
0
1
0
1
2
3
0
1
0
1
13 
1
0
3
2
5
4
12 
7
6
0
1
0
1
11 
0
1
3
2
4
5
6
7
8
9
16 
10 
11 
12 
13 
14 
15 
17 
16 
282 
240 
79 
72 
216 
71 
214 
213 
69 
211 
68 
66 
225 
210 
65 
232 
228 
86 
82 
62 
208 
81 
224 
63 
207 
235 
49 
194 
56 
201 
47 
192 
54 
199 
75 
74 
219 
218 
60 
203 
5
150 
12 
157 
3
148 
10 
155 
16 
161 
23 
168 
14 
159 
21 
166 
27 
172 
34 
179 
25 
170 
32 
177 
38 
183 
45 
190 
36 
181 
43 
188 
97 
104 
249 
95 
102 
247 
108 
253 
115 
260 
106 
251 
113 
258 
119 
264 
126 
271 
117 
262 
124 
269 
130 
275 
137 
128 
273 
135 
280 
78 
87 
91 
222 
58 
205 
227 
144 
84 
89 
93 
237 
139 
140 
238 
230 
141 
285 
284 
146 
SCONN 
H44441-004 
J1A2 
234 
0
15 
3
1
6
9
7
4
2
5
11 
8
14 
61 86 61 86 
86 61 
61 86 
55 83 84 86 87 88 
61 86 
43 44 45 46 47 48 49 50 51 52 
53 54 77 78 79 80 81 82 83 84 
86 87 88 94 
89 83 84 86 87 88 
99 83 84 86 87 88 
100 86 
61 86 
61 86 
61 86 
61 86 
61 86 
61 86 
61 86 
61 86 
61 86 
61 86 
61 86 
83 84 86 87 88 99 
BOM NOTE: 
DO NOT SCALE DRAWING 
SCONN288_H44441004 
SCONN288_H44441004 
SCONN288_H44441004 
SCONN288_H44441004 
SHEET 
B
AA
B
B
SIZE 
SCALE: 
234
1234
DEPARTMENT CODE 
1
DOCUMENT NUMBER REV 
BI 
BI 
P12V_NVDIMM_KLM 
IN 
PVPP_KLM 
PVPP_KLM 
OUT 
IN 
IN 
BI 
PVTT_KLM 
IN 
IN 
IN 
PVDDQ_KLM 
IN 
IN 
BI 
IN 
OUT 
IN 
IN 
IN 
IN 
IN 
IN 
BI 
85 OF 270 
DQS9P DQS9N DQS8P DQS8N DQS7P DQS7N DQS6P DQS6N DQS5P DQS5N DQS4P DQS4N 
DQS3P DQS3N DQS2P DQS2N DQS1P DQS1N 
DQS17P DQS17N DQS16P 
DQS16N DQS15P DQS15N DQS14P DQS14N DQS13P DQS13N DQS12P DQS12N DQS11P DQS11N DQS10P DQS10N 
DQS0P DQS0N 
VSS<0> VSS<1> VSS<2> VSS<3> VSS<4> VSS<5> VSS<6> VSS<7> VSS<8> VSS<9> VSS<10> VSS<11> 
VSS<12> VSS<13> VSS<14> VSS<15> VSS<16> VSS<17> VSS<18> VSS<19> VSS<20> VSS<21> VSS<22> VSS<23> VSS<24> 
VSS<25> VSS<26> VSS<27> VSS<28> VSS<29> VSS<30> VSS<31> VSS<32> VSS<33> VSS<34> VSS<35> VSS<36> VSS<37> 
VSS<38> VSS<39> VSS<40> VSS<41> VSS<42> VSS<43> VSS<44> 
VSS<47> VSS<48> VSS<49> VSS<50> VSS<51> VSS<52> VSS<53> VSS<54> VSS<55> VSS<56> VSS<57> VSS<58> 
VSS<59> VSS<60> VSS<61> VSS<62> VSS<63> VSS<64> VSS<65> VSS<66> VSS<67> 
VSS<84> 
VSS<85> VSS<86> VSS<87> VSS<88> VSS<89> VSS<90> VSS<91> VSS<92> VSS<93> 
VSS<68> VSS<69> VSS<70> VSS<71> 
VSS<72> VSS<73> VSS<74> VSS<75> VSS<76> VSS<77> VSS<78> VSS<79> VSS<80> VSS<81> VSS<82> VSS<83> 
VSS<45> VSS<46> 
12V<0> VPP<2> 
VPP<4> 
VTT<0> VTT<1> 
VPP<0> VPP<1> 
VDD<0> VDD<1> VDD<2> VDD<3> VDD<4> VDD<5> VDD<6> VDD<7> VDD<8> VDD<9> VDD<10> VDD<11> VDD<12> 
VDD<13> VDD<14> VDD<15> VDD<16> VDD<17> VDD<18> VDD<19> VDD<20> VDD<21> VDD<22> VDD<23> VDD<24> VDD<25> 
12V<1> VPP<3> 
BA<1> 
BA<0> DQ<42> 
DQ<29> 
CK0N CK0P CK1N CK1P 
BG<0> 
SAVE_N_NC 
RFU<0> RFU<1> 
RESET_N PAR 
EVENT_N 
DQ<0> 
DQ<3> DQ<4> DQ<5> 
DQ<13> DQ<14> 
DQ<15> DQ<16> DQ<17> 
DQ<20> 
DQ<22> DQ<23> DQ<24> DQ<25> DQ<26> 
DQ<30> 
DQ<39> DQ<40> 
DQ<43> 
DQ<46> DQ<47> DQ<48> DQ<49> 
DQ<52> 
DQ<53> DQ<54> DQ<55> DQ<56> DQ<57> 
DQ<59> 
DQ<61> DQ<62> DQ<63> 
CB<0> CB<1> 
CB<6> CB<7> 
C<2> 
BG<1> 
A9 
A5 
A4 
A3 
A14_WE_N 
A13 
A12 
A11 
A10 
A1 
A0 
DQ<38> 
DQ<37> 
DQ<36> 
DQ<35> 
DQ<34> 
DQ<33> 
DQ<32> 
DQ<31> 
RFU<2> 
DQ<2> 
DQ<1> 
VDDSPD 
SA<2> 
SA<1> 
SA<0> 
SDA 
SCL 
VREFCA 
ACT_N ALERT_N 
A2 
DQ<51> 
DQ<41> 
DQ<44> DQ<45> 
A6 
A7 A8 
CB<2> CB<3> CB<4> CB<5> 
DQ<28> 
DQ<27> 
DQ<18> DQ<19> 
DQ<21> 
ODT<0> ODT<1> 
CKE<0> 
CKE<1> 
S0_N S1_N S2_N_C<0> S3_N_C<1> 
DQ<50> 
DQ<58> 
DQ<60> A15_CAS_N A16_RAS_N A17 
DQ<6> DQ<7> DQ<8> DQ<9> DQ<10> DQ<11> DQ<12> 
PVDDQ (SINGLE SIDE) CAP: 10UF X1, 22UF X50 
PVDDQ (DOUBLE SIDE) CAP: 100UF X8, 47UF X41 
PVPP CAP: 10UF X12 
PVTT CAP: 100UF X2, 47UF X1 
STUFF FOR SKU A & B 
CPU1 DDR4 CH L DIMM0 
CAP BETWEEN DIMM 
Wed Feb 08 16:34:53 2017 
PLACE CAP NEAR DIMM CONNECTOR 
WIWYNN CORPORATION 
SMBUS ADDR: 0XA4 
2/4 
3/4 4/4 
1/4 



63 
178 
105 
TP_CH_L_DIMM0_RFU_2 
M_L_MA<17:0> 
111 
11 
10 
164 
163 
153 
280 
135 
58 
57 
J9L2 
M_L_DQ<63:0> 
269 30 11 
M_L_ACT_N 
M_L_VREF 
TP_CH_L_DIMM0_RFU_0 
TP_CH_L_DIMM0_RFU_1 
SMB_DDR_KLM_VPP_SCL 
M_L_ALERT_N 
FM_ADR_COMPLETE_KLM_N 
FM_DIMM_EVENT_COD_N 
M_KLM_RST_N 
M_L_PAR 
M_L_C<2> 
M_L_DQS_DN<17:0> 
M_L_DQS_DP<17:0> 
M_L_CLK_DN<3:0> 
M_L_CLK_DP<3:0> 
M_L_BG<1:0> 
M_L_BA<1:0> 
M_L_ODT<3:0> 
M_L_CKE<3:0> 
M_L_ECC<7:0> 
M_L_CS_N<7:0> 
42 
43 
46 
45 
44 
41 
39 
40 
37 
38 
32 
33 
36 
34 
35 
30 
31 
29 
28 
27 
23 
22 
26 
24 
25 
19 
20 
21 
17 
18 
14 
15 
16 
13 
12 
9
11 
7
8
6
10 
J9L2 
145 
1
236 
233 
231 
229 
226 
223 
220 
217 
215 
212 
209 
206 
204 
92 
90 
88 
85 
83 
80 
76 
73 
70 
67 
64 
61 
59 
287 
286 
288 
143 
142 
221 
77 
SCONN 
H44441-003 
3
5
2
1
4
0
0
1
1
0
0
3
2
3
6
7
4
5
2
3
2
2
3
7
6
5
4
2
3
X7R 
25V 
0402V 
10% 
0.01UF 
A36096-045 
C1A17 
0
17 
15 
16 
17 
14 
13 
16 
15 
13 
1
14 
12 
12 
10 
8
7
9
8
9
7
5
6
3
2
4
6
4
5
3
2
1
0
1
0
SCONN 
J9L2 
191 
15 
283 
281 
279 
276 
274 
272 
270 
268 
265 
263 
261 
259 
257 
254 
252 
250 
248 
246 
243 
241 
239 
202 
200 
198 
195 
193 
189 
187 
184 
182 
180 
176 
173 
171 
169 
167 
165 
162 
160 
158 
156 
154 
151 
149 
147 
138 
136 
134 
131 
129 
127 
125 
123 
120 
118 
116 
114 
112 
109 
107 
103 
101 
98 
96 
94 
57 
55 
53 
50 
48 
46 
44 
42 
39 
37 
35 
33 
31 
28 
26 
24 
22 
20 
17 
13 
11 
9
6
4
2
H44441-003 
61 
60 
62 
59 
54 
53 
56 
55 
52 
48 
47 
49 
51 
271 
5
79 
72 
216 
71 
214 
213 
69 
211 
68 
66 
225 
210 
65 
232 
228 
86 
82 
62 
208 
81 
224 
63 
207 
235 
49 
194 
56 
201 
47 
192 
54 
199 
75 
74 
219 
218 
60 
203 
150 
12 
157 
3
148 
10 
155 
16 
161 
23 
168 
14 
159 
21 
166 
27 
172 
34 
179 
25 
170 
32 
177 
38 
183 
45 
190 
36 
181 
43 
188 
97 
242 
104 
249 
95 
240 
102 
247 
108 
253 
115 
260 
106 
251 
113 
258 
119 
264 
126 
117 
262 
124 
130 
275 
137 
282 
128 
273 
78 
87 
91 
222 
58 
205 
227 
144 
84 
89 
93 
237 
139 
140 
238 
230 
141 
285 
284 
146 
SCONN 
H44441-003 
J9L2 
234 
50 
17 
16 
15 
14 
12 
13 
11 
10 
9
SMB_DDR_KLM_VPP_SDA 
7
8
6
4
5
3
2
1
277 
152 
174 
175 
185 
186 
244 
245 
255 
256 
266 
267 
278 
196 
197 
8
7
19 
18 
29 
41 
40 
100 
99 
110 
122 
121 
133 
132 
52 
51 
SCONN 
H44441-003 
61 85 61 85 
61 85 
100 85 
99 83 84 85 87 88 
85 61 
89 83 84 85 87 88 
43 44 45 46 47 48 49 50 51 52 
53 54 77 78 79 80 81 82 83 84 
85 87 88 94 
55 83 84 85 87 88 
61 85 
61 85 
61 85 
61 85 
61 85 
61 85 
61 85 
61 85 
61 85 
61 85 
61 85 
61 85 
83 84 85 87 88 99 
BOM NOTE: 
DO NOT SCALE DRAWING 
SCONN288_H44441003 
SCONN288_H44441003 
SCONN288_H44441003 
SCONN288_H44441003 
SHEET 
B
AA
B
B
SIZE 
SCALE: 
234
1234
DEPARTMENT CODE 
1
DOCUMENT NUMBER REV 
PVPP_KLM 
IN 
OUT 
PVTT_KLM 
PVDDQ_KLM 
IN 
OUT 
PVPP_KLM 
IN 
IN 
IN 
IN 
IN 
IN 
IN 
IN 
P12V_NVDIMM_KLM 
BI 
BI 
IN 
IN 
BI 
BI 
IN 
BI 
IN 
IN 
86 OF 270 
Wed Feb 08 16:34:53 2017 
VDD<25> 
VDD<24> 
VDD<23> 
VDD<22> 
VDD<21> 
VDD<20> 
VDD<19> 
VDD<18> 
VDD<17> 
VDD<16> 
VDD<15> 
VDD<14> 
VDD<13> 
VDD<12> 
VDD<11> 
VDD<10> 
VDD<9> 
VDD<8> 
VDD<7> 
VDD<6> 
VDD<5> 
VDD<4> 
VDD<3> 
VDD<2> 
VDD<1> 
VDD<0> 
VPP<1> 
VPP<0> 
VTT<1> 
VTT<0> 
VPP<4> 
VPP<3> 
VPP<2> 12V<0> 12V<1> 
VSS<83> 
VSS<82> 
VSS<81> 
VSS<80> 
VSS<79> 
VSS<78> 
VSS<77> 
VSS<76> 
VSS<75> 
VSS<74> 
VSS<73> 
VSS<72> 
VSS<71> 
VSS<70> 
VSS<69> 
VSS<68> 
VSS<93> 
VSS<92> 
VSS<91> 
VSS<90> 
VSS<89> 
VSS<88> 
VSS<87> 
VSS<86> 
VSS<85> 
VSS<84> 
VSS<67> 
VSS<66> 
VSS<65> 
VSS<64> 
VSS<63> 
VSS<62> 
VSS<61> 
VSS<60> 
VSS<59> 
VSS<58> 
VSS<57> 
VSS<56> 
VSS<55> 
VSS<54> 
VSS<53> 
VSS<52> 
VSS<51> 
VSS<50> 
VSS<49> 
VSS<48> 
VSS<47> 
VSS<46> 
VSS<45> 
VSS<44> 
VSS<43> 
VSS<42> 
VSS<41> 
VSS<40> 
VSS<39> 
VSS<38> 
VSS<37> 
VSS<36> 
VSS<35> 
VSS<34> 
VSS<33> 
VSS<32> 
VSS<31> 
VSS<30> 
VSS<29> 
VSS<28> 
VSS<27> 
VSS<26> 
VSS<25> 
VSS<24> 
VSS<23> 
VSS<22> 
VSS<21> 
VSS<20> 
VSS<19> 
VSS<18> 
VSS<17> 
VSS<16> 
VSS<15> 
VSS<14> 
VSS<13> 
VSS<12> 
VSS<11> 
VSS<10> VSS<9> 
VSS<8> 
VSS<7> 
VSS<6> 
VSS<5> 
VSS<4> 
VSS<3> 
VSS<2> 
VSS<1> 
VSS<0> 
DQ<12> 
DQ<11> 
DQ<10> DQ<9> 
DQ<8> 
DQ<7> 
DQ<6> 
A17 
A16_RAS_N 
A15_CAS_N DQ<60> 
DQ<58> 
DQ<50> 
S3_N_C<1> 
S2_N_C<0> 
S1_N 
S0_N 
CKE<1> 
CKE<0> 
ODT<1> 
ODT<0> 
DQ<21> 
DQ<19> 
DQ<18> 
DQ<27> 
DQ<28> 
CB<5> 
CB<4> 
CB<3> 
CB<2> 
A8 
A7 
A6 
DQ<45> 
DQ<44> 
DQ<41> 
DQ<51> 
A2 
ALERT_N 
ACT_N 
VREFCA 
SCL SDA SA<0> SA<1> SA<2> VDDSPD 
DQ<1> 
DQ<2> 
RFU<2> 
DQ<31> DQ<32> DQ<33> DQ<34> DQ<35> DQ<36> DQ<37> DQ<38> 
A0 A1 
A10 A11 A12 A13 A14_WE_N 
A3 A4 A5 
A9 
BG<1> 
C<2> 
CB<7> 
CB<6> 
CB<1> 
CB<0> 
DQ<63> 
DQ<62> 
DQ<61> 
DQ<59> 
DQ<57> 
DQ<56> 
DQ<55> 
DQ<54> 
DQ<53> 
DQ<52> 
DQ<49> 
DQ<48> 
DQ<47> 
DQ<46> 
DQ<43> 
DQ<40> 
DQ<39> 
DQ<30> 
DQ<26> 
DQ<25> 
DQ<24> 
DQ<23> 
DQ<22> 
DQ<20> 
DQ<17> 
DQ<16> 
DQ<15> 
DQ<14> 
DQ<13> 
DQ<5> 
DQ<4> 
DQ<3> 
DQ<0> 
EVENT_N 
PAR 
RESET_N 
RFU<1> 
RFU<0> 
SAVE_N_NC 
BG<0> 
CK1P 
CK1N 
CK0P 
CK0N 
DQ<29> 
DQ<42> BA<0> BA<1> 
DQS0N DQS0P 
DQS10N 
DQS10P DQS11N DQS11P DQS12N DQS12P DQS13N DQS13P DQS14N DQS14P DQS15N DQS15P DQS16N DQS16P 
DQS17N DQS17P 
DQS1N DQS1P DQS2N DQS2P DQS3N DQS3P 
DQS4N DQS4P DQS5N DQS5P DQS6N DQS6P DQS7N DQS7P DQS8N DQS8P DQS9N DQS9P 
PVDDQ (SINGLE SIDE) CAP: 10UF X1, 22UF X50 PVTT CAP: 100UF X2, 47UF X1 
PVDDQ (DOUBLE SIDE) CAP: 100UF X8, 47UF X41 
PVPP CAP: 10UF X12 
BOM_SS=NOPOP 
BOM_SS=NOPOP 
BOM_SS=NOPOP 
BOM_SS=NOPOP 
UNSTUFF FOR SKU B 
CPU1 DDR4 CH L DIMM1 
CAP BETWEEN DIMM 
PLACE CAP NEAR DIMM CONNECTOR 
WIWYNN CORPORATION 
SMBUS ADDR: 0XA6 4/4 3/4 
1/4 
2/4 



129 
95 
171 
107 
M_M_MA<17:0> 
242 
109 
62 
M_M_ACT_N 
M_M_ALERT_N 
M_M_C<2> 
FM_DIMM_EVENT_COD_N 
M_M_PAR 
M_KLM_RST_N 
FM_ADR_COMPLETE_KLM_N 
SMB_DDR_KLM_VPP_SCL 
TP_CH_M_DIMM_M0_RFU_2 
TP_CH_M_DIMM_M0_RFU_0 
TP_CH_M_DIMM_M0_RFU_1 
M_M_VREF 
M_M_ODT<3:0> 
M_M_BG<1:0> 
M_M_CKE<3:0> 
M_M_ECC<7:0> 
M_M_BA<1:0> 
M_M_CLK_DP<3:0> 
M_M_CLK_DN<3:0> 
M_M_CS_N<7:0> 
M_M_DQ<63:0> 
M_M_DQS_DN<17:0> 
M_M_DQS_DP<17:0> 
11 
9
14 
15 
16 
17 
12 
21 
18 
20 
23 
19 
25 
24 
27 
29 
26 
22 
30 
12 
31 
28 
33 
32 
35 
34 
37 
36 
39 
38 
13 
40 
41 
43 
42 
0
4
5
2
1
3
14 
10 
9
6
7
8
44 
45 
47 
49 
46 
15 
50 
51 
53 
52 
48 
57 
54 
59 
56 
55 
16 
61 
60 
63 
58 
14 
15 
11 
12 
17 
13 
16 
17 
0
2
1
3
4
152 
153 
163 
164 
174 
175 
185 
186 
244 
245 
255 
256 
266 
267 
277 
278 
196 
197 
8
7
19 
18 
30 
29 
41 
40 
100 
99 
111 
110 
122 
121 
133 
132 
52 
51 
SCONN 
H44441-004 
J1A1 
J1A1 
232 
210 
225 
108 
247 
79 
72 
216 
71 
214 
213 
69 
211 
68 
66 
65 
228 
86 
82 
62 
208 
81 
224 
63 
207 
235 
49 
194 
56 
201 
47 
192 
54 
199 
75 
74 
219 
218 
60 
203 
5
150 
12 
157 
3
148 
10 
155 
16 
161 
23 
168 
14 
159 
21 
166 
27 
172 
34 
179 
25 
170 
32 
177 
38 
183 
45 
190 
36 
181 
43 
188 
97 
104 
249 
240 
102 
253 
115 
260 
106 
251 
113 
258 
119 
264 
126 
271 
117 
262 
124 
269 
130 
275 
137 
282 
128 
273 
135 
280 
78 
87 
91 
222 
58 
205 
227 
144 
84 
89 
93 
237 
139 
140 
238 
230 
141 
285 
284 
146 
SCONN 
H44441-004 
234 
J1A1 
173 
283 
281 
279 
276 
274 
272 
270 
268 
265 
263 
261 
259 
257 
254 
252 
250 
248 
246 
243 
241 
239 
202 
200 
198 
195 
193 
191 
189 
187 
184 
182 
180 
178 
176 
169 
167 
165 
162 
160 
158 
156 
154 
151 
149 
147 
138 
136 
134 
131 
127 
125 
123 
120 
118 
116 
114 
112 
105 
103 
101 
98 
96 
94 
57 
55 
53 
50 
48 
46 
44 
42 
39 
37 
35 
33 
31 
28 
26 
24 
22 
20 
17 
15 
13 
11 
9
6
4
2
SCONN 
H44441-004 
5
2
1
X7R 
25V 
0402V 
10% 
0.01UF 
A36096-045 
C1A5 
SMB_DDR_KLM_VPP_SDA 
6
145 
1
236 
233 
231 
229 
226 
223 
220 
217 
215 
212 
209 
206 
204 
92 
90 
88 
85 
83 
80 
76 
73 
70 
67 
64 
61 
59 
287 
286 
288 
143 
142 
221 
77 
SCONN 
H44441-004 
J1A1 
0
1
0
1
0
1
7
2
3
0
1
0
1
8
1
0
3
2
5
4
9
6
7
1
0
0
1
10 
0
1
2
3
4
5
6
7
9
8
11 
10 
11 
12 
13 
14 
15 
17 
16 
0
3
1
2
5
4
7
6
13 
10 
8
62 88 
62 88 
88 62 
62 88 
43 44 45 46 47 48 49 50 51 52 
53 54 77 78 79 80 81 82 83 84 
85 86 88 94 
62 88 
55 83 84 85 86 88 
89 83 84 85 86 88 
99 83 84 85 86 88 
100 88 
62 88 
62 88 
62 88 
62 88 
62 88 
62 88 
62 88 
62 88 
62 88 
62 88 
62 88 
83 84 85 86 88 99 
BOM NOTE: 
DO NOT SCALE DRAWING 
SCONN288_H44441004 
SCONN288_H44441004 
SCONN288_H44441004 
SCONN288_H44441004 
SHEET 
B
AA
B
B
SIZE 
SCALE: 
234
1234
DEPARTMENT CODE 
1
DOCUMENT NUMBER REV 
PVTT_KLM 
BI 
BI 
P12V_NVDIMM_KLM 
IN 
PVPP_KLM 
PVPP_KLM 
IN 
IN 
BI 
OUT 
IN 
IN 
IN 
IN 
IN 
BI 
IN 
OUT 
IN 
IN 
IN 
IN 
IN 
IN 
PVDDQ_KLM 
BI 
87 OF 270 
Wed Feb 08 16:34:54 2017 
DQS9P DQS9N DQS8P DQS8N DQS7P DQS7N DQS6P DQS6N DQS5P DQS5N DQS4P DQS4N 
DQS3P DQS3N DQS2P DQS2N DQS1P DQS1N 
DQS17P DQS17N DQS16P 
DQS16N DQS15P DQS15N DQS14P DQS14N DQS13P DQS13N DQS12P DQS12N DQS11P DQS11N DQS10P DQS10N 
DQS0P DQS0N 
BA<1> 
BA<0> DQ<42> 
DQ<29> 
CK0N CK0P CK1N CK1P 
BG<0> 
SAVE_N_NC 
RFU<0> RFU<1> 
RESET_N PAR 
EVENT_N 
DQ<0> 
DQ<3> DQ<4> DQ<5> 
DQ<13> DQ<14> 
DQ<15> DQ<16> DQ<17> 
DQ<20> 
DQ<22> DQ<23> DQ<24> DQ<25> DQ<26> 
DQ<30> 
DQ<39> DQ<40> 
DQ<43> 
DQ<46> DQ<47> DQ<48> DQ<49> 
DQ<52> 
DQ<53> DQ<54> DQ<55> DQ<56> DQ<57> 
DQ<59> 
DQ<61> DQ<62> DQ<63> 
CB<0> CB<1> 
CB<6> CB<7> 
C<2> 
BG<1> 
A9 
A5 
A4 
A3 
A14_WE_N 
A13 
A12 
A11 
A10 
A1 
A0 
DQ<38> 
DQ<37> 
DQ<36> 
DQ<35> 
DQ<34> 
DQ<33> 
DQ<32> 
DQ<31> 
RFU<2> 
DQ<2> 
DQ<1> 
VDDSPD 
SA<2> 
SA<1> 
SA<0> 
SDA 
SCL 
VREFCA 
ACT_N ALERT_N 
A2 
DQ<51> 
DQ<41> 
DQ<44> DQ<45> 
A6 
A7 A8 
CB<2> CB<3> CB<4> CB<5> 
DQ<28> 
DQ<27> 
DQ<18> DQ<19> 
DQ<21> 
ODT<0> ODT<1> 
CKE<0> 
CKE<1> 
S0_N S1_N S2_N_C<0> S3_N_C<1> 
DQ<50> 
DQ<58> 
DQ<60> A15_CAS_N A16_RAS_N A17 
DQ<6> DQ<7> DQ<8> DQ<9> DQ<10> DQ<11> DQ<12> 
VSS<0> VSS<1> VSS<2> VSS<3> VSS<4> VSS<5> VSS<6> VSS<7> VSS<8> VSS<9> VSS<10> 
VSS<11> VSS<12> VSS<13> VSS<14> VSS<15> VSS<16> VSS<17> VSS<18> VSS<19> VSS<20> VSS<21> VSS<22> VSS<23> 
VSS<24> VSS<25> VSS<26> VSS<27> VSS<28> VSS<29> VSS<30> VSS<31> VSS<32> VSS<33> VSS<34> VSS<35> VSS<36> 
VSS<37> VSS<38> VSS<39> VSS<40> VSS<41> VSS<42> VSS<43> VSS<44> 
VSS<47> VSS<48> VSS<49> VSS<50> VSS<51> VSS<52> VSS<53> VSS<54> VSS<55> VSS<56> VSS<57> 
VSS<58> VSS<59> VSS<60> VSS<61> VSS<62> VSS<63> VSS<64> VSS<65> VSS<66> VSS<67> 
VSS<84> VSS<85> VSS<86> VSS<87> VSS<88> VSS<89> VSS<90> VSS<91> VSS<92> VSS<93> 
VSS<68> VSS<69> VSS<70> 
VSS<71> VSS<72> VSS<73> VSS<74> VSS<75> VSS<76> VSS<77> VSS<78> VSS<79> VSS<80> VSS<81> VSS<82> VSS<83> 
VSS<45> VSS<46> 
12V<0> VPP<2> 
VPP<4> 
VTT<0> VTT<1> 
VPP<0> VPP<1> 
VDD<0> VDD<1> VDD<2> VDD<3> VDD<4> VDD<5> VDD<6> VDD<7> VDD<8> VDD<9> VDD<10> VDD<11> VDD<12> 
VDD<13> VDD<14> VDD<15> VDD<16> VDD<17> VDD<18> VDD<19> VDD<20> VDD<21> VDD<22> VDD<23> VDD<24> VDD<25> 
12V<1> VPP<3> 
PVDDQ (SINGLE SIDE) CAP: 10UF X1, 22UF X50 
PVDDQ (DOUBLE SIDE) CAP: 100UF X8, 47UF X41 
PVTT CAP: 100UF X2, 47UF X1 PVPP CAP: 10UF X12 
STUFF FOR SKU A & B 
CPU1 DDR4 CH M DIMM0 
CAP BETWEEN DIMM 
PLACE CAP NEAR DIMM CONNECTOR 
WIWYNN CORPORATION 
SMBUS ADDR: 0XA8 
2/4 
1/4 
3/4 
4/4 



127 
M_M_DQ<63:0> 
SCONN 
105 
M_M_VREF 
J9L1 
153 
61 
63 
172 
16 
3
15 
246 
248 
107 
M_M_MA<17:0> 
TP_CH_M_DIMM_M1_RFU_2 
TP_CH_M_DIMM_M1_RFU_0 
TP_CH_M_DIMM_M1_RFU_1 
SMB_DDR_KLM_VPP_SCL 
FM_ADR_COMPLETE_KLM_N 
FM_DIMM_EVENT_COD_N 
M_M_PAR 
M_KLM_RST_N 
M_M_C<2> 
M_M_ACT_N 
M_M_ALERT_N 
M_M_DQS_DP<17:0> 
M_M_CLK_DN<3:0> 
M_M_CLK_DP<3:0> 
M_M_ODT<3:0> 
M_M_BG<1:0> 
M_M_CKE<3:0> 
M_M_ECC<7:0> 
M_M_CS_N<7:0> 
M_M_BA<1:0> 
M_M_DQS_DN<17:0> 
10 
8
15 
14 
17 
13 
20 
19 
21 
22 
18 
186 
164 
152 
163 
174 
175 
185 
244 
245 
255 
256 
266 
267 
277 
278 
196 
197 
8
7
19 
18 
30 
29 
41 
40 
100 
99 
111 
110 
122 
121 
133 
132 
52 
51 
SCONN 
H44441-003 
J9L1 
24 
25 
26 
28 
27 
23 
31 
12 
30 
29 
32 
33 
34 
35 
36 
37 
38 
39 
13 
41 
40 
42 
43 
0
4
5
2
1
3
14 
10 
9
6
7
8
45 
44 
46 
48 
47 
15 
51 
50 
52 
53 
49 
56 
55 
58 
57 
54 
16 
60 
62 
59 
14 
15 
11 
12 
17 
13 
16 
17 
J9L1 
6
9
11 
272 
24 
283 
281 
279 
276 
274 
270 
268 
265 
263 
261 
259 
257 
254 
252 
250 
243 
241 
239 
202 
200 
198 
195 
193 
191 
189 
187 
184 
182 
180 
178 
176 
173 
171 
169 
167 
165 
162 
160 
158 
156 
154 
151 
149 
147 
138 
136 
134 
131 
129 
125 
123 
120 
118 
116 
114 
112 
109 
103 
101 
98 
96 
94 
57 
55 
53 
50 
48 
46 
44 
42 
39 
37 
35 
33 
31 
28 
26 
22 
20 
17 
13 
4
2
SCONN 
H44441-003 
0
2
1
4
3
3
5
2
1
X7R 
25V 
0402V 
10% 
0.01UF 
A36096-045 
C9L1 
SMB_DDR_KLM_VPP_SDA 
6
145 
1
236 
233 
231 
229 
226 
223 
220 
217 
215 
212 
209 
206 
204 
92 
90 
88 
85 
83 
80 
76 
73 
70 
67 
64 
61 
59 
287 
286 
288 
143 
142 
221 
77 
H44441-003 
2
3
2
3
4
5
6
7
7
2
2
8
0
1
2
3
4
5
9
7
6
1
0
0
1
10 
0
1
2
3
4
5
6
7
9
8
11 
10 
11 
12 
13 
14 
15 
17 
16 
232 
228 
79 
72 
216 
71 
214 
213 
69 
211 
68 
66 
225 
210 
65 
86 
82 
234 
62 
208 
81 
224 
63 
207 
235 
49 
194 
56 
201 
47 
192 
54 
199 
75 
74 
219 
218 
60 
203 
5
150 
12 
157 
3
148 
10 
155 
16 
161 
23 
168 
14 
159 
21 
166 
27 
34 
179 
25 
170 
32 
177 
38 
183 
45 
190 
36 
181 
43 
188 
97 
242 
104 
249 
95 
240 
102 
247 
108 
253 
115 
260 
106 
251 
113 
258 
119 
264 
126 
271 
117 
262 
124 
269 
130 
275 
137 
282 
128 
273 
135 
280 
78 
87 
91 
222 
58 
205 
227 
144 
84 
89 
93 
237 
139 
140 
238 
230 
141 
285 
284 
146 
SCONN 
H44441-003 
J9L1 
1
2
0
3
4
5
6
7
12 
11 
9
62 87 
100 87 
62 87 
99 83 84 85 86 87 
89 83 84 85 86 87 
43 44 45 46 47 48 49 50 51 52 
53 54 77 78 79 80 81 82 83 
84 85 86 87 94 
62 87 
55 83 84 85 86 87 
62 87 
62 87 
87 62 
62 87 
62 87 
62 87 
62 87 
62 87 
62 87 
62 87 
62 87 
62 87 
62 87 
83 84 85 86 87 99 
BOM NOTE: 
DO NOT SCALE DRAWING 
SCONN288_H44441003 
SCONN288_H44441003 
SCONN288_H44441003 
SCONN288_H44441003 
SHEET 
B
AA
B
B
SIZE 
SCALE: 
234
1234
DEPARTMENT CODE 
1
DOCUMENT NUMBER REV 
PVTT_KLM 
BI 
BI 
P12V_NVDIMM_KLM 
IN 
PVPP_KLM 
PVPP_KLM 
OUT 
BI 
IN 
IN 
IN 
IN 
IN 
IN 
IN 
BI 
IN 
OUT 
IN 
IN 
IN 
IN 
IN 
IN 
PVDDQ_KLM 
BI 
88 OF 270 
Wed Feb 08 16:34:54 2017 
DQS0N DQS0P 
DQS10N DQS10P DQS11N DQS11P DQS12N DQS12P DQS13N DQS13P DQS14N DQS14P DQS15N DQS15P DQS16N 
DQS16P DQS17N DQS17P 
DQS1N DQS1P DQS2N DQS2P DQS3N DQS3P 
DQS4N DQS4P DQS5N DQS5P DQS6N DQS6P DQS7N DQS7P DQS8N DQS8P DQS9N DQS9P 
VSS<83> 
VSS<82> 
VSS<81> 
VSS<80> 
VSS<79> 
VSS<78> 
VSS<77> 
VSS<76> 
VSS<75> 
VSS<74> 
VSS<73> 
VSS<72> 
VSS<71> 
VSS<70> 
VSS<69> 
VSS<68> 
VSS<93> 
VSS<92> 
VSS<91> 
VSS<90> 
VSS<89> 
VSS<88> 
VSS<87> 
VSS<86> 
VSS<85> 
VSS<84> 
VSS<67> 
VSS<66> 
VSS<65> 
VSS<64> 
VSS<63> 
VSS<62> 
VSS<61> 
VSS<60> 
VSS<59> 
VSS<58> 
VSS<57> 
VSS<56> 
VSS<55> 
VSS<54> 
VSS<53> 
VSS<52> 
VSS<51> 
VSS<50> 
VSS<49> 
VSS<48> 
VSS<47> 
VSS<46> 
VSS<45> 
VSS<44> 
VSS<43> 
VSS<42> 
VSS<41> 
VSS<40> 
VSS<39> 
VSS<38> 
VSS<37> 
VSS<36> 
VSS<35> 
VSS<34> 
VSS<33> 
VSS<32> 
VSS<31> 
VSS<30> 
VSS<29> 
VSS<28> 
VSS<27> 
VSS<26> 
VSS<25> 
VSS<24> 
VSS<23> 
VSS<22> 
VSS<21> 
VSS<20> 
VSS<19> 
VSS<18> 
VSS<17> 
VSS<16> 
VSS<15> 
VSS<14> 
VSS<13> 
VSS<12> 
VSS<11> 
VSS<10> VSS<9> 
VSS<8> 
VSS<7> 
VSS<6> 
VSS<5> 
VSS<4> 
VSS<3> 
VSS<2> 
VSS<1> 
VSS<0> 
VDD<25> 
VDD<24> 
VDD<23> 
VDD<22> 
VDD<21> 
VDD<20> 
VDD<19> 
VDD<18> 
VDD<17> 
VDD<16> 
VDD<15> 
VDD<14> 
VDD<13> 
VDD<12> 
VDD<11> 
VDD<10> 
VDD<9> 
VDD<8> 
VDD<7> 
VDD<6> 
VDD<5> 
VDD<4> 
VDD<3> 
VDD<2> 
VDD<1> 
VDD<0> 
VPP<1> 
VPP<0> 
VTT<1> 
VTT<0> 
VPP<4> 
VPP<3> 
VPP<2> 12V<0> 12V<1> 
DQ<12> 
DQ<11> 
DQ<10> DQ<9> 
DQ<8> 
DQ<7> 
DQ<6> 
A17 
A16_RAS_N 
A15_CAS_N DQ<60> 
DQ<58> 
DQ<50> 
S3_N_C<1> 
S2_N_C<0> 
S1_N 
S0_N 
CKE<1> 
CKE<0> 
ODT<1> 
ODT<0> 
DQ<21> 
DQ<19> 
DQ<18> 
DQ<27> DQ<28> 
CB<5> 
CB<4> 
CB<3> 
CB<2> 
A8 
A7 
A6 
DQ<45> 
DQ<44> 
DQ<41> 
DQ<51> 
A2 
ALERT_N 
ACT_N 
VREFCA 
SCL SDA SA<0> 
SA<1> SA<2> VDDSPD 
DQ<1> DQ<2> 
RFU<2> 
DQ<31> DQ<32> DQ<33> DQ<34> DQ<35> DQ<36> DQ<37> DQ<38> 
A0 A1 
A10 A11 A12 A13 A14_WE_N 
A3 A4 A5 
A9 
BG<1> 
C<2> 
CB<7> 
CB<6> 
CB<1> 
CB<0> 
DQ<63> 
DQ<62> 
DQ<61> 
DQ<59> 
DQ<57> 
DQ<56> 
DQ<55> 
DQ<54> 
DQ<53> 
DQ<52> 
DQ<49> 
DQ<48> 
DQ<47> 
DQ<46> 
DQ<43> 
DQ<40> 
DQ<39> 
DQ<30> 
DQ<26> 
DQ<25> 
DQ<24> 
DQ<23> 
DQ<22> 
DQ<20> 
DQ<17> 
DQ<16> 
DQ<15> 
DQ<14> 
DQ<13> 
DQ<5> 
DQ<4> 
DQ<3> 
DQ<0> 
EVENT_N 
PAR 
RESET_N 
RFU<1> 
RFU<0> 
SAVE_N_NC 
BG<0> 
CK1P 
CK1N 
CK0P 
CK0N 
DQ<29> 
DQ<42> BA<0> 
BA<1> 
PVDDQ (SINGLE SIDE) CAP: 10UF X1, 22UF X50 
PVDDQ (DOUBLE SIDE) CAP: 100UF X8, 47UF X41 
PVTT CAP: 100UF X2, 47UF X1 PVPP CAP: 10UF X12 
BOM_SS=NOPOP 
BOM_SS=NOPOP 
BOM_SS=NOPOP 
BOM_SS=NOPOP 
UNSTUFF FOR SKU B 
CPU1 DDR4 CH M DIMM1 
CAP BETWEEN DIMM 
PLACE CAP NEAR DIMM CONNECTOR 
WIWYNN CORPORATION 
SMBUS ADDR: 0XAA 
2/4 
3/4 4/4 
1/4 



WR8D30 
CHIP 
G21796-016 
IRQ_DIMM_SAVE_R_N 
IRQ_DIMM_SAVE_CPU1_R_N 
FM_ADR_SMI_GPIO_N 
IRQ_DIMM_SAVE_LVT3_CPU1 
IRQ_DIMM_SAVE_LVT3_N 
IRQ_DIMM_SAVE_LVT3 
FM_ADR_COMPLETE_CPU1_R 
FM_ADR_COMPLETE_R 
IRQ_DIMM_SAVE_N 
FM_ADR_COMPLETE_CPU0_R 
FM_ADR_COMPLETE 
2
1
0402 
CHIP 
1/16W 
1% 
10.0K 
R6F3 
R6F2 
1 2
G21796-047 
1/16W CHIP 
1% 
0402 
49.9 
G21497-028 
5% 330 
R1W31 
21
CHIP 0402 1/16W 
1
IC 
3
2
Q1W6 
C52245-001 
MMBT3904 
SM 
0402 
G21497-028 
R1W32 
CHIP 
5% 330 
1/16W 
1 2 MMBT3904 
Q1F1 1
3
SM 
IC 
2 C52245-001 
C52264-001 
3 MBT3904 
XSTR 
Q8W1 
4
5
C52264-001 
XSTR 
6
Q8W1 
2
1
MBT3904 
1/16W CHIP 
1% 
R6F5 
1 2
49.9 
G21796-047 
0402 
4.75K 
1/16W 
1% 
G21796-072 
0402 
CHIP 
R8W9 
6
Q8D1 
C52264-001 
2 XSTR 
1
MBT3904 
1
G21796-016 
2
CHIP 0402 
1% 
1/16W 
10.0K 
10.0K 
R6W29 
1
0402 
G21796-016 
CHIP 2
1% 
1/16W 
R6F1 
1/16W CHIP 
2
1% 
0402 
G21796-047 
1
49.9 
C52264-001 
4
5
3
Q8D1 
XSTR 
MBT3904 
1
R8D30 
10.0K 
1/16W 
G21796-016 
2
1% 
0402 CHIP 
49.9 
1 2
R6F4 
0402 
G21796-047 
1% 
1/16W 
1/16W 
CHIP 
4.75K 
1% 
R8D31 
G21796-072 
0402 
R8D29 
1% 
CHIP 
1/16W 
4.75K 
G21796-072 
0402 
0402 1/16W 
G21497-005 
5% 
R2P12 
EMPTY 0.0 
1/16W CHIP 0402 
G21497-005 
R4T1 
21
5% 0.0 
FM_ADR_COMPLETE_KLM_N 
FM_ADR_COMPLETE_GHJ_N 
FM_ADR_COMPLETE_DEF_N 
FM_ADR_COMPLETE_ABC_N 
FM_ADR_COMPLETE_DLY 
EMPTY 0402 1/16W 
G21497-005 
2
R4T2 
1
0.0 5% 
TP FAB1 CHANGE MOS TO BJT 0406 
156 157 191 120 
120 145 
120 191 
83 84 85 86 87 88 
77 78 79 80 81 82 
49 50 51 52 53 54 
43 44 45 46 47 48 
191 
FM_ADR_COMPLETE_CPU1_N 
1
2
DO NOT SCALE DRAWING SHEET 
B
AA
B
B
SIZE 
SCALE: 
234
1234
DEPARTMENT CODE 
1
DOCUMENT NUMBER REV 
IN 
P3V3_STBY 
PVPP_ABC 
OUT 
P3V3_STBY 
P3V3_STBY 
OUT 
PVPP_ABC 
OUT 
OUT 
OUT 
OUT 
IN 
89 OF 270 
Wed Feb 08 16:34:54 2017 
NVDIMM INTERNAL R-PULLUP TO VPP (2.5V) IS 2 K OHM TO SUPPORT UP TO 6 NVDIMM LOADS TOTAL ON ALL FM_ADR_COMPLETE_XXX_N NETS 
TP FAB1 CHANGE Q8D1 BACK AS CRB 0406 
TP FAB1 CHANGE ADD BJT AND RES 0406 
ROOM=NVDIMM 
BOM_COST=MEM_NV 
TP FAB1 ADD MOS AND RES 0401 
TP FAB1 ADD DUAL RES 0405 
TP FAB1 CHANGE MOS TO BJT 0406 
TP FAB1 ADD RES 0406 
TP FAB1 CHANGE TO SINGLE BJT 0405 
IMPORTANT DESIGN NOTE: 
NVDIMM SUPPORT 
WIWYNN CORPORATION 



H_CPU0_BMCINIT 
R4P1 
PU_CPU0_SOCKET_ID_0 
PU_CPU0_SAFE_MODE_BOOT 
EMPTY 
G21796-294 
PU_CPU1_TXT_AGENT 
PU_CPU0_SOCKET_ID_1 
PU_CPU1_SAFE_MODE_BOOT 
PD_CPU0_TEST12 
PD_CPU0_TEST13 
PD_CPU0_TEST14 
PU_CPU0_LEGACY_SKT 
PD_CPU0_EAR_N 
PU_CPU0_FRMAGENT 
PD_CPU1_EAR_N 
PU_CPU1_LEGACY_SKT 
PU_CPU0_TXT_AGENT 
PD_CPU1_KSFC_DIS 
PD_CPU1_DMIMODE_OVERRIDE 
PU_CPU1_FRMAGENT 
H_CPU1_BMCINIT 
PD_CPU1_BIST_ENABLE 
PD_CPU1_TEST12 
PD_CPU0_KSFC_DIS 
PD_CPU1_TEST13 
PD_CPU1_TEST14 
PD_CPU0_DMIMODE_OVERRIDE 
PD_CPU0_TXT_PLTEN 
PD_CPU0_BIST_ENABLE 
PU_CPU1_SOCKET_ID_1 
PU_CPU1_SOCKET_ID_0 
PD_CPU1_TXT_PLTEN 
G21796-294 
0402 EMPTY 
1
1.0% 
2
240 
R3D13 
1/16W 
0402 
G21796-294 
240 1.0% 
1 2
EMPTY 1/16W 
G21796-294 
CHIP 
2
1/16W 240 1.0% 0402 
R5D4 1
1/16W 49.9 
1
G21796-047 
2
1% 
R3D9 
0402 CHIP 
1/16W 49.9 
1
R8P2 
CHIP G21796-047 0402 1% 
2
1/16W 
R8P1 
G21796-047 
2
1% 49.9 
1
0402 CHIP 
1/16W G21796-047 
2
R6D5 
1
CHIP 0402 49.9 1% 
1/16W G21796-047 49.9 1% CHIP 0402 
1
R5P3 
2
1/16W 49.9 
1
R5P2 
CHIP 0402 1% 
2
G21796-047 
G21796-294 
1.0% 240 
R7P22 
1/16W EMPTY 0402 
1 2
EMPTY 
G21796-294 
0402 1/16W 240 
21
1.0% 
R7P15 
0402 240 
R4P7 G21796-294 
EMPTY 
21
1/16W 1.0% 
0402 1/16W 
21
1.0% 
G21796-294 R4P6 
240 
G21796-294 R3D25 
240 1.0% 
1
1/16W EMPTY 0402 
2
G21796-294 
0402 240 
R3D17 
1.0% EMPTY 1/16W 
CHIP 
G21796-294 
1.0% 240 
R3D24 
1/16W 0402 
R4P14 
240 1.0% 
G21796-294 
1/16W CHIP 
2
0402 
1
2
1/16W 
G21796-294 
0402 EMPTY 
R6D14 
1.0% 
1
240 
1
0402 1/16W 
2R6D10 
1.0% 240 
G21796-294 
EMPTY 
1
1/16W 
2
240 0402 1.0% 
R6D15 G21796-294 
EMPTY 
G21796-294 
0402 
R6D13 
240 1.0% EMPTY 1/16W 
21
0402 EMPTY 1/16W 
21
1.0% 240 
R6D7 
240 
G21796-294 
1.0% 
R5D3 
1/16W 
1 2
0402 CHIP 
1.0% EMPTY 
R3D26 
240 
1 G21796-294 2
0402 1/16W 
G21796-294 
EMPTY 240 
R3D23 2
1/16W 
1
1.0% 0402 
G21796-294 
EMPTY 
R3D16 
0402 240 1.0% 
21
1/16W 
1.0% 1/16W 
G21796-294 
EMPTY 0402 
1 2
240 
R3D22 
1/16W 
R3D12 G21796-294 
0402 EMPTY 
1
1.0% 
2
240 
G21796-294 
1/16W 
R6D6 
240 1.0% 
1 2
0402 EMPTY 
R7P14 1
0402 CHIP 240 1.0% 
2
1/16W 
G21796-294 
156 21 
21 
21 
55 
21 
55 
21 
21 
21 
21 
21 
21 
55 
55 
21 
55 
56 
55 
156 55 
55 
55 
21 
55 
55 
22 
21 
21 
55 
55 
55 
PD 
(DEFAULT) PU/PD 
INTERNAL 
(DEFAULT) 
CPU0 CPU1 
DESIGN NOTE: 
CAD NOTE: 
CAD NOTE: 
21
21
(FOLLOW PDG P202) 
(FOLLOW PDG P202) 
DO NOT SCALE DRAWING SHEET 
B
AA
B
B
SIZE 
SCALE: 
234
1234
DEPARTMENT CODE 
1
DOCUMENT NUMBER REV 
OUT 
OUT 
OUT 
OUT 
OUT 
OUT 
OUT 
OUT 
OUT 
OUT 
OUT 
OUT 
OUT 
OUT 
OUT 
PVCCIO_CPU1 
PVCCIO_CPU1 
OUT 
IN 
IN 
OUT 
OUT 
PVCCIO_CPU0 
IN 
IN 
PVCCIO_CPU0 
OUT 
OUT 
OUT 
OUT 
OUT 
OUT 
OUT 
OUT 
MCI_SOCKET_ID[1..0] 
PD 
1
0
00 01 LEGACY CPU = 00 
0BMCINIT 
MCI_FRMAGENT 
MCI_TXT_PLTEN 
EAR_N 
LEGACY_SXT 
PU 
0: CPU IS NOT A TXT AGENT 
LEGACY CPU 
1: CPU HAULTS UNTIL BMC RELEASES BOOT FLOW 
0: NORMAL BOOT FLOW 
NOTE: MUST BE SET FOR ALL PROCESSORS 
0: TXT DISABLED 
IN THE SYSTEM 
CPU DMI PORT MODE 
0: PCIE MODE 
NON-LEGACY CPUS = 01 OR 10 OR 11 
NOTE: PIN SHOULD ONLY BE ASSERTED ON 
1: CPU IS TXT AGENT 
0: SAFE MODE BOOT DISABLED 
1: SAFE MODE BOOT ENABLED 
SAFE MODE BOOT (DISABLES CLOCK GATING) 
1
SKX PIN NAME 
MCI_TXT_AGENT PD 
0
DMIMODE_OVERRIDE 
SERVICE PROCESSOR BOOT MODE 
0
1
1: TXT ENABLED 
TXT ENABLE 
TXT AGENT (DRIVES TXT TRANSACTIONS) 
1MCI_BIST_ENABLE 
PD 
SOCKET IDENTIFIER 
PU 
1: DMI MODE 
PD 
PU 
PD MCI_SAFE_MODE_BOOT 
DESCRIPTION 
PU 
0: BIST DISABLED 
PU 
1: BIST ENABLED 
0
BUILT IN SELF TEST 
1
90 OF 270 
Wed Feb 08 16:34:55 2017 
***TXT IS DISABLED FOR EARLY SILICON 
ENABLE ACCORDING TO TABLE 
WHEN TXT IS READY 
0: CNX FETCHES HASH FROM LBG 
KSFC=KEY SELECT FROM CHIPSET: SKX IGNORE 
1: F/W IS LOCAL TO THIS SOCKET'S PCH 
TP FAB1 POP R3D13 0111 
TP FAB1 NOPOP RES R3D13 0418 
TP FAB1 NOPOP RES R7P14 0111 
TP FAB1 POP RES R4P1 0111 
TP FAB1 NOPOP RES R4P1 0418 
EXTERNAL ALIGNMENT OF RESET 
0: NON-LEGACY. DMI3 IS NOT INITIALIZED 
DMI MODE 
1: F/W IS LOCAL TO THIS SOCKET'S PCH 
BOOT MODE OPERATION 
0:STALL INTERNAL_RESET FLOW 
0: NON-LEGACY. DMI3 IS NOT INITIALIZED 
1: CNX FETCHES HASH FROM CPU KSFC_DIS 
TP FAB1 POP RES R7P14 0418 
TP FAB1 CHANGE R6D14 TO PD 0107 
TP FAB1 POP RES R5D4 0111 
TP FAB1 CHANGE R3D25 TO PD 0107 
1:CONITINUE TO BOOT WITHOUT CLK ALIGNING 
PLACE PD WITHIN 500 MILS OF CPU0 
PLACE PD WITHIN 500 MILS OF CPU1 
11
1
0
1
1 1
0
0
1
CPU SIDE BAND: HW STRAPS 
STRAPS (CPU1) 
STRAPS (CPU0) 
WIWYNN CORPORATION 
BOM_COST=PROC_SIDEBAND 
ROOM=PROC_SIDEBAND 



G21796-072 
4.75K 
1/16W 
CHIP 
0402 
G21796-072 
CHIP 
MP2 
1/16W 
PWRGD_PVPP_ABC 
SMB_OCP_FRU_STBY_LVC3_SDA 
SMB_OCP_FRU_STBY_LVC3_SCL 
SMB_HFI1_CPU0_LVC2_SCL 
FM_MODPRST_HFI1_CPU0_LVT2_N SMB_HFI1_CPU0_LVC2_SDA 
LED_HFI1_CPU0_N RST_HFI1_CPU0_LVT2_N 
IRQ_HFI1_CPU0_LVT2_N 
TP_HFI_IO_CONN0_RSVD_17 
SMB_HFI0_CPU0_LVC2_SCL 
FM_MODPRST_HFI0_CPU0_LVT2_N SMB_HFI0_CPU0_LVC2_SDA 
LED_HFI0_CPU0_N RST_HFI0_CPU0_LVT2_N 
IRQ_HFI0_CPU0_LVT2_N 
1
2
1/16W 
CHIP 
0402 
1% 
1.8K 
G21796-336 
R8B6 
1
2 CHIP 
0402 
1% 
1.8K 
G21796-336 
R8B7 
1
2
1/16W 
CHIP 
0402 
1% 
1.8K 
G21796-336 
R8B11 
1
2
1/16W 
CHIP 
0402 
1% 
1.8K 
G21796-336 
R8B13 
1
2
1/16W 
CHIP 
0402 
1% 
4.75K 
G21796-072 
R8B3 
1
2
1/16W 
CHIP 
0402 
1% 
4.75K 
G21796-072 
R8B5 
1
2
1/16W 
CHIP 
0402 
1% 
G21796-072 
R8B19 
0402 
1
2
1/16W 
CHIP 
1% 
4.75K 
G21796-072 
R8B18 
1
2
1/16W 
CHIP 
0402 
1% 
4.75K 
G21796-072 
R8B17 
1
2
1/16W 
CHIP 
1% 
4.75K 
R8B16 
1
2
0402 
1% 
4.75K 
R8B10 
1
2
1/16W 
0402 
1% 
4.75K 
G21796-072 
R8B8 
1 2
3 4
5 6
7 8
9 10 
11 12 
13 14 
15 16 
17 18 
19 20 
21 22 
23 24 
MP1 
SCONN 
H46321-001 
J8B1 
231 190 
138 159 186 188 
138 159 186 188 
29 
29 29 
29 29 
29 
29 
29 29 
29 29 
29 
DESIGN NOTE: 
DO NOT SCALE DRAWING 
SCONN24_H46321001 
SHEET 
B
AA
B
B
SIZE 
SCALE: 
234
1234
DEPARTMENT CODE 
1
DOCUMENT NUMBER REV 
BI 
IN 
OUT 
OUT 
BI 
IN 
P3V3 
PVPP_ABC 
PVPP_ABC PVPP_ABC 
IN 
IN 
OUT 
IN 
IN 
OUT 
BI 
IN 
IN 
91 OF 270 
Wed Feb 08 16:34:55 2017 
IO1 
IO10 IO11 IO12 
IO13 IO14 
IO15 IO16 
IO17 IO18 
IO19 
IO2 
IO20 IO21 IO22 
IO23 IO24 
IO4 
IO6 IO7 IO8 
IO9 
IO5 IO3 
MP2 MP1 
OCP MEZZ A AND MCP SIDEBAND HFI: FRU SMBUS ADDRESS 0XA2 
TEMP SMBUS ADDRESS 0X3E OCP MEZZ C: FRU SMBUS ADDRESS 0XAE 
TEMP SMBUS ADDRESS 0X3E 
FOR DEBUG ONLY 
ROOM=HFI 
BOM_COST=PROC_SIDEBAND 
HFI-IO CONNECTOR 
WIWYNN CORPORATION 



1% 
G21796-017 
0402 
PD_GTL2104_DIR_0 
0402 
1
2
0402 
R7W4 
49.9 
1% 
1/16W 
EMPTY 
G21796-047 
C7D5 1
0.1UF 
CHIP 
R7D34 
374R2F-1-GP 
1/16W 
CHIP 
0402 
R7D32 
P0V7_GTL2104_VREF_1 
R3P49 C3P49 
0.1UF 
2 CHIP 
1/16W 
G21796-074 
CHIP 
X7R 2
10% 
A36096-030 
0402V 
1
R3W10 
49.9 
1% 
1/16W 
EMPTY 
G21796-047 
2
1
R3P45 
374R2F-1-GP 
1
1/16W 
CHIP 
0402 
G21497-005 
H_CPU1_ERR2_G_N 
150.0 
1
G21796-267 
14 
X6S 
D97712-011 
G21796-074 
FM_CPU_CATERR_LVT3_N 
FM_CPU1_FIVR_FAULT_LVT3 
R3P42 
33.2 
1% 
1/16W 
0402 
14 
H_CPU1_THERMTRIP_G_N 
H_CPU_CATERR_G_N 
H_CPU1_FIVR_FAULT_G 
PWRGD_CPUPWRGD_GTL 
FM_CPU1_THERMTRIP_LVT3_N 
PWRGD_CPUPWRGD 
0402 
0402 CHIP 
G21796-074 
FM_CPU0_THERMTRIP_LVT3_N 
1% 
R3R3 
33.2 
G21796-074 
FM_CPU1_FIVR_FAULT_R_LVT3 
1/16W 
2
11 
3
5
D66151-001 
13 
12 
10 
9
2
6
1
7
8
4
IC 
U3P2 
1
2
1/16W 
CHIP 
0402 
1% 
150.0 
G21796-009 
R7P18 
1
2
1/16W 
CHIP 
0402 
1% 
150.0 
G21796-009 
R4R2 
1
33.2 1/16W 
R3P46 
R3P43 
1 2
1% 33.2 
CHIP 
1 2
1% 
1/16W CHIP 0402 
1
2 CHIP 
0402 
1.0% 
75 
R7E2 
1/16W 
1 2
CHIP 
1% 33.2 
G21796-074 1/16W 
1 2
1/16W 
0402 1% 
R7D31 
CHIP 
33.2 
1
1/16W CHIP 
1% 33.2 0402 
2
R7D29 
13 
12 
10 
9
2
3
5
6
7
8
11 
4
D66151-001 
1
U7D2 
R3R1 
1 2
G21796-026 0402 
1
1/16W 
0402 1.00K G21796-026 1% 
2
R7D26 
1 2
1% 
1
2
1/16W 
CHIP 
0402 
1% 
G21796-009 
R6D9 
2
1/16W 
CHIP 
0402 
150.0 
G21796-009 
R7P27 
1 2
1/16W CHIP 0402 5% 
0.0 
G21497-005 R7D28 
1 2
1/16W 
CHIP 0402 5% 
0.0 
G21497-005 
R7D27 
1 2
1/16W CHIP 
0402 1% 33.2 
G21796-074 
R7D25 
R3R2 
G21796-026 
1.00K 
1% 
0402 
CHIP 
1/16W 
2
1
2
0402 
C7D4 
10% 
16V 
1.0UF 
1
1
2
C3P50 
1.0UF 
16V 
10% 
X6S 
1/16W 
CHIP 
G21796-267 
1
2
1.0% 
75 
R3P41 
2
R2T44 
0.0 5% 1/16W 
1
G21497-005 
0402 CHIP 
R2T40 
0.0 5% 
CHIP 
1/16W 
21 G21796-004 
200.0 
R2T37 
0402 
1% 
R2T43 
G21796-267 
0402 
1 2
1/16W CHIP 
1.0% 75 
1 2
1/16W CHIP 0402 
5% 
0.0 
G21497-005 
R3P59 
1 2
1/16W CHIP 0402 
5% 
0.0 
G21497-005 
R3P58 
FM_CPU0_FIVR_FAULT_R_LVT3 
FM_CPU_MSMI_LVT3_R_N 
FM_CPU_ERR2_LVT3_R_N 
FM_CPU_ERR2_LVT3_N 
FM_CPU0_THERMTRIP_LVT3_R_N H_CPU0_THERMTRIP_G_N 
H_CPU_ERR2_GTL_N 
H_CPU0_FIVR_FAULT_G 
H_CPU_MSMI_G_N 
H_CPU1_CATERR_G_N 
H_CPU1_MSMI_G_N 
H_CPU0_MSMI_G_N 
H_CPU0_ERR2_G_N 
H_CPU_ERR2_G_R_N 
H_CPU0_CATERR_G_N 
IC 
0402 
G21796-074 
FM_CPU0_FIVR_FAULT_LVT3 
G21796-074 
FM_CPU_MSMI_LVT3_N 
D97712-011 
PD_GTL2104_DIR_1 
1.00K 
FM_CPU1_THERMTRIP_LVT3_R_N 
FM_CPU_CATERR_LVT3_R2_N 
PWRGD_CPUPWRGD_R1 
1/16W CHIP 
0402 
16V 
100.0 
1% 
0402 
G21796-017 
2
1
A36096-030 
16V 
2 X7R 
0402V 
10% 
1% 
100.0 
R7D33 
P0V7_GTL2104_VREF_0 
55 
144 190 247 
191 
55 
56 
118 
191 
191 
191 
120 144 
21 
22 
55 
55 
21 
21 
21 
191 
147 120 190 247 
PLACE PULLUP RESISTOR WITHIN 
* PLACE PULL-UP RESISTORS CLOSE TO GTL2014 
0402 
374 OHM 
1% 
1/16W 
374 OHM 
1/16W 
0402 
1% 
2.5 INCH OF CPU0 
* PLACE PULL-UP RESISTORS CLOSE TO GTL2014 
PLACE ALL COMPONENTS NEAR GTL CONVERTER 
* PLACE  RESISTORS CLOSE TO  GTL2014 
PLACE SERIES RESISTORS NEAR GTL CONVERTER 
PLACE PULLUP RESISTOR WITHIN 2.5 INCH OF CPU0 
DESIGN NOTE: 
CAD NOTE: 
CAD NOTE: 
CAD NOTE: 
CAD NOTE: 
CAD NOTE: 
CAD NOTE: 
CAD NOTE: 
CAD NOTE: 
DESIGN NOTE: 
TP FAB3 ADD R3W10 0803 
TP FAB3 CHANGE R3P45 AND CONNECT TO P3V3 0803 
TARGET 0.7V 
TARGET 0.7V 
TP FAB3 CHANGE R7D33 AND CONNECT TO P3V3 0803 TP FAB3 ADD R7W4 0803 
THE GTL2014 IS BEING USED AS GTL TO LVTTL CONVERTER, SO 
THE PINS 'BX' ARE INPUTS & 'AX' OUTPUTS ARE PUSH-PULL. 
VREF IS SET AT 2/3 OF VCCIO 
* PLACE SERIES RESISTORS CLOSE TO  GTL2014 
THE GTL2014 IS BEING USED AS GTL TO LVTTL CONVERTER, SO 
THE PINS 'BX' ARE INPUTS & 'AX' OUTPUTS ARE PUSH-PULL. 
VREF IS SET AT 2/3 OF VCCIO 
DO NOT SCALE DRAWING SHEET 
B
AA
B
B
SIZE 
SCALE: 
234
1234
DEPARTMENT CODE 
1
DOCUMENT NUMBER REV 
PVCCIO_CPU0 
PVCCIO_CPU0 
IN 
IN 
OUT 
OUT 
PVCCIO_CPU0 
OUT 
PVCCIO_CPU0 
IN 
IN 
OUT 
IN 
P3V3 
IN 
P3V3 
IN 
IN 
IN 
OUT 
OUT 
OUT 
OUT 
PVCCIO_CPU0 
PVCCIO_CPU0 P3V3 
P3V3 
IN 
IN 
PVCCIO_CPU1 
2 1
2 1
92 OF 270 
Wed Feb 08 16:34:55 2017 
DIR 
VREF VCC 
GND<0> GND<1> GND<2> 
B0 B1 
B2 B3 
A0 A1 
A2 A3 
DIR 
VREF VCC 
GND<0> GND<1> 
GND<2> 
B0 B1 B2 B3 
A0 A1 A2 A3 
CPU SIDE BAND: MISC 
ROOM=PROC_SIDEBAND 
BOM_COST=PROC_SIDEBAND 
GTL2014 
GTL2014 
WIWYNN CORPORATION 



H_CPU0_ERR0_G_N 
0402 
1/16W 
0402 
200.0 
374R2F-1-GP 
R2T36 
C2T32 1
0402 G21497-005 CHIP 
1/16W 5% R2T68 0.0 
1 2
G21497-005 
0402 
1/16W 
0.0 
CHIP 
5% 
R2T60 
21
2
1% 
1
CHIP 
G21796-009 
R7P28 
150.0 
0402 
1/16W 
R2T59 
1
EMPTY 
0.0 
5% 
1/16W 
2
G21497-005 
0402 
2
1
5% 
EMPTY 
G21497-005 
0.0 
0402 
1/16W 
R2T69 
1 0.0 
R2T71 
1/16W 
2 EMPTY 
0402 
G21497-005 
5% 
2
5% 
0.0 1
R7D43 
0402 
G21497-005 
EMPTY 
1/16W 
0402 
CHIP 1/16W 5% 0.0 R2T65 
1 2
G21497-005 
0402 G21497-005 
CHIP 1/16W 5% 0.0 
21
R2T66 
1
R2T67 0.0 
2
5% 1/16W CHIP 
G21497-005 0402 
0402 
CHIP 
R7D41 
1 2
0.0 1/16W 5% 
G21497-005 
0.0 
1/16W 
1
5% 
R8F38 
CHIP 
2
G21497-005 
0402 
5% CHIP 1/16W 
0.0 
G21497-005 
1
R2T64 
2
0402 
1/16W 
0.0 
G21497-005 
1
5% 
R1T36 
CHIP 
2
0402 
1/16W 
0.0 
G21497-005 
1
5% CHIP 
R1T37 
2
0402 
1% 
0402 
CHIP 
1/16W 
1.00K 1
CHIP 
0.0 
0402 
1
5% 
2
R2T27 
G21497-005 
EMPTY 1/16W 
0.0 
G21497-005 
1
5% 
2
R8F37 
0402 
1/16W 
0.0 
G21497-005 
1
5% EMPTY 
R2T63 
2
1/16W 
0.0 
5% EMPTY 
21
G21497-005 
R1T35 
0402 
1/16W 
0.0 
G21497-005 
1
5% EMPTY 
R1T38 
2
0402 
2
0402 
CHIP 
1/16W 
G21796-009 
1% 
1 150.0 
R2T72 
1 150.0 
2
0402 
CHIP 
1% 
R2T73 
1/16W 
G21796-009 
0402 
0.0 
CHIP 
1
5% 
2
1/16W 
R2T32 
G21497-005 
G21497-005 0402 
1/16W 
R2T20 
1
5% 0.0 
CHIP 
2
G21497-005 
5% 0.0 
CHIP 
R2T17 
1 2
1/16W 
7
8
11 
6
5
3
2 D66151-001 
13 
12 
10 
9
1
IC 
U2T4 
4
14 
G21796-074 1/16W CHIP 
1% 
1
R2T38 
2
0402 
CHIP G21796-074 
33.2 1% 
1
R2T33 
2
0402 
33.2 
1/16W CHIP 
1% 
2
G21796-074 
0402 
R2T30 
1
CHIP G21796-074 
0402 1% 
1/16W 
1 2
R7D24 
2
1/16W 
CHIP 
G21796-004 
0402 
1% 
1
R2T19 
1/16W 
75 
CHIP 
0402 
1.0% 
21
R2T16 
G21796-267 
G21796-267 
1/16W 
1
CHIP 
1.0% 
75 
2
R2T31 
2
1 C2T33 
D97712-004 
1.0UF 
10% 
0402V 
6.3V 
X6S 
0402 
CHIP 
1/16W 
2
1% 
1
R4R3 
150.0 
G21796-009 
CHIP 2
1/16W 
G21796-004 
0402 
1% 
200.0 1
R2T26 
2 EMPTY 
G21497-005 
0402 
1
R2T57 
0.0 
5% 
1/16W 
2 EMPTY 
G21497-005 
0402 
1
R2T61 
0.0 
5% 
1/16W 
2
1
R2T62 
0.0 
5% 
1/16W 
EMPTY 
G21497-005 
0402 
2
1
5% 
0.0 
EMPTY 
R2T58 
1/16W 
G21497-005 
0402 
USE SHARED PADS 
USE SHARED PADS WITH 
FM_CPU0_PROCHOT_LVT3_BMC_N 
H_CPU0_PROCHOT_G_PCH_N 
H_CPU1_PROCHOT_G_N 
H_CPU0_PROCHOT_G_N 
FM_CPU_ERR0_LVT3_N 
H_CPU_ERR1_PCH_N 
H_CPU_ERR0_PCH_N 
FM_CPU_ERR1_LVT3_R_N 
H_CPU_ERR0_GTL_N 
H_CPU_ERR1_GTL_N 
H_CPU_ERR0_GTL_R_N 
FM_CPU_ERR1_LVT3_BMC_N 
FM_CPU_ERR1_PCH_N 
FM_CPU1_PROCHOT_LVT3_BMC_N 
FM_CPU_ERR0_PCH_N 
FM_CPU0_PROCHOT_PCH_N 
FM_CPU1_PROCHOT_PCH_N 
FM_CPU_ERR0_LVT3_BMC_N 
H_CPU1_ERR1_G_N 
H_CPU1_ERR0_G_N 
H_CPU0_ERR1_G_N 
FM_CPU_ERR0_LVT3_N 
FM_CPU_ERR1_LVT3_N 
FM_CPU0_PROCHOT_LVT3_N 
FM_CPU1_PROCHOT_LVT3_N 
FM_CPU_ERR0_LVT3_K_N 
FM_CPU_ERR1_LVT3_N 
FM_CPU1_PROCHOT_LVT3_N 
FM_CPU0_PROCHOT_LVT3_N 
FM_CPU_ERR1_LVT3_K_N 
H_CPU_ERR1_GTL_R_N 
H_CPU0_PROCHOT_G_R_N 
H_CPU1_PROCHOT_G_R_N FM_CPU1_PROCHOT_LVT3_R_N 
FM_CPU0_PROCHOT_LVT3_R_N 
FM_CPU_ERR0_LVT3_R_N 
PD_GTL2104_4_DIR 
P0V7_GTL2104_5_VREF 
R2T50 
1
2X7R 
0402V 
A36096-030 2
R2T39 
100.0 
1% 
1/16W 
CHIP 
0.1UF 
16V 
10% 
2
1
0402 
49.9 
EMPTY 
H_CPU1_PROCHOT_G_PCH_N 
0402 
USE SHARED PADS FOR 0OHM 
1/16W 
FM_CPU0_PROCHOT_LVT3_K_N 
33.2 
FM_CPU1_PROCHOT_LVT3_K_N 
33.2 
USE SHARED PADS WITH 0OHM 
PD_GTL2104_4_DIR 
2
G21796-026 
0402 
G21796-017 
P0V7_GTL2104_5_VREF 
G21796-047 
1% 
1/16W 
R2W2 
21 
145 
55 95 
21 95 
93 
145 
121 
145 
121 
121 
121 
145 
55 
55 
21 
93 
93 
93 
93 
93 
93 
93 
93 
93 
93 
93 
0402 
STEERING RESISTORS 
33.2OHM RESISTORS 
FOR RESISTORS 
STEERING RESISTORS 
1/16W 
1% 
374 OHM 
DESIGN NOTE: 
CAD NOTE: 
CAD NOTE: 
CAD NOTE: 
CAD NOTE: 
DESIGN NOTE: 
CAD NOTE: 
CAD NOTE: 
TP FAB3 ADD R2W2 0803 
THE GTL2014 IS BEING USED AS GTL TO LVTTL CONVERTER, SO 
PLACE ALL COMPONENTS NEAR GTL CONVERTER 
VREF IS SET AT 2/3 OF VCCIO 
PLACE ONE 150 OHM PU RESISTOR NEAR CPU 
THE OTHER NEAR GTL2014 FOR EACH SIGNAL 
THE PINS 'BX' ARE INPUTS & 'AX' OUTPUTS ARE PUSH-PULL. 
DO NOT SCALE DRAWING SHEET 
B
AA
B
B
SIZE 
SCALE: 
234
1234
DEPARTMENT CODE 
1
DOCUMENT NUMBER REV 
IN 
IN 
PVCCIO_CPU0 OUT 
OUT 
P3V3 
PVCCIO_CPU0 
IN 
IN 
OUT 
OUT 
IN 
IN 
PVCCIO_CPU0 P3V3 
OUT 
OUT 
OUT 
OUT 
OUT 
IN 
IN 
IN 
IN 
IN 
OUT 
OUT 
OUT 
OUT 
PVCCIO_CPU1 
IN 
OUT 
2 1
93 OF 270 
Wed Feb 08 16:34:55 2017 
DIR 
VREF 
VCC 
GND<0> 
GND<1> 
GND<2> 
B0 
B1 
B2 
B3 
A0 
A1 
A2 
A3 
TP FAB3 CHANGE R2T36 AND CONNECT TO P3V3  0803 
WITH 20 OHM RESISTOR G21976-173 
STUFF R2T17, R2T20, R2T32, & R2T27 
R1T35 
R1T38 
R2T58 
R2T65 
R2T62 
R2T71 
R8F37 
R2T63 
TARGET 0.7V 
R7D41 
R2T66 
R2T68 
R2T59 
IE ONLY (NO BMC) 
R2T69 
R2T57 
STUFF 
R2T61 R2T31 
R2T16 
UNSTUFF 
U2T4 
R2T60 
R2T67 
R8F38 
R2T64 
R1T37 
R1T36 
ERRORS CIRCUITRY 
GTL2014 
ROOM=PROC_SIDEBAND WIWYNN CORPORATION 



CHIP 
NTJD4001N 
H_CPU1_MEMKLM_MEMHOT_G_N 
H_CPU1_MEMGHJ_MEMHOT_G_N 
H_CPU1_MEMGHJ_MEMHOT 
H_CPU1_MEMKLM_MEMHOT 
IRQ_PVDDQ_GHJ_VRHOT_LVT3_N 
IRQ_PVDDQ_KLM_VRHOT_LVT3_N 
FM_DIMM_EVENT_COD_N 
H_CPU0_MEMDEF_MEMHOT_G_N 
H_CPU0_MEMDEF_MEMHOT 
IRQ_PVDDQ_DEF_VRHOT_LVT3_N 
IRQ_PVDDQ_ABC_VRHOT_LVT3_N 
FM_MEM_THERM_EVENT_LVT3_N 
FM_DIMM_EVENT_FET 
H_CPU0_MEMABC_MEMHOT_G_N 
H_CPU0_MEMABC_MEMHOT 
E40049-001 
Q4U1 
FET 
NTJD4001N 
6
2
1
1
2
1/16W 
0402 
1% 
4.75K 
G21796-072 
R4U3 
0402 
CHIP 
G21796-072 
1/16W 
1% 
4.75K 
R4U1 
2
1
E40049-001 
FET 
NTJD4001N 
3
5
4
Q3U1 
E40049-001 
NTJD4001N 
Q4B1 
6
2
1
FET 
1
21/16W 
CHIP 
0402 
1% 
4.75K 
R6M4 
0402 
CHIP 
1/16W 
1
2
1% 
4.75K 
R3R10 
E40049-001 
3
5
4
FET 
NTJD4001N 
Q4B1 
E40049-001 
3
5
4
FET 
Q7E2 
6
2
1
FET 
NTJD4001N 
E40049-001 
Q7E2 
1
21/16W 
CHIP 
0402 
1% 
4.75K 
R3R4 
3
5
4
FET 
NTJD4001N 
E40049-001 
Q7E1 
6
2
1
FET 
NTJD4001N 
E40049-001 
Q7E1 
1
21/16W 
CHIP 
0402 
1% 
4.75K 
R7G7 
NTJD4001N 
6
2
1
FET 
E40049-001 
Q3U1 
R4U4 
33.0K 1
0402 
G21497-023 
2
1/16W 
CHIP 
5% 
FET 
NTJD4001N 
E40049-001 
3
5
Q4U1 
4
CHIP 
1
2
1/16W 
0402 
1% 
2.21K 
G21796-112 
R4U2 
55 95 152 
55 95 152 
223 119 144 
226 119 145 
43 44 45 46 47 48 49 50 51 52 
53 54 77 78 79 80 81 82 83 
84 85 86 87 88 
95 21 152 
218 119 
146 
215 119 
145 
156 191 
95 21 152 
S
D
G
S
D
G
S
D
G
S
D
G
S
D
G
S
D
G
S
D
G
S
D
G
S
D
G
S
D
G G21796-072 G21796-072 
G21796-072 G21796-072 
DO NOT SCALE DRAWING SHEET 
B
AA
B
B
SIZE 
SCALE: 
234
1234
DEPARTMENT CODE 
1
DOCUMENT NUMBER REV 
PVPP_ABC 
P3V3_STBY 
OUT 
IN 
IN 
P3V3 
P3V3 
OUT 
OUT 
IN 
P3V3 
OUT 
IN 
P3V3 
OUT 
PVPP_ABC 
IN 
94 OF 270 
Wed Feb 08 16:34:56 2017 
CPU SIDE BAND: PROCHOT & MEMHOT (1/2) 
ROOM=PROC_SIDEBAND WIWYNN CORPORATION 



10% 
E40049-001 
FET 
H_CPU0_PROCHOT_G_N 
IRQ_PVCCIN_CPU0_VRHOT_LVC3_N 
FM_PVCCIN_CPU1_PWR_IN_ALERT_N 
H_CPU1_MEMKLM_MEMHOT_G_N 
H_CPU1_MEMGHJ_MEMHOT_G_N 
H_CPU0_MEMDEF_MEMHOT_G_N 
IRQ_PVCCIN_CPU1_VRHOT_LVC3_N 
H_CPU0_MEMABC_MEMHOT_G_N 
H_CPU1_PROCHOT_G_N 
H_CPU0_PROCHOT_G_N 
IRQ_CPU1_VRHOT 
IRQ_CPU0_VRHOT 
FM_PVCCIN_CPU0_PWR_IN_ALERT_N 
IRQ_CPU0_PROCHOT_G_N 
H_CPU1_PROCHOT_G_N 
IRQ_CPU1_PROCHOT_G_N 
FM_SYS_THROTTLE_LVC3 
FM_THROTTLE_N FM_THROTTLE_R_N 
FM_PWRBRK_N 
FM_SYS_THROTTLE_LVC3 
A36096-030 
16V 
0.1UF 
C7E3 
0402V 
X7R 
1
2
1/16W 
0402 
R7E11 
4.75K 
1% 
2
1
Q7E6 
FET 
NTJD4001N 
3
5
4
0402 
1/16W 
R7E10 
4.75K 
1% 
2
1
Q7E5 
E40049-001 
NTJD4001N 
FET 
4
5
3
E40049-001 
Q7E3 
NTJD4001N 
FET 
1
2
6
Q7E3 
E40049-001 
FET 
4
5
3
NTJD4001N 
Q4B2 
E40049-001 
NTJD4001N 
FET 
4
5
3
Q4B2 
E40049-001 
NTJD4001N 
FET 
1
2
6
Q2U1 
E40049-001 
NTJD4001N 
FET 
1
2
6
Q7E8 
2N7002 
C79254-001 
C79254-001 
2N7002 
FET 
Q7E4 
SOTLF 
IC 
VCC=P3V3_STBY;GND=GND; 
U7E3 
D10321-001 
NC7SZ08 
4
2
1
1
D10321-001 
VCC=P3V3_STBY;GND=GND; 
U7E2 
NC7SZ08 
SOTLF 
IC 
4
2
A36096-030 
X7R 
10% 
16V 
0.1UF 
C7E4 
0402V 
1
2
Q2U1 
E40049-001 
NTJD4001N 
FET 
4
5
3
Q7E6 
E40049-001 
NTJD4001N 
FET 
1
2
6
Q7E5 
1
2
6
E40049-001 
FET 
NTJD4001N 
1
R7E9 0.0 
2
5% 
1/16W CHIP 
G21497-005 
0402 
R7E7 
1% 
0402 
CHIP 2
1 4.75K 
1/16W 
G21796-072 
21 95 93 
201 145 
206 
55 94 152 
55 94 152 
94 21 152 
206 145 
94 21 152 
55 95 93 
21 95 93 
201 
55 95 93
95 
119 133 170 146 
147 108 
95 
CHIP 
CHIP 
S
D
G
S
D
G
S
D
G
S
D
G
S
D
G
S
D
G
S
D
G
S
D
G
S
D
G
S
D
G
S
D
G
S
D
G
G21796-072 
G21796-072 
CAD NOTE: 
CAD NOTE: 
DO NOT SCALE DRAWING SHEET 
B
AA
B
B
SIZE 
SCALE: 
234
1234
DEPARTMENT CODE 
1
DOCUMENT NUMBER REV 
P3V3_STBY 
IN 
IN 
P3V3 
OUT 
IN 
IN 
P3V3 
OUT 
OUT IN 
OUT 
OUT 
OUT 
OUT 
OUT 
OUT 
P3V3_STBY 
OUT 
IN 
P3V3 
95 OF 270 
Wed Feb 08 16:34:56 2017 
PLACE CAP CLOSE TO 
U7E2 
U7E3 PLACE CAP CLOSE TO 
CPU SIDE BAND: PROCHOT & MEMHOT (2/2) 
ROOM=PROC_SIDEBAND WIWYNN CORPORATION 



PWRGD_CPU1_DRAMPWROK_GHJ_G 
PD_GTL2014_1_VREF 
PWRGD_CPU0_G 
RST_CPU0_G_N 
PWRGD_CPU0_DRAMPWROK_ABC_G 
D66151-001 
PWRGD_CPU1_G 
PWRGD_CPU0_DRAMPWROK_DEF_G 
PWRGD_CPU1_DRAMPWROK_KLM_G 
RST_CPU1_G_N 
PWRGD_CPU0_LVC3 
PU_GTL2014_1_DIR 
PWRGD_DRAMPWRGD 
PWRGD_DRAMPWRGD 
RST_CPU1_LVC3_N 
PWRGD_CPU1_LVC3 
RST_CPU0_LVC3_N 
PD_GTL2014_2_VREF 
PU_GTL2014_2_DIR 
2
1
X6S 
6.3V 
0402V 
10% 
1.0UF 
D97712-004 
C4C3 
2
1
X6S 
6.3V 
0402V 
10% 
1.0UF 
D97712-004 
C3P42 
G21796-026 
1 2
1/16W CHIP 0402 1% 1.00K 
R3P32 
1
2
1/16W 
CHIP 
0402 
1.0% 
64.9 
G21796-298 
R3P38 
1 2
1/16W CHIP 0402 
1% 1.00K 
G21796-026 
R4C9 
1
2
1/16W 
CHIP 
0402 
1% 
1.00K 
G21796-026 
R4C8 
1
2
1/16W 
CHIP 
0402 
1.0% 
64.9 
G21796-298 
R3P29 
13 
12 
10 
9
2
3
5
6
1
7
8
11 
14 
4
IC 
D66151-001 
U4C2 
13 
12 
10 
9
2
3
5
6
1
7
8
11 
14 
4
IC 
U3P1 
1
2
1/16W 
CHIP 
1% 
1.00K 
G21796-026 
0402 
R3P36 
1
2
1/16W 
CHIP 
0402 
1.0% 
64.9 
G21796-298 
R3D21 
1
2
1/16W 
CHIP 
0402 
1% 
49.9 
G21796-047 
R6D8 
1
2
1/16W 
CHIP 
0402 
1.0% 
64.9 
G21796-298 
R7M9 
1
2
1/16W 
CHIP 
0402 
1% 
49.9 
G21796-047 
R3D15 
1
2
1/16W 
CHIP 
0402 
1% 
49.9 
G21796-047 
R3D20 
1
1/16W 
CHIP 
0402 
1% 
49.9 
G21796-047 
R6D12 
2
55 
21 113 
21 
21 
55 
21 
55 
55 
190 
190 96 
190 96 
190 
190 
190 
DESIGN NOTE: 
CAD NOTE: 
DESIGN NOTE: 
CAD NOTE: 
CPU0 
TO 
CPU0/MCP JTAG DEBUG HEADER 
TO 
FROM 
CPLD 
THE GTL2014 IS BEING USED AS LVTTL TO GTL CONVERTER, SO 
THE PINS 'AX' ARE INPUTS & 'BX' OUTPUTS ARE OPEN-DRAIN 
THE GTL2014 IS BEING USED AS LVTTL TO GTL CONVERTER, SO 
AND VREF PIN IS NOT USED 
THE PINS 'AX' ARE INPUTS & 'BX' OUTPUTS ARE OPEN-DRAIN 
AND VREF PIN IS NOT USED 
DO NOT SCALE DRAWING SHEET 
B
AA
B
B
SIZE 
SCALE: 
234
1234
DEPARTMENT CODE 
1
DOCUMENT NUMBER REV 
OUT 
OUT 
P3V3_STBY 
P3V3_STBY 
IN 
IN 
PVDDQ_ABC 
IN 
IN 
IN 
IN 
PVDDQ_DEF 
PVDDQ_GHJ PVDDQ_KLM PVCCIO_CPU1 
OUT 
OUT 
OUT 
OUT 
OUT 
OUT 
PVCCIO_CPU0 
96 OF 270 
Wed Feb 08 16:34:56 2017 
DIR 
VREF VCC 
GND<0> GND<1> GND<2> 
B0 
B1 B2 B3 
A0 
A1 A2 A3 
DIR 
VREF VCC 
GND<0> GND<1> GND<2> 
B0 B1 B2 B3 
A0 A1 A2 A3 
TO CPU1 
FROM 
CPLD 
CPU SIDE BAND:RESETS & POWER GOODS 
PLACE PU RESISTORS NEAR CPU0 
PLACE PU RESISTORS NEAR CPU1 
BOM_COST=PROC_SIDEBAND 
ROOM=PROC_RSTS_PGOODS 
GTL2014 
GTL2014 
WIWYNN CORPORATION 



CHIP 
CHIP 
2
0402 
R3D18 
H_CPU1_FAST_WAKE_N 
PD_CPU0_MCP01_DMON 
PD_CPU1_MCP01_DMON 
PU_CPU1_TSC_SYNC 
PU_CPU0_TSC_SYNC 
H_CPU0_FAST_WAKE_N 
1 2
1/16W CHIP 0402 
1% 10.0K 
G21796-016 
R7P13 
1 2
1/16W CHIP 0402 
1% 10.0K 
R4P5 
G21796-016 
1 2
1/16W CHIP 0402 1.0% 240 G21796-294 
R4C10 
1 2
1/16W 0402 1.0% 240 G21796-294 
R4P21 
1
2
1/16W 
1% 
150.0 
R7P20 
G21796-009 
1
2
1/16W 
CHIP 
0402 
1% 
150.0 
G21796-009 
R4R4 
1/16W 
CHIP 
0402 0.0 
G21497-005 
5% 
1
TO/FROM TO/FROM 
55 
39 
73 
55 
21 
21 
157 
CAD NOTE: 
CPU1 CPU0 
DO NOT SCALE DRAWING SHEET 
B
AA
B
B
SIZE 
SCALE: 
234
1234
DEPARTMENT CODE 
1
DOCUMENT NUMBER REV 
PVCCIO_CPU0 
OUT 
OUT 
PVCCIO_CPU1 
OUT 
OUT 
PVCCIO_CPU0 
PVCCIO_CPU0 
BI BI 
97 OF 270 
Wed Feb 08 16:34:56 2017 
PLACE R4R4 NEAR CPU0, AND R7P20 NEAR CPU1. 
CPU SIDE BAND:PULL-UPS/PULL-DOWNS 
BOM_COST=PROC_SIDEBAND 
ROOM=PROC_SIDEBAND WIWYNN CORPORATION 



2
R4G2 
M_C_VREF 
M_F_VREF 
M_C_CPU_VREF 
M_F_CPU_VREF 
M_B_VREF 
M_E_VREF 
M_B_CPU_VREF 
M_E_CPU_VREF 
M_A_VREF 
M_D_VREF 
M_A_CPU_VREF 
M_D_CPU_VREF 
1
2
1/16W 
CHIP 
0402 
1% 
1.00K 
G21796-026 
R6M1 
2
1
X7R 
25V 
0402V 
10% 
0.01UF 
A36096-045 
C4F9 
2
1
X7R 
25V 
0402V 
10% 
0.01UF 
A36096-045 
C6L2 
1
1/16W CHIP 
0402 1.0% 
2
G21796-274 
R6L3 
1
2
1/16W 
CHIP 
0402 
1% 
1.00K 
G21796-026 
R6L1 
1
2
1/16W 
CHIP 
0402 
1% 
1.00K 
G21796-026 
R6L2 
2
1
X7R 
25V 
0402V 
10% 
0.01UF 
A36096-045 
C6L7 
1 2
1/16W CHIP 
0402 1.0% 
2
G21796-274 
R6L14 
1
2
1/16W 
CHIP 
0402 
1% 
1.00K 
G21796-026 
R6L12 
1
2
1/16W 
CHIP 
0402 
1% 
1.00K 
G21796-026 
R6L13 
2
1
X7R 
25V 
0402V 
10% 
0.01UF 
A36096-045 
C4G17 
1 2
1/16W CHIP 
0402 1.0% 
2
G21796-274 
R4G20 
1 2
1/16W CHIP 
0402 1.0% 
2
G21796-274 
R4F3 
1
2
1/16W 
CHIP 
0402 
1% 
1.00K 
G21796-026 
R4G22 
1
2
1/16W 
CHIP 
0402 
1% 
1.00K 
G21796-026 
R4G21 
2
1
X7R 
25V 
0402V 
10% 
0.01UF 
A36096-045 
C4G1 
1 2
1/16W CHIP 
0402 1.0% 
2
G21796-274 
R4G1 
1
2
1/16W 
CHIP 
0402 
1% 
1.00K 
G21796-026 
R4G3 
1
2
1/16W 
CHIP 
0402 
1% 
1.00K 
G21796-026 
R4F5 
1
2
1/16W 
CHIP 
0402 
1% 
1.00K 
G21796-026 
1
2
1/16W 
CHIP 
0402 
1% 
1.00K 
G21796-026 
R4F4 
2
1
X7R 
25V 
0402V 
10% 
0.01UF 
A36096-045 
C6M2 
1 2
1/16W CHIP 
0402 1.0% 
2
G21796-274 
R6M2 
1
2
1/16W 
CHIP 
0402 
1% 
1.00K 
G21796-026 
R6L16 
47 48 
53 54 
21 
21 
45 46 
51 52 
21 
21 
43 44 
49 50 
21 
21 
CAD NOTE: CAD NOTE: 
CAD NOTE: CAD NOTE: CAD NOTE: 
CAD NOTE: 
DO NOT SCALE DRAWING SHEET 
B
AA
B
B
SIZE 
SCALE: 
234
1234
DEPARTMENT CODE 
1
DOCUMENT NUMBER REV 
IN 
PVDDQ_DEF PVDDQ_DEF 
IN OUT IN OUT 
IN OUT 
PVDDQ_ABC 
IN OUT 
PVDDQ_ABC 
OUT 
IN OUT 
PVDDQ_DEF 
PVDDQ_ABC 
98 OF 270 
Wed Feb 08 16:34:57 2017 
PLACE BETWEEN DIMM_A1 & A2 
PLACE BETWEEN DIMM_F1 & F2 PLACE BETWEEN DIMM_E1 & E2 PLACE BETWEEN DIMM_D1 & D2 
PLACE BETWEEN DIMM_C1 & C2 PLACE BETWEEN DIMM_B1 & B2 
CPU SIDE BAND:CPU0 DIMM CA VREF 
WIWYNN CORPORATION 



C4G22 
SMB_DDR_ABC_SDA_G_R 
SMB_DDR_DEF_VPP_SDA_R 
0402 
0402V 
GND=GND 
G21796-066 
G21796-294 
1/16W 
SMB_DDR_GHJ_VPP_SCL 
SMB_DDR_DEF_SCL_G_R 
SMB_DDR_KLM_VPP_SCL_R 
SMB_DDR_KLM_VPP_SDA_R 
SMB_DDR_DEF_VPP_SCL SMB_DDR_DEF_VPP_SCL_R 
SMB_DDR_ABC_VPP_SCL 
SMB_DDR_ABC_VPP_SDA_R 
SMB_DDR_ABC_VPP_SCL_R SMB_DDR_ABC_SCL_G_R 
SMB_DDR_ABC_SDA_G 
SMB_DDR_ABC_SCL_G 
TP_SMB_DDR_ABC_EN 
SMB_DDR_DEF_SDA_G 
SMB_DDR_DEF_SCL_G 
TP_SMB_DDR_DEF_EN 
SMB_DDR_GHJ_SCL_G_R 
SMB_DDR_GHJ_SDA_G_R SMB_DDR_GHJ_SDA_G 
SMB_DDR_GHJ_SCL_G 
TP_SMB_DDR_GHJ_EN 
SMB_DDR_KLM_VPP_SCL 
SMB_DDR_KLM_VPP_SDA 
SMB_DDR_KLM_SCL_G_R 
TP_SMB_DDR_KLM_EN 
SMB_DDR_KLM_SDA_G 
SMB_DDR_KLM_SCL_G 
SMB_DDR_KLM_SDA_G_R 
SMB_DDR_GHJ_VPP_SDA SMB_DDR_GHJ_VPP_SDA_R 
SMB_DDR_GHJ_VPP_SCL_R 
CHIP G21796-066 
1
0402 
10.0 1/16W 1% R7M3 
2
SMB_DDR_DEF_SDA_G_R 
R6T3 1% 1/16W 10.0 
2
0402 
1
G21796-066 CHIP 
1 2
1% 0402 
CHIP 
G21796-173 
1/16W 20.0 R4T9 
1/16W 
G21796-066 
10.0 
1
CHIP 
R3R7 
2
1% 
0402 
10.0 R4T3 
CHIP 
1% 
0402 
1/16W 
G21796-066 
1 2
0402 
R7M2 
G21796-294 
240 
1.0% 
CHIP 
1/16W 
2
1
R7M7 
G21796-294 
240 
1.0% 
0402 
CHIP 
1/16W 
2
1
1
GND=GND 
U3B1 
G81764-001 
IC 
8
63
72
5
R6T2 
240 
1.0% 
0402 
CHIP 
1/16W 
2
1
G21796-294 G21796-294 
R6T1 
240 
1.0% 
0402 
CHIP 
1/16W 
2
1
C6F3 
0.1UF 
16V 
1
2
10% 
X7R 
A36096-030 
0402V 
0402 
CHIP 
1.0% 
240 
R3P60 
2
1
R3R13 
G21796-294 
240 
1.0% 
0402 
CHIP 
1/16W 
2
1
8
7GND=GND 
U4G1 
G81764-001 
IC 
1
63
2
5
U7E1 
G81764-001 
IC 
81
63
72
5
0402 R7M4 20.0 
2
1/16W 
1% 
G21796-173 
CHIP 
1
1/16W 
G21796-173 
1% R7M5 20.0 0402 
CHIP 
21
C3B5 
0.1UF 
A36096-030 
10% 
16V 
0402V 
X7R 
1
2
0402V 
A36096-030 
C3B4 
10% 
16V 
X7R 2
0.1UF 1
R6U13 
2
20.0 
CHIP 
1
1% 
1/16W 
0402 
G21796-173 
C4G25 
0.1UF 
X7R 
A36096-030 
16V 
10% 
0402V 
1
2
R3R8 
G21796-173 
20.0 1% 0402 
CHIP 1/16W 
21
SMB_DDR_DEF_VPP_SDA 
R3R9 
G21796-173 
20.0 1% 0402 
CHIP 1/16W 
21
C7E2 
A36096-030 
0.1UF 
10% 
16V 
X7R 
1
2
0.1UF 
16V 
10% 
X7R 
A36096-030 
0402V 
1
2
A36096-030 
C7E1 
0.1UF 
10% 
0402V 
16V 
X7R 
1
2
1/16W G21796-066 
1
10.0 1% 
2
0402 CHIP R4T4 
X7R 
1
2
C6F2 
0.1UF 
16V 
10% 
A36096-030 
0402V 
1.0% 
1
CHIP 
1/16W 
240 
R4T5 
2
G21796-294 
0402 
G21796-294 
CHIP 
1/16W 
1.0% 
1
R4T6 
240 
2
GND=GND 
U6F1 
G81764-001 
81
63
2
5
7
IC 
665 
2
1
R4T7 
1.0% 
1/16W 
0402 
CHIP 
G21796-235 
20.0 1% 1/16W R6U14 0402 G21796-173 CHIP 
21
10.0 R7M8 1% 1/16W CHIP G21796-066 0402 
21
21
CHIP 1/16W 1% R6T4 10.0 G21796-066 0402 
1/16W CHIP 0402 1% 
21
10.0 R3R14 
2
0402 
CHIP 
G21796-235 
1/16W 
1.0% 
R4T8 
665 1
R7M1 
G21796-235 
665 
1.0% 
0402 
CHIP 
1/16W 
2
1
G21796-235 
1.0% 
R7M6 
665 
0402 
CHIP 
1/16W 
2
1
0402 
1.0% 
665 
R6U17 
CHIP 
G21796-235 
1/16W 
2
1
G21796-235 
1/16W 
R6U18 
0402 
2 CHIP 
665 1
1.0% 
R3R5 
G21796-235 
665 
1.0% 
0402 
CHIP 
1/16W 
2
1
R3R12 
G21796-235 
665 
1.0% 
0402 
CHIP 
1/16W 
2
1
0402 
G21796-173 
1% 
1/16W 
21
CHIP 
SMB_DDR_ABC_VPP_SDA 
20.0 R4T10 
21 
77 78 79 80 81 82 
21 49 50 51 52 53 54 
43 44 45 46 47 48 21 
55 
55 
83 84 85 86 87 88 
83 84 85 86 87 88 
55 
55 
77 78 79 80 81 82 
21 49 50 51 52 53 54 
43 44 45 46 47 48 
DO NOT SCALE DRAWING SHEET 
B
AA
B
B
SIZE 
SCALE: 
234
1234
DEPARTMENT CODE 
1
DOCUMENT NUMBER REV 
IN 
IN 
BI 
BI 
IN 
BI 
IN 
PVCCIO_CPU1 
PVCCIO_CPU1 
PVPP_KLM 
PVCCIO_CPU1 
PVCCIO_CPU1 
PVCCIO_CPU0 
PVCCIO_CPU0 
PVPP_GHJ 
PVPP_DEF 
PVPP_KLM 
BI 
OUT 
BI 
PVCCIO_CPU1 
OUT 
PVPP_GHJ 
PVPP_DEF 
OUT 
BI 
PVCCIO_CPU1 
BI 
OUT 
PVCCIO_CPU0 
PVCCIO_CPU0 
PVCCIO_CPU0 
PVPP_ABC 
PVPP_ABC 
PVPP_ABC 
PVPP_KLM 
PVPP_GHJ 
PVPP_DEF 
BI 
PVCCIO_CPU0 
99 OF 270 
Wed Feb 08 16:34:57 2017 
PCA9617 VCCA 
SCLA 
SDAA SCLB SDAB 
VCCB 
EN 
PCA9617 VCCA 
SCLA 
SDAA SCLB SDAB 
VCCB 
EN 
PCA9617 VCCA 
SCLA 
SDAA SCLB SDAB 
VCCB 
EN 
PCA9617 VCCA 
SCLA 
SDAA SCLB SDAB 
VCCB 
EN 
CPU SIDE BAND:DIMM SMBUS TRANSLATORS 
ROOM=MEM 
WIWYNN CORPORATION 



1.00K 
G21796-026 
R1G2 
M_J_VREF M_J_CPU_VREF 
M_M_VREF M_M_CPU_VREF 
M_H_VREF 
M_L_VREF M_L_CPU_VREF 
M_H_CPU_VREF M_G_VREF 
M_K_VREF 
M_G_CPU_VREF 
M_K_CPU_VREF 
2
1
X7R 
25V 
0402V 
10% 
0.01UF 
A36096-045 
C1F19 
1 2
1/16W CHIP 
0402 1.0% 
2
G21796-274 
R1F4 
1
2
1/16W 
CHIP 
0402 
1% 
1.00K 
G21796-026 
R1F5 
2
1
X7R 
25V 
0402V 
10% 
0.01UF 
A36096-045 
C9L3 
1 2
1/16W CHIP 
0402 1.0% 
2
G21796-274 
R9L3 
2
1
X7R 
25V 
0402V 
10% 
0.01UF 
A36096-045 
C1G18 
1 2
1/16W CHIP 
0402 1.0% 
2
G21796-274 
R1G14 
1
2
1/16W 
CHIP 
0402 
1% 
G21796-026 
R9L1 
1
2
1/16W 
CHIP 
0402 
1% 
1.00K 
G21796-026 
R9L11 
1
2
1/16W 
CHIP 
0402 
1% 
1.00K 
G21796-026 
R9L2 
1
2
1/16W 
CHIP 
0402 
1% 
1.00K 
G21796-026 
R1G17 
1
2
1/16W 
CHIP 
0402 
1% 
1.00K 
G21796-026 
R1G15 
2
1
X7R 
25V 
0402V 
10% 
0.01UF 
A36096-045 
C9L8 
1 2
1/16W CHIP 
0402 1.0% 
2
G21796-274 
R9L8 
2
1
X7R 
25V 
0402V 
10% 
0.01UF 
A36096-045 
C1G8 
1 2
1/16W CHIP 
0402 1.0% 
2
G21796-274 
R1G1 
1
2
1/16W 
CHIP 
0402 
1% 
1.00K 
G21796-026 
R9L6 
2
1/16W 
CHIP 
0402 
1% 
1.00K 
G21796-026 
R9L7 
1
1
2
1/16W 
CHIP 
0402 
1% 
1.00K 
G21796-026 
R1G3 
1
2
1/16W 
CHIP 
0402 
1% 
1.00K 
G21796-026 
R1F6 
1
2
1/16W 
CHIP 
0402 
1% 
1.00K 
2
1
X7R 
25V 
0402V 
10% 
0.01UF 
A36096-045 
C9M2 
1 2
1/16W CHIP 
0402 1.0% 
2
G21796-274 
R9M2 
1
2
1/16W 
CHIP 
0402 
1% 
1.00K 
G21796-026 
R9M1 
81 82 55 
87 88 55 
79 80 
85 86 55 
55 77 78 
83 84 
55 
55 
CAD NOTE: 
CAD NOTE: 
CAD NOTE: CAD NOTE: 
CAD NOTE: CAD NOTE: 
DO NOT SCALE DRAWING SHEET 
B
AA
B
B
SIZE 
SCALE: 
234
1234
DEPARTMENT CODE 
1
DOCUMENT NUMBER REV 
PVDDQ_GHJ 
IN 
IN 
OUT 
PVDDQ_KLM 
OUT 
PVDDQ_GHJ 
IN OUT 
IN 
OUT 
PVDDQ_KLM 
OUT 
PVDDQ_GHJ 
IN 
IN 
PVDDQ_KLM 
OUT 
100 OF 270 
Wed Feb 08 16:34:57 2017 
PLACE BETWEEN DIMM_M1 & M2 PLACE BETWEEN DIMM_L1 & L2 
PLACE BETWEEN DIMM_H1 & H2 PLACE BETWEEN DIMM_G1 & G2 PLACE BETWEEN DIMM_ J1 & J2 
PLACE BETWEEN DIMM_K1 & K2 
CPU SIDE BAND:CPU1 DIMM CA VREF 
WIWYNN CORPORATION 



A36096-045 
G21796-074 0402 1/16W CHIP 
33.2 
CHIP 
CHIP 
22.1 
22.1 
0402 
CHIP 
R2T42 
0402 
CLK_50M_CKMNG_BMC_2 
CLK_50M_CKMNG_SPRVLLE 
CLK_25M_BMC 
CLK_50M_CKMNG_PCH_10GBE 
G21796-250 
1/16W 
G21796-250 
G21796-250 
X6S 
G21796-250 1.0% 
22.1 
33.2 
C8F19 
15.0PF 
GND=GND 
IC 
0402LF 
1
A36095-047 
PWRGD_P3V3_STBY 
2
Y8F1 
XTAL_CK_MNG_OUT 
C2T18 
A36096-045 
0.01UF 
10% 
25V 
X7R 
1
2
0402V 
R2T21 
2.2 1.0% 0603 
CHIP 
21
1/10W 
G22026-127 
0402V 
D97712-004 
C2T19 
1.0UF 
6.3V 
1
2
10% 
0402V 
C2T34 
0.1UF 
10% 
16V 
X7R 
1
2 A36096-030 
10% 
X7R 
A36096-030 
0402V 
16V 
1
2
0.1UF 
C2T30 C2T25 
A36096-030 
0.1UF 
10% 
16V 
X7R 
1
2
C2T17 
A36096-030 
0.1UF 
10% 
16V 
X7R 
1
2
0402V 
C2T22 
10UF 
10% 
16V 
2
1
X6S 
0805 
C95333-007 
FB2T2 
600 
SMLF 
FB 
21
656554-043 
D97712-004 
1.0UF 
0402V 
6.3V 
X6S 
1
2
10% 
C2T28 
0402 
2
1/16W 
1
G21796-250 1.0% 
CHIP 
21R2T46 
CHIP 
R2T47 
0402 1% 
1 2
1/16W 
33.2 
G21796-074 
0402 CHIP 
R1W22 
0.0 1/16W 
1
5% G21497-005 
2
0402 CHIP 
R1W23 
0.0 
21
1/16W G21497-005 5% 
R1W24 
5% 0.0 0402 
1
1/16W 
G21796-026 
R1W25 
1.00K 
1% 
0402 
CHIP 
1/16W 
2
1
G21796-074 
R8F27 
1/16W CHIP 1% 
1 2
0402 
1/16W 
R8G24 1 2
0402 1.0% 
22.1 
1/16W 
R8G25 1 2
0402 1.0% 
22.1 
R8G1 1 2
CHIP 1.0% 1/16W 
2
1% 
1 R8F29 
0402 
G21796-077 
R8F25 
475.0 
1/16W 
CHIP 
1% 
2
1
26 
34 
17 
27 
5
12 
16 
13 
7
3
1
41 
21 
35 
10 
30 
11 
25 
38 
39 
23 
2
9
15 
31 
IC 
4
18 
14 
37 
EU8F2 
28 
29 
32 
33 
8
36 
22 
24 
1
1% 
CHIP 
R2T25 
1/16W 
2
0402 
1.00K 
CLK_25M_CPLD 
10% 
1
6.3V 
1.0UF 
C2T31 
D97712-004 
0402V 
2 X6S 2
1
X7R 
25V 
10% 
0.01UF 
C2T27 
0402V 
A36096-045 
1 2
1/10W CHIP 
0603 
1.0% 2.2 
G22026-127 
R2T23 
R2T52 
1/10W 
21
2.2 
G22026-127 
1.0% 
CHIP 
0603 
1
2
10% 
X6S 
6.3V 
0402V 
1.0UF 
C2T38 
D97712-004 
C2T37 
0402V 
1
10% 
2
25V 
0.01UF 
X7R 
TP_CLK_100M_R_DP 
TP_CLK_100M_R_DN 
TP_CLK_96M_CKMNG_P 
TP_CLK_96M_CKMNG_N 
CLK_32K_SUSCLK_PLD 
CLK_50M_CKMNG_BMC_2_R 
CLK_50M_CKMNG_SPRVLLE_R 
CLK_50M_CKMNG_PCH_10GBE_R 
CLK_32K_SUSCLK_PLD_R 
CLK_50M_CKMNG_BMC_1 
CLK_50M_CKMNG_OCP 
PD_CKMNG_OE 
PU_33P_33M_SMBADR 
CLK_50M_CKMNG_BMC_1_R 
CLK_50M_CKMNG_OCP_R 
TP_CLK5_50M_CKMNG 
TP_CLK_125M_BMCA 
TP_CLK_125M 
SMB_HOST_STBY_LVC3_SDA 
SMB_HOST_STBY_LVC3_SCL SMB_HOST_STBY_LVC3_SCL_R4 
SMB_HOST_STBY_LVC3_SDA_R4 
A_COMP_CKMNG 
CLK_25M_CPLD_R 
CLK_25M_BMC_R 
P3V3_STBY_MNG 
P3V3_STBY_MNG_RGMII 
P3V3_STBY_MNG P3V3_STBY_MNG_RMII 
P3V3_STBY_MNG 
P3V3_STBY_MNG 
P3V3_STBY_MNG_RGMII 
P3V3_STBY_MNG_RMII 
P3V3_STBY_MNG_CPU 
P3V3_STBY_MNG 
P3V3_STBY_MNG_CPU 
0402V 
19 
CHIP 
40 
E95226-001 
50V 
5% 
G21796-026 
G21497-005 
XTAL_CK_MNG_OUT_R 
6
XTAL_CK_MNG_IN 
20 
COG 2
3
1
0402LF 
A36095-047 
C8F18 
1
25.000MHZ 
D71700-033 
15.0PF 
50V 
5% 
COG 
2
TP FAB3 CHANGE CAP 0823 
147 
139 
145 
121 
240 189 191 196 237 239 
190 
190 
147 
186 
102 111 138 156 159 247 
138 159 102 111 156 247 
GROUP=NI_I210&RJ45 
C95333-007 
16V 
0805 
10UF 
C1W17 
10% 
EMPTY 
CURRENT SHOULD FLOW THROUGH 10UF CAP PAD 
PLACE ALL 0.1UF NEAR CHIP PIN 
PLACE 10UF CAP CLOSE TO FERRITE BEAD 
10UF CAP AND 0.1UF CAP SHOULD BE SEPARATED BY 250MILS 
CAD NOTE: 
CAD NOTE: 
CAD NOTE: 
CAD NOTE: 
1
2
DO NOT SCALE DRAWING SHEET 
B
AA
B
B
SIZE 
SCALE: 
234
1234
DEPARTMENT CODE 
1
DOCUMENT NUMBER REV 
OUT 
OUT 
OUT 
OUT 
OUT 
OUT 
IN 
OUT 
BI 
IN 
OUT 
P3V3_STBY 
ROOM=SYS_CLOCK 
101 OF 270 
ICS9FGP204 
RGMII<1> 
RGMII<0> 
GND_RGMII 
VDD_RGMII 
SMBDAT 
X2_25 
SMBCLK 
VTTPWR_GD_PD_N 
VDDCPU 
GNDCPU 
OE_CPU 
VDD96 
OE_96 
VDD33 
33MHZ_SMBADR 
GNDRMII<1> 
VDDRMII<1> 
VDDRMII<0> 
GNDRMII<0> 
X1_25 
IREF 
VDDREF 
CPUCLKT0 
GNDREF 
CPUCLKC0 
DOT96SST DOT96SSC 
GND<0> GND33 
GND<1> 
RMII<0> 
RMII<3> RMII<4> RMII<5> 
RMII<2> 
RMII<1> 
25MHZ_1 25MHZ_0 
GND32K 
32KHZ 
VDD32K 
TP FAB1 CHANGE RESISTANCE 0216 
TP FAB1 CHANGE RESISTANCE 0216 
TP FAB1 ADD RES 0215 TP FAB1 ADD RES 0215 
TP FAB1 ADD CAP 0215 
TP FAB1 ADD RES 0215 
SMBUS ADDRESS =0XD0 
PLACE SOURCE TERM RES WITHIN 1 INCH OF CKMNG+ 
PLACE CAPS CLOSE TO CK-MNG+ PINS 
PLACE 0.01UF NEAR CHIP PIN 
CKMNG+ Wed Feb 08 16:34:58 2017 
CKMNG+ 
WIWYNN CORPORATION 



13 SMB_HOST_STBY_LVC3_SCL_R2 
G22026-127 
EU4D2 
SMB_HOST_STBY_LVC3_SCL_R2 
FM_DB1200_SMB_SA1 
CLK_100M_CPU0_RC_REFCLK1_R_DN 
CLK_100M_CPU1_BCLK0_R_DP 
CLK_100M_CPU0_RC_REFCLK0_R_DN 
CLK_100M_CPU1_RC_REFCLK1_R_DN 
CLK_100M_CPU1_RC_REFCLK0_R_DP 
CLK_100M_CPU1_RC_REFCLK1_R_DP 
CLK_100M_CPU1_RC_REFCLK0_R_DN 
CLK_100M_CPU1_PE_REFCLK_R_DP 
CLK_100M_CPU1_BCLK2_R_DP 
CLK_100M_CPU1_PE_REFCLK_R_DN 
CLK_100M_CPU1_BCLK1_R_DP 
CLK_100M_CPU1_BCLK2_R_DN 
CLK_100M_CPU1_BCLK1_R_DN 
CLK_100M_CPU0_BCLK1_R_DP 
CLK_100M_CPU0_BCLK0_R_DP 
FM_CPU0_MCP_CLK_EN_N 
FM_CPU1_MCP_CLK_EN_N 
FM_100M_N 
FM_HBW_BYPASS_LOWBW_N 
CLK_100M_CPU0_RC_REFCLK1_R_DP 
SMB_HOST_STBY_LVC3_SCL 
SMB_HOST_STBY_LVC3_SDA SMB_HOST_STBY_LVC3_SDA_R2 
FM_DB1200_SMB_SA0 
CLK_100M_CPU1_BCLK0_R_DN 
CLK_100M_CPU0_RC_REFCLK0_R_DP 
CLK_100M_CPU0_PE_REFCLK_R_DP 
CLK_100M_CPU0_BCLK1_R_DN 
P3V3_DB1200_A 
CLK_100M_CPU0_PE_REFCLK_R_DN 
CLK_100M_CPU0_BCLK2_R_DP 
CLK_100M_CPU0_BCLK2_R_DN 
CLK_100M_CPU0_BCLK0_R_DN 
P3V3_DB1200_R 
SMB_HOST_STBY_LVC3_SDA_R2 
FM_DB1200_SMB_SA1 
FM_DB1200_SMB_SA0 
FM_CPU0_MCP_CLK_EN_N 
FM_DB1200ZL_BCLKS_EN_N 
FM_DB1200ZL_BCLKS_EN_N 
FM_CPU1_MCP_CLK_EN_N 
FM_DB1200_PWRGD 
FM_100M_N 
FM_HBW_BYPASS_LOWBW_N 
CLK_100M_DB1200_DN 
CLK_100M_DB1200_DP 
G21796-072 
1
1% 
1/16W 
CHIP 2
R4D70 
0402 
4.75K 
CHIP 
0402 
G21796-072 
1/16W 
1% 
4.75K 
R4D69 
2
1
R6P48 
G21796-072 
1/16W 
CHIP 
0402 
1% 
2
14.75K 
G21796-026 
0402 
CHIP 
1/16W 
1% 
1.00K 1
R6P20 
2
G21796-026 
0402 
CHIP 
1/16W 
1% 
1.00K 
R6P21 
2
1
1
600 
SMLF 
FB6P1 
2
FB 
656554-043 
0.1UF 
C6P9 
2
0402V 
10% 
X7R 
16V 
A36096-030 
1
0402 
G21796-072 
CHIP 
1/16W 
1% 
4.75K 
R4D41 
2
1
P3V3_DB1200 
0402 
G21796-072 
EMPTY 
1/16W 
1% 
4.75K 
R6P22 
1
2
0402 
G21796-072 
EMPTY 
1/16W 
1% 
4.75K 
R6P23 
2
1
1
2
R4D40 
4.75K 
1% 
1/16W 
CHIP 
G21796-072 
0402 
P3V3_DB1200 
G21796-016 
0402 
EMPTY 
1/16W 
1% 
10.0K 
R4D35 
2
1
1/16W 
EMPTY 
0402 
1% 
10.0K 
R4D38 
1
2
G21796-016 
0402V 
D97712-004 
6.3V 
X6S 
10% 
1.0UF 
C4D27 
2
1
0402V 
C4D22 1
2 A36096-030 
X7R 
10% 
16V 
0.1UF 
P3V3_DB1200 
CHIP 
1.0% 
1/10W 
0603 
2.2 
21
R6P25 
G22026-127 
P3V3_DB1200 
P3V3_DB1200 
P3V3_DB1200 
1/10W 
R3D14 
2
CHIP 
1
0603 
1.0% 2.2 
6.3V 
1.0UF 
C4D23 
0402V 
D97712-004 
X6S 
10% 
1
2
16V 
A36096-030 
0402V 
C4D24 1
2 X7R 
0.1UF 
10% 
16V 
0.1UF 1
2 X7R 
10% 
0402V 
A36096-030 
C6P11 C6P12 
2 X7R 
16V 
0402V 
10% 
A36096-030 
1 0.1UF 
C6P5 
0.1UF 
A36096-030 
10% 
2 X7R 
16V 
0402V 
10.1UF 
2
1
10% 
0402V 
16V 
X7R 
A36096-030 
C6P10 
0.1UF 
10% 
0402V 
16V 
X7R 2
1 C6P6 
A36096-030 
0402 
1/16W 
EMPTY 
G21497-005 0.0 
5% 
R4W5 
FET 
Q4W2 
1
3
2 C79254-001 
2N7002 
P3V3_DB1200 
0.1UF 
16V 
10% 
0402V 
X7R 
2
A36096-030 
1 C6P4 
CHIP 
G21796-072 
0402 
R4W6 
1/16W 
1% 
4.75K 1
2
P3V3_DB1200 P3V3_DB1200 
1% 
0402 
1/16W 
CHIP 
G21796-026 
1.00K 
R4W2 
1
2
Q4W1 
2N7002DW 
FET 
D24280-001 
Q4W1 
D24280-001 
FET 
2N7002DW 
2
1
X7R 
16V 
0805 
10% 
10UF 
G10601-001 
C3D22 
H13585-001 
5
10 
6
37 
4
30 
32 
45 
62 
61 
52 
44 
36 
29 
28 
20 
19 
48 
63 
25 
57 
42 
15 
16 
38 
18 
8
14 
24 
40 
56 
49 
65 
17 
22 
21 
27 
26 
31 
35 
34 
39 
43 
47 
46 
51 
50 
55 
54 
60 
59 
64 
7
23 
33 
41 
58 
2
3
IC 
1
53 
11 
12 
9
102 
102 
102 
103 
103 
103 
103 
103 
103 
103 
103 
103 
103 
103 
103 
103 
103 
103 
191 102 
191 102 
102 
102 
103 
138 159 101 111 156 247 
101 111 138 156 159 247 
102 
103 
103 
103 
103 
103 
103 
103 
103 
102 
102 
102 
102 191 
102 190 
190 102 
102 191 
191 
102 
102 
114 
114 
P3V3_DB1200_R1 
FM_DB1200_PWRGD_R 
0402 
G21497-013 
R4W4 
3.3K 
CHIP 
1/16W 
5% 
0402 
G21497-013 
R4W3 
CHIP 
1/16W 
3.3K 
5% 
S
D
G
DESIGN NOTE: 
DESIGN NOTE: 
DESIGN NOTE: 
'1' FOR 100M MODE 
'0' FOR 133M MODE 
'0' FOR LBW MODE 
'1' FOR HBW MODE (DEFAULT) 
PU & PD FOR BYPASS MODE 
2
1
2
1
DO NOT SCALE DRAWING 
S
D
G
S
D
G
6
2
1
3
5
4
SHEET 
B
AA
B
B
SIZE 
SCALE: 
234
1234
DEPARTMENT CODE 
1
DOCUMENT NUMBER REV 
IN 
OUT 
OUT 
OUT 
P3V3 
IN 
P3V3 
IN 
OUT IN 
BI BI 
OUT 
OUT 
OUT 
OUT 
OUT 
OUT 
OUT 
OUT 
OUT 
OUT 
OUT 
OUT 
OUT 
OUT 
OUT 
OUT 
OUT 
OUT 
OUT 
OUT 
OUT 
OUT 
OUT 
OUT 
OUT 
OUT 
IN 
OUT 
OUT 
IN 
IN 
IN 
BI 
IN 
IN 
IN 
IN 
1 2
102 OF 270 
Wed Feb 08 16:34:58 2017 
NB3W1200L 
SCL 
100M_133M_N 
OE_2_N 
OE_1_N 
OE_0_N 
OE_3_N OE_4_N OE_5_N OE_6_N OE_7_N 
VDDIO<1> VDDIO<2> 
VDDIO<0> 
VDDIO<3> 
OE_8_N 
OE_11_N 
OE_10_N 
OE_9_N 
VDD<2> 
VDD<1> 
VDDR 
VDD<0> 
VDDA 
GND<2> 
GND<4> 
GND<3> 
GND<5> 
THPAD GND<0> GND<1> 
GNDA 
DIF_2N DIF_1P DIF_1N DIF_0P DIF_0N 
DIF_2P 
DIF_6N DIF_5P 
DIF_3P 
DIF_4P DIF_4N 
DIF_5N 
DIF_3N 
DIF_6P DIF_7N DIF_7P 
DIF_11N DIF_11P 
DIF_10N DIF_9P 
DIF_10P 
DIF_9N DIF_8P DIF_8N 
CLK_INN CLK_INP 
HBW_BYPASS_LOBW_N 
PWRGD_PWRDN_N 
SA_0 
SA_1 
SDA 
NC<0> 
NC<2> 
NC<1> 
TP FAB1 CHANGE CONNECTION 0318 
SMBUS ADDRESS: 0XD8 
TP FAB1 NOPOP RES 0318 
TP FAB1 ADD ISOLATION CIRCUIT 0317 
ROOM=DB1200Z 
BOM_COST=SYS_CLOCK 
TP FAB1 ADD MOS 0318 
TP FAB1 DEL NETS 0309 
RC CLKS USED FOR DEBUG ONLY 
DB1200ZL 
WIWYNN CORPORATION 



CLK_100M_CPU1_PE_REFCLK_R_DN 
G21796-259 
CLK_100M_CPU1_RC_REFCLK1_R_DP 
CLK_100M_CPU1_RC_REFCLK0_DN 
CLK_100M_CPU1_BCLK0_R_DN 
CLK_100M_CPU1_BCLK0_R_DP 
CLK_100M_CPU1_BCLK1_R_DN 
CLK_100M_CPU1_BCLK1_R_DP 
CLK_100M_CPU1_BCLK2_R_DN 
CLK_100M_CPU1_BCLK2_R_DP 
CLK_100M_CPU1_PE_REFCLK_R_DP 
CLK_100M_CPU1_RC_REFCLK0_R_DN 
CLK_100M_CPU1_RC_REFCLK1_R_DN 
CLK_100M_CPU1_BCLK1_DN 
CLK_100M_CPU1_BCLK0_DP 
CLK_100M_CPU1_BCLK0_DN 
CLK_100M_CPU1_PE_REFCLK_DP 
CLK_100M_CPU1_PE_REFCLK_DN 
CLK_100M_CPU1_BCLK2_DP 
CLK_100M_CPU1_BCLK2_DN 
CLK_100M_CPU1_BCLK1_DP 
CLK_100M_CPU1_RC_REFCLK1_DN 
CLK_100M_CPU1_RC_REFCLK0_DP 
CLK_100M_CPU0_PE_REFCLK_R_DP 
CLK_100M_CPU0_RC_REFCLK0_R_DN 
CLK_100M_CPU0_RC_REFCLK0_R_DP 
CLK_100M_CPU0_RC_REFCLK1_R_DP 
CLK_100M_CPU0_BCLK0_R_DP 
CLK_100M_CPU0_BCLK0_R_DN 
CLK_100M_CPU0_BCLK1_R_DN 
CLK_100M_CPU0_BCLK1_R_DP 
CLK_100M_CPU0_BCLK2_R_DN 
CLK_100M_CPU0_BCLK2_R_DP 
CLK_100M_CPU0_PE_REFCLK_R_DN 
CLK_100M_CPU0_BCLK1_DN 
CLK_100M_CPU0_BCLK0_DP 
CLK_100M_CPU0_BCLK0_DN 
CLK_100M_CPU0_RC_REFCLK0_DN 
CLK_100M_CPU0_PE_REFCLK_DP 
CLK_100M_CPU0_PE_REFCLK_DN 
CLK_100M_CPU0_BCLK2_DP 
CLK_100M_CPU0_BCLK2_DN 
CLK_100M_CPU0_BCLK1_DP 
CLK_100M_CPU0_RC_REFCLK1_DP 
CLK_100M_CPU0_RC_REFCLK0_DP CLK_100M_CPU1_RC_REFCLK0_R_DP 
CLK_100M_CPU1_RC_REFCLK1_DP 
CLK_100M_CPU0_RC_REFCLK1_R_DN CLK_100M_CPU0_RC_REFCLK1_DN 
G21796-182 
1% 0402 
CHIP 
2
R4D10 
1/16W 
1
27.4 
G21796-182 
R4D12 
1% 0402 
CHIP 
2
1/16W 
1
27.4 
0402 
CHIP 
G21796-182 
21
1% 1/16W 
27.4 
R4D23 
G21796-182 
1% 0402 
CHIP 
2
R4D7 
1/16W 
27.4 
1
G21796-182 
CHIP 
2
R4D8 
27.4 
1
1% 0402 1/16W 
G21796-182 
1% 0402 
CHIP 
2
R4D5 
1/16W 
27.4 
1
G21796-182 
1% 0402 
CHIP 
2
R4D6 
1/16W 
27.4 
1
G21796-182 2
R4D29 
1
27.4 CHIP 
1% 0402 1/16W 
G21796-182 
CHIP 
0402 
2
R4D3 
1
1% 1/16W 
27.4 
G21796-182 2
R4D4 
1
CHIP 
0402 1% 1/16W 
27.4 
G21796-182 
0402 
CHIP 
2
1% 1/16W 
R4D1 
1
27.4 
G21796-182 
0402 
CHIP 
2
1% 
R4D2 
1/16W 
1
27.4 
G21796-182 
R4D11 
21
0402 
CHIP 
1% 1/16W 
27.4 
G21796-182 
0402 
CHIP 
2
R4D9 
1
1% 1/16W 
27.4 
G21796-182 
R4D16 
0402 
CHIP 
2
1% 1/16W 
1
27.4 
G21796-182 
R4D13 
0402 
CHIP 
2
1% 1/16W 
1
27.4 
G21796-182 
R4D21 
0402 
CHIP 
21
1% 1/16W 
27.4 
G21796-182 
R4D19 
CHIP 
21
1% 0402 1/16W 
27.4 
G21796-259 
1.0% 
2
EMPTY 0402 
R6P15 
42.2 
1/16W 
1
0402 
G21796-259 
EMPTY 
1.0% 
2
R6P17 
42.2 
1/16W 
1
0402 
G21796-259 2
EMPTY 
1.0% 
R4D18 
42.2 
1/16W 
1
G21796-259 2
R4D24 
1
42.2 1.0% 
0402 EMPTY 1/16W 
0402 
G21796-259 
1.0% 
2
EMPTY 
R6P12 
42.2 
1/16W 
1
0402 
G21796-259 
EMPTY 
1.0% 
2
R6P13 
42.2 
1/16W 
1
G21796-259 2
R6P9 
0402 EMPTY 
1.0% 42.2 
1/16W 
1
0402 
G21796-259 2
1.0% 
EMPTY 
R6P11 
42.2 
1/16W 
1
0402 
G21796-259 
EMPTY 
1.0% 
2
R6P2 
42.2 
1/16W 
1
R6P1 
G21796-259 21
0402 
1.0% 42.2 
1/16W EMPTY 
0402 
G21796-259 2
EMPTY 
1.0% 
R6P4 
42.2 
1/16W 
1
0402 
G21796-259 2
1.0% 
EMPTY 
R6P3 
1
42.2 
1/16W 
G21796-259 
0402 
2
1.0% 
R6P6 
1
42.2 
EMPTY 1/16W 
G21796-259 
0402 
R6P5 
EMPTY 
2
1.0% 
1
42.2 
1/16W 
R4D28 
G21796-182 
0402 
CHIP 
2
1% 1/16W 
1
27.4 
G21796-259 
0402 
2
EMPTY 
1.0% 
R6P8 
1
42.2 
1/16W 
G21796-259 2
R6P7 
1
42.2 1.0% 
0402 EMPTY 1/16W 
G21796-259 
0402 
2
1.0% 
EMPTY 
R7P2 
1
42.2 
1/16W 
G21796-259 
0402 EMPTY 
2
1.0% 
R7P1 
1
42.2 
1/16W 
G21796-259 
0402 
2
R7P4 
1
EMPTY 
1.0% 42.2 
1/16W 
G21796-259 
0402 
2
1.0% 
EMPTY 
R7P3 
1
42.2 
1/16W 
0402 EMPTY 
1.0% 
R7P7 
42.2 
1/16W 
R7P6 
G21796-259 21
0402 EMPTY 
1.0% 42.2 
1/16W 
0402 
G21796-259 
2
EMPTY 
1.0% 
R7P12 
42.2 
1/16W 
1
0402 EMPTY 
2
1.0% 
R7P9 
G21796-259 
1
42.2 
1/16W 
G21796-182 
1% 0402 
CHIP 
2
R4D20 
1/16W 
27.4 
1
G21796-182 2
1% 0402 
CHIP 
R4D22 
1/16W 
1
27.4 
G21796-182 2R4D14 1
1% 0402 
CHIP 
1/16W 
27.4 
G21796-182 2
CHIP 
0402 1% 
R4D17 
1/16W 
27.4 
1
G21796-182 2
CHIP 
0402 1% 
R4D25 
1/16W 
1
27.4 
102 
102 
56 
102 
102 
102 
102 
102 
102 
102 
102 
102 
55 
55 
55 
63 
63 
55 
55 
55 
70 
56 
102 
102 
102 
102 
102 
102 
102 
102 
102 
102 
102 
21 
21 
21 
22 
29 
29 
21 
21 
21 
36 
22 102 
70 
102 36 
CAD NOTE: 
DESIGN NOTE: 
DO NOT SCALE DRAWING SHEET 
B
AA
B
B
SIZE 
SCALE: 
234
1234
DEPARTMENT CODE 
1
DOCUMENT NUMBER REV 
OUT 
IN OUT 
IN OUT 
IN OUT 
IN OUT 
IN OUT 
IN OUT 
IN OUT 
IN 
OUT 
OUT 
IN OUT 
IN 
OUT 
OUT 
IN OUT 
IN 
IN 
OUT 
IN OUT 
IN OUT 
IN OUT 
IN OUT 
IN 
IN OUT 
IN OUT 
IN 
OUT 
OUT 
IN OUT 
IN 
IN 
103 OF 270 
Wed Feb 08 16:34:58 2017 
ROOM=DB1200Z 
BOM_COST=SYS_CLOCK 
SOURCE WITHIN 0.5 INCHES 
PLACE RESISTORS CLOSE TO CLK 
ONLY REQUIRED WITH -L VERSION 
PARALLEL RESISTORS ARE NOT 
REQUIRED WITH -ZL VERSION 
DB1200ZL CLOCK TERMINATION 
WIWYNN CORPORATION 



FM_CPU1_STL_BRD_OSC_EN 
G21497-005 
G21497-005 
CLK_156M_OSC_BRD_CPU1_DN 
0402 
R7D39 
2
CHIP 
CLK_156M_OSC_CPU1_HFI_DN 
CLK_322M_OSC_CPU1_RC_DP 
CLK_156M_OSC_CPU0_HFI_DN 
CHIP 
EMPTY 
5% 
5% CHIP 
0402 
1/16W 
1 2
5% 
R6F10 
EMPTY 0.0 
0.0 
1
5% EMPTY 
R6F6 
R6F7 
1/16W 
21
0.0 5% 
0402 
0402 5% 
1
0.0 1/16W 
R6F8 
1
5% 0402 
R6F9 
2
0.0 1/16W 
G63831-004 
0.0 1/16W 
G21497-005 
CLK_156M_OSC_BRD_CPU1_DP 
CLK_156M_OSC_BRD_CPU0_DP 
CLK_156M_OSC_BRD_CPU0_DN 
FM_156M_CPU1_BRD_OSC_EN 
FM_CPU1_VRM_OSC_EN 
FM_CPU0_STL_BRD_OSC_EN 
FM_CPU0_STL_BRD_OSC_EN 
FM_CPU1_STL_BRD_OSC_EN 
2
R7D38 
1/16W 
1
0.0 
2
CHIP 5% 
R7D36 
1/16W 
1
0.0 
0402 
2
5% 
1
0402 CHIP 
2
5% 
R8D43 
1
2
1
6
Y3F1 
OSC 
156.25MHZ 
4
5
3
G63831-004 
Y6F1 
2
1
6
4
3
5
OSC 
21
1/16W 0.0 
A36096-030 
0.1UF 
0402V 
16V 
C3F2 
10% 
X7R 2
1
A36096-030 
0402V 
0.1UF 
C6F1 1
16V 
X7R 
10% 
2 156.25MHZ 
FM_CPU0_VRM_OSC_EN 
0.0 
1
R3F3 
2
0.0 1/16W 
1 2
5% 
5% 
EMPTY 
EMPTY 
CLK_322M_156M_CPU1_OSC_VRM_DP 
CLK_156M_OSC_BRD_CPU1_DP 
0.0 5% 
2
1/16W 0.0 
1
5% 
2
0402 
1
EMPTY 
R3F5 
1/16W EMPTY 
R3F1 
R3F2 
0.0 EMPTY 
CLK_322M_156M_CPU1_OSC_VRM_DN 
1 2 G21497-005 
G21497-005 2
R6F11 
1/16W 
G21497-005 
0402 
G21497-005 
R3F6 
1/16W 
CLK_156M_OSC_BRD_CPU1_DN 
CLK_322M_156M_CPU0_OSC_VRM_DP 
CLK_156M_OSC_BRD_CPU0_DP 
0402 
G21497-005 
G21497-005 
0402 CHIP 
2
1/16W 
0402 
G21497-005 
G21497-005 
CLK_156M_OSC_BRD_CPU0_DN 
CLK_322M_156M_CPU0_OSC_VRM_DN 
G21497-005 
CLK_156M_OSC_CPU1_HFI_DP 
CLK_322M_OSC_CPU1_RC_DN 
CLK_322M_OSC_CPU0_RC_DP 
CLK_156M_OSC_CPU0_HFI_DP 
CLK_322M_OSC_CPU0_RC_DN 
0.0 
FM_156M_CPU0_BRD_OSC_EN 
1/16W 
R7D40 
EMPTY 
5% 
0402 
G21497-005 
EMPTY 
G21497-005 
0402 
G21497-005 
1/16W 0402 
1
R3F4 
CHIP 5% 
2
0.0 
G21497-005 
1/16W 0402 
1
CHIP 5% 0.0 
FM_CPU1_VRM_322M_156M_OSC_EN 2
R7D37 
0402 
G21497-005 
G21497-005 
1/16W 0402 
1
5% 0.0 
FM_CPU0_VRM_322M_156M_OSC_EN 
TP FAB3 POP R7D37 1101 
TP FAB3 POP R7D39 1101 
TP FAB3 ADD R6W31 0803 
TP FAB3 RECONNECT R6W31 1012 
TP FAB3 DELETE R6W31 1019 
TP FAB3 ADD R6W32 0803 
TP FAB3 RECONNECT R6W32 1012 
TP FAB3 DELETE R6W32 1019 
TP FAB3 ADD R6W33 0803 
TP FAB3 RECONNECT R6W33 1012 
TP FAB3 DELETE R6W33 1019 
TP FAB3 ADD R6W34 0803 
TP FAB3 RECONNECT R6W34 1012 
TP FAB3 DELETE R6W34 1019 
104 
104 
63 
56 
29 
104 
104 
104 
190 
191 
104 
104 
104 
190 
193 
104 
193 
104 
194 
104 
104 
194 
63 
56 
22 
29 
22 
190 
193 
194 
NC_CLK_156M_CPU0_OSC 
NC_CLK_156M_CPU1_OSC 
CAD NOTE: 
CPLD CPU0 STL OSC EN 
CPLD CPU0 MCP OSC EN 
CPU0 MCP 
CPU0 MCP 
CPU0 STL 
CPU1 STL 
CPU1 MCP 
CPU1 STL 
CPU0 VRM 
ON-BOARD CPU0 STL OSC 
ON-BOARD CPU0 STL OSC 
CPU0 VRM 
ON-BOARD CPU1 STL OSC 
ON-BOARD CPU0 STL OSC 
CPU0 STL 
CPU1 MCP 
CPU1 VRM 
ON-BOARD CPU1 STL OSC 
CPU1 VRM 
CPLD CPU1 MCP OSC EN 
CPLD CPU1 STL OSC EN ON-BOARD CPU1 STL OSC 
CPU0 VRM 
CPU1 VRM 
DO NOT SCALE DRAWING SHEET 
B
AA
B
B
SIZE 
SCALE: 
234
1234
DEPARTMENT CODE 
1
DOCUMENT NUMBER REV 
IN 
OUT 
OUT 
OUT 
OUT 
OUT 
IN 
OUT 
IN 
OUT 
OUT 
IN 
IN 
OUT 
OUT 
OUT 
OUT 
IN 
IN 
IN 
OUT 
OUT 
OUT 
IN OUT 
IN 
P3V3 
IN 
P3V3 
IN 
IN 
IN 
104 OF 270 
Wed Feb 08 16:34:58 2017 
OSC_C 
ENABLE_DISABLE OUT 
GND 
VCC OUT_N 
NC_GND 
OSC_C 
ENABLE_DISABLE OUT 
GND 
VCC OUT_N 
NC_GND 
SKX OR SKX MCP STEERING OPTIONS 
USE 322MHZ: 
POP R6F10, R6F11, R3F5, R3F6 
NOPOP R6W31-34 
ROOM=CLOCK_CPU1_OSC 
ROOM=CLOCK_CPU0_OSC 
SKX MCP 
SKX 
CPU 
322MHZ 
FREQUENCY 
156MHZ G63831-004 
OSC IPN 
H77101-001 
N/A 
COMMENTS 
DEBUG ONLY 
FROM CPLD 
322MHZ IS REQUIRED ONLY IF HSSI IS CONFIGURED AS AN ETHERNET. 
USE A COMMON FOOTPRINT FOR RESISTORS 
HFI OSCILLATORS 
ENABLE SIGNALS 
OSC CHOICE BASED ON CPU 
WIWYNN CORPORATION 



X7R 
P3E_CPU0_PE1_PCH_RXP<15:8> 
2
10% 
X7R 
0.22UF 
0402 
A36096-155 
0402 
16V 
10% 
2
1
0.22UF 
16V 
10% 
A36096-155 
0402 
C6B14 
16V 
0402 
0.22UF 
16V 
10% 
2
0402 
C6B20 
A36096-155 
0.22UF 
C7G17 
P3E_CPU0_PE1_PCH_C_TXP<15:8> 
P3E_CPU0_PE1_PCH_TXP<15:8> 
P3E_CPU0_PE1_PCH_RXN<15:8> 
P3E_CPU0_PE1_PCH_R_RXN<15:8> 
P3E_CPU0_PE2_SS_TXN<15:0> 
P3E_CPU0_PE2_SS_C_TXP<15:0> 
P3E_CPU0_PE2_SS_C_TXN<15:0> 
P3E_CPU0_PE1_PCH_TXN<15:8> 
P3E_CPU0_PE1_PCH_R_RXP<15:8> 
P3E_CPU0_PE2_SS_TXP<15:0> 
C8G10 
0.22UF 
A36096-155 
0402 
16V 
X7R 2
1
10% 
2A36096-155 
C8G9 
0.22UF 
10% 
0402 
16V 
X7R 
1
0402 
C7G10 
A36096-155 
0.22UF 
10% 
16V 
X7R 2
1
A36096-155 
10% 
16V 
C8G8 
0.22UF 
0402 
X7R 2
1
A36096-155 
C8G5 1
0.22UF 
10% 
0402 
16V 
X7R 2
0402 
A36096-155 
C8G3 
0.22UF 
10% 
16V 
X7R 2
1
A36096-155 
C8G1 1
0.22UF 
10% 
0402 
16V 
X7R 2
C7G7 
A36096-155 
0.22UF 
10% 
0402 
16V 
X7R 2
1
C7G25 
A36096-155 
0.22UF 
10% 
0402 
16V 
X7R 2
1
A36096-155 
C8G7 
0.22UF 
10% 
0402 
16V 
X7R 2
1
0.22UF 
16V 
C8G6 
A36096-155 
10% 
0402 
2
1
0402 
C7G6 
A36096-155 
0.22UF 
10% 
16V 
X7R 
0.22UF 
10% 
C8G2 
A36096-155 
0402 
16V 
X7R 2
1
A36096-155 
10% 
C8G4 
0.22UF 
0402 
16V 
X7R 2
1
A36096-155 
C7G26 
0.22UF 
10% 
0402 
16V 
X7R 2
1
A36096-155 
C7G23 
16V 
X7R 
10% 
0402 
2
1
C7G21 
0.22UF 
16V 
10% 
X7R 
A36096-155 
0402 
2
1
16V 
0.22UF 
C7G15 
A36096-155 
10% 
0402 
X7R 2
1
A36096-155 
0.22UF 
10% 
0402 
16V 
X7R 2
1
A36096-155 
1
0.22UF 
C7G22 
10% 
0402 
16V 
X7R 2
10% 
X7R 
A36096-155 
0402 
C7G18 
0.22UF 
16V 
2
1
C7G16 
0.22UF 
16V 
10% 
X7R 
A36096-155 
0402 
2
1
C7G14 
A36096-155 
0.22UF 
10% 
0402 
16V 
X7R 2
1
C7G11 
A36096-155 
0.22UF 
10% 
0402 
16V 
X7R 2
1 C7G20 
A36096-155 
0.22UF 
10% 
0402 
16V 
X7R 2
1
1
2X7R 
16V 
0402 
10% 
0.22UF 
A36096-155 
C7G19 
C3M1 
A36096-155 
0.22UF 
10% 
0402 
16V 
1
2X7R 
C3M14 
0.22UF 
10% 
16V 
X7R 2
1
0402 
A36096-155 
A36096-155 
10% 
0402 
16V 
X7R 2
1
C3M12 
A36096-155 
0.22UF 
0402 
16V 
1
2X7R 
C3M4 
0.22UF 
10% 
16V 
X7R 2
1
A36096-155 
0402 
10% 
0.22UF 
C3M13 
A36096-155 
0402 
X7R 2
1
10% 
C3M11 
A36096-155 
0.22UF 
16V 
X7R 2
1
10% 
16V 
X7R 2
1
C3M26 
A36096-155 
0402 
16V 
2
1
X7R 
10% 
0.22UF 
C3M35 
0.22UF 
16V 
X7R 2
1
10% 
A36096-155 
0.22UF 
0402 
16V 
X7R 2
1C3M32 
C7G8 
A36096-155 
0.22UF 
10% 
0402 
16V 
X7R 2
1
0402 
C3M36 
A36096-155 
16V 
X7R 2
1
0402 
A36096-155 2
C3M33 
16V 
1
0.22UF 
C3M28 
10% 
16V 
2
1
C7G9 
A36096-155 
0.22UF 
10% 
0402 
16V 
X7R 2
1
A36096-155 
C3M34 1
16V 
10% 
X7R 2
0402 
A36096-155 
0402 
16V 
C6B5 
A36096-155 
0.22UF 
10% 
0402 
16V 
X7R 2
1
C7G5 
A36096-155 
0.22UF 
10% 
0402 
16V 
X7R 2
1
C6B8 
A36096-155 
0.22UF 
10% 
0402 
16V 
X7R 2
1
10% 
C6B4 
A36096-155 
X7R 2
1
16V 
0.22UF 
A36096-155 
10% 
0402 
16V 
X7R 2
10.22UF 
C6B10 C6B13 
A36096-155 
0.22UF 
10% 
0402 
16V 
X7R 2
1
C6B12 
0402 
16V 
2A36096-155 
X7R 
10% 
0.22UF 1
X7R 2
C6B9 
10% 
1
A36096-155 
10% 
0402 
16V 
X7R 2
10.22UF 
C6B16 
C6B17 
X7R 2
1
A36096-155 
16V 
0.22UF 
A36096-155 
0402 
X7R 2
1
10% 
C6B6 
A36096-155 
0.22UF 
10% 
0402 
X7R 2
1 C6B11 
0.22UF 
16V 
1 C6B15 
0.22UF 
X7R 2
1
A36096-155 
0402 
A36096-155 
C6B19 
0.22UF 
10% 
16V 
X7R 
1
2
C6B18 
0.22UF 
10% 
0402 
16V 
X7R 2
1
C7G13 
A36096-155 
0.22UF 
10% 
0402 
16V 
X7R 2
1
C7G12 
A36096-155 
0.22UF 
10% 
0402 
16V 
X7R 2
1 0.22UF 
10% 
16V 
C7G24 1
X7R 
A36096-155 
0402 
2
16V 
10% 
X7R 
A36096-155 
0402 
0.22UF 
X7R 
A36096-155 
0402 
P3E_CPU0_PE1_PCH_C_TXN<15:8> 
10% 
0402 
0.22UF 
0402 
A36096-155 
1C3M25 
A36096-155 
X7R 
C3M2 
0.22UF 
16V 
0.22UF 0.22UF 
X7R 
10% 10% 10% 
0402 
0.22UF 
C3M3 
30 244 
117 
30 244 
30 244 
117 
31 
109 245 
109 245 
30 244 
117 
31 
117 
GROUP=PCIE_UPLINK 
GROUP=PCIE_UPLINK 
GROUP=PCIE_UPLINK 
GROUP=PCIE_UPLINK GROUP=PCIE_UPLINK 
GROUP=PCIE_UPLINK 
GROUP=PCIE_UPLINK 
GROUP=PCIE_UPLINK 
GROUP=PCIE_UPLINK GROUP=PCIE_UPLINK 
GROUP=PCIE_UPLINK GROUP=PCIE_UPLINK GROUP=PCIE_UPLINK
GROUP=PCIE_UPLINK GROUP=PCIE_UPLINK GROUP=PCIE_UPLINK GROUP=PCIE_UPLINK
GROUP=PCIE_UPLINK GROUP=PCIE_UPLINK GROUP=PCIE_UPLINK GROUP=PCIE_UPLINK 
GROUP=PCIE_UPLINK GROUP=PCIE_UPLINK GROUP=PCIE_UPLINK GROUP=PCIE_UPLINK 
GROUP=PCIE_UPLINK 
GROUP=PCIE_UPLINK GROUP=PCIE_UPLINK 
GROUP=PCIE_UPLINK GROUP=PCIE_UPLINK GROUP=PCIE_UPLINK GROUP=PCIE_UPLINK 
15 
14 
0
0 0
0
1
2
13 
3
4
5
6
7
8
10 
9
12 
13 
14 
15 
1
1
2
3
3
4
4
5
5
2
1
3
5
4
6
14 
6
7
7
8
8
9
9
15 
10 
10 
7
8
9
10 
11 
15 
14 
12 
13 
15 
11 
15 
14 
13 
12 
14 
13 
12 
12 
15 
14 
13 
11 
12 
10 
8
9
11 
10 
11 
10 
9
9
8
8
10 
9
8
15 
14 
15 
14 
13 
12 
11 
10 
13 
9
13 
12 
11 
13 
10 
9
9
8 8
15 
14 
14 
13 
11 
12 
10 
9
14 
8
13 
12 
8
11 
2
15 
15 
11 
12 
11 
10 
11 
6
12 
CAD NOTE: 
DO NOT SCALE DRAWING SHEET 
B
AA
B
B
SIZE 
SCALE: 
234
1234
DEPARTMENT CODE 
1
DOCUMENT NUMBER REV 
OUT 
OUT 
IN 
IN 
IN 
IN 
OUT 
OUT 
OUT 
OUT 
IN 
IN 
105 OF 270 
Wed Feb 08 16:34:59 2017 
TO PCH PCIEUP 
FROM CPU0 
TO X24 SLOT 
DE NOTE: 
CPU0 TO PCIE X24 SLOT TX CAPS 
CPU0 TO PCH PCIEUP TX CAPS 
FROM CPU0 
DE NOTE: 
TO CPU0 
FROM PCH PCIEUP 
C3M3, C3M25, C3M28, C3M36, C3M34, C3M1, C3M12, C3M14, C3M4, C3M26, C3M32, C3M35 AND C3M33 
DE NOTE: 
PCH PCIEUP TO CPU0 RX CAPS 
PCIE_UPLINK POP: C6B4, C6B6, C6B9, C6B11, C6B14, C6B15, C6B17, C6B19, C6B5, C6B8, C6B10, C6B12, C6B13, C6B16, C6B18, C6B20, C3M2, C3M11, C3M13, 
NEAR CPU, PLACE NEAR SLOT 
IF THERE IS NOT ENOUGH ROOM 
PLACE CLOSE TO CPU. 
PCIE TX CAPS 
WIWYNN CORPORATION 



P3E_CPU0_PE3_OCP_TXP<15:0> 
C1R9 
10% 
0402 0402 
P3E_OCP_CPU0_PE3_C_TXP<15:0> 
P3E_OCP_CPU0_PE3_C_TXN<15:0> 
P3E_CPU0_PE3_OCP_TXN<15:0> 
X7R 
16V 
0402 
10% 
0.22UF 
A36096-155 
C1M15 
X7R 
16V 
0402 
10% 
0.22UF 
A36096-155 
C1M17 
X7R 
16V 
0402 
10% 
0.22UF 
A36096-155 
C1M19 
X7R 
16V 
0402 
10% 
0.22UF 
A36096-155 
C2M15 
16V 
X7R 
0402 
0.22UF 
A36096-155 
C1M14 
X7R 
16V 
0402 
10% 
0.22UF 
A36096-155 
C1M16 
X7R 
16V 
10% 
0.22UF 
A36096-155 
C1M18 
X7R 
16V 
0402 
10% 
0.22UF 
A36096-155 
C2M14 
X7R 
16V 
0402 
10% 
0.22UF 
A36096-155 
C1R7 
X7R 
16V 
0402 
10% 
0.22UF 
A36096-155 
C1R5 
X7R 
16V 
0402 
10% 
0.22UF 
A36096-155 
C1R8 
X7R 
16V 
0402 
10% 
0.22UF 
A36096-155 
C1R6 
X7R 
16V 
0402 
10% 
0.22UF 
A36096-155 
C1R3 
X7R 
16V 
0402 
10% 
0.22UF 
A36096-155 
C1R1 
X7R 
16V 
0402 
10% 
0.22UF 
A36096-155 
C1R4 
X7R 
16V 
0402 
10% 
0.22UF 
A36096-155 
C2R9 
X7R 
16V 
10% 
0.22UF 
A36096-155 
C2R10 
X7R 
16V 
0402 
10% 
0.22UF 
A36096-155 
C2R8 
X7R 
16V 
0402 
10% 
0.22UF 
A36096-155 
C2R13 
X7R 
16V 
0402 
10% 
0.22UF 
A36096-155 
X7R 
16V 
0402 
10% 
0.22UF 
A36096-155 
C2R14 
X7R 
16V 
0402 
10% 
0.22UF 
A36096-155 
C1R10 
X7R 
16V 
0402 
10% 
0.22UF 
A36096-155 
C2R7 
X7R 
16V 
0402 
10% 
0.22UF 
A36096-155 
C1M7 
X7R 
16V 
0402 
10% 
0.22UF 
A36096-155 
C1M11 
X7R 
16V 
0402 
10% 
0.22UF 
A36096-155 
C1M9 
X7R 
16V 
0402 
10% 
0.22UF 
A36096-155 
C1M13 
X7R 
16V 
0402 
10% 
0.22UF 
A36096-155 
C1M6 
X7R 
16V 
0402 
10% 
0.22UF 
A36096-155 
C1M8 
X7R 
16V 
0402 
10% 
0.22UF 
A36096-155 
C1M10 
X7R 
16V 
0402 
10% 
0.22UF 
A36096-155 
C1M12 
A36096-155 
X7R 
16V 
0402 
10% 
0.22UF 
C1R2 
32 
186 187 
186 187 
32 
14 
13 
12 
11 
10 
11 
10 
0
9 9
8
11 
10 
11 
10 
9
8 8
8
9
3
2
3
2
3
2
3
2
1
0
1
0
1
0
7
6
7
6
7
6
5
4
5
4
5
4
5
4
7
6
15 15 
14 
13 
12 
14 
13 
12 
1
15 15 
14 
13 
12 
CAD NOTE: 
DO NOT SCALE DRAWING SHEET 
B
AA
B
B
SIZE 
SCALE: 
234
1234
DEPARTMENT CODE 
1
DOCUMENT NUMBER REV 
OUT 
OUT 
IN 
IN 
106 OF 270 
Wed Feb 08 16:34:59 2017 
CPU0 TO OCP MEZZ TX CAPS 
FROM CPU0 
DE NOTE: 
TO OCP 
PLACE CLOSE TO CPU 
CPU OCP TX CAPS 
WIWYNN CORPORATION 



107 30 
117 
30 107 
30 107 
30 107 
117 
30 107 
107 30 
109 
107 30 
107 30 
109 109 
117 
117 
109 
GROUP=PCIE_UPLINK GROUP=PCIE_UPLINK GROUP=PCIE_UPLINK 
GROUP=PCIE_UPLINK 
16V 
16V 
X7R 
0402 
GROUP=PCIE_UPLINK 
GROUP=PCIE_UPLINK GROUP=PCIE_UPLINK 
GROUP=PCIE_UPLINK 
P3E_CPU0_PE1_SS_RXN<7:0> 
GROUP=PCIE_UPLINK 
16V 
0.22UF 
C2U7 
GROUP=PCIE_UPLINK 
GROUP=PCIE_UPLINK GROUP=PCIE_UPLINK GROUP=PCIE_UPLINK 
GROUP=PCIE_UPLINK GROUP=PCIE_UPLINK GROUP=PCIE_UPLINK 
GROUP=PCIE_UPLINK 
GROUP=PCIE_UPLINK 
GROUP=PCIE_UPLINK GROUP=PCIE_UPLINK 
P3E_CPU0_PE1_PCH_TXN<7:0> 
C3P11 
GROUP=PCIE_UPLINK 
GROUP=PCIE_UPLINK 
GROUP=PCIE_UPLINK 
GROUP=PCIE_UPLINK 
GROUP=PCIE_UPLINK 
C3P17 
A36096-155 
X7R 
0402 
0402 
A36096-155 
X7R 
10% 
16V 
0.22UF 
C3P24 
A36096-155 
10% 
16V 
0.22UF 
GROUP=PCIE_RISER GROUP=PCIE_RISER 
GROUP=PCIE_RISER 
GROUP=PCIE_RISER 
GROUP=PCIE_RISER 
5% 
1/16W 
0402 
CHIP 
R2U21 0402 
0.0 
CHIP CHIP 
P3E_CPU0_PE1_SS_TXP<7:0> 
A36096-155 
16V 
C3P34 
P3E_CPU0_PE1_SS_TXN<7:0> 
P3E_CPU0_PE1_SS_TXP<7:0> 
P3E_CPU0_PE1_PCH_TXP<7:0> 
P3E_CPU0_PE1_SS_TXN<7:0> 
P3E_CPU0_PE1_SS_RXP<7:0> 
P3E_CPU0_PE1_SS_R_RXN<7:0> 
P3E_CPU0_PE1_SS_RXP<7:0> 
R2U24 
0.0 
G21497-005 
1/16W 
5% 
0402 
CHIP 
G21497-005 
0402 
R2U22 
CHIP 
0.0 
1/16W 
5% 
R2U20 
0.0 
5% 
1/16W 
CHIP 
0402 
0.0 
G21497-005 
0402 
0.0 
5% 
1/16W 
R2U28 
CHIP 
0402 
G21497-005 
CHIP 
0402 
G21497-005 G21497-005 
0.0 
CHIP 
0402 
1/16W 
R2U26 
5% 
G21497-005 
R2U27 
5% 
1/16W 
CHIP 
0402 
0.0 
R2U25 
0.0 
0.0 
R2U23 
R2U29 
G21497-005 
0.0 
0402 
CHIP 
5% 
1/16W 
0.0 
G21497-005 
R2U17 
5% 
1/16W 
0402 
0.0 
G21497-005 
0402 
1/16W 
5% 
R2U15 
CHIP 
G21497-005 
5% 
1/16W 
0402 
0.0 
0.22UF 
10% 
X7R 
0402 
0.22UF 
16V 
10% 
0402 
A36096-155 
C3P26 
C3P38 
A36096-155 
0402 
X7R 
10% 
0402 
A36096-155 
0402 
10% 
16V 
C3P22 
10% 
X7R 
A36096-155 
0402 
16V 
10% 
X7R 
C3P12 
16V 
0402 
X7R 
C3P29 
0402 
X7R 
16V 
0.22UF 
10% 
X7R 
C3P33 
0402 
10% 
16V 
0.22UF 
C3P16 
10% 
16V 
C3P36 
0.22UF 
X7R 
0402 
10% 
16V 
C3P41 
X7R 
A36096-155 
0402 
10% 
0.22UF 
16V 
16V 
10% 
2
C2U17 
0.22UF 1
0402 
X7R 2
1
C2U13 
0.22UF 
16V 
10% 
X7R 
0402 
X7R 2
0.22UF 
16V 
10% 
1
0402 
C2U15 
C2U18 
16V 
10% 
1
2X7R 
0402 
10% 
0402 
1
2
0.22UF 
0.22UF 
2
1
C2U16 
X7R 
16V 
10% 
10% 
2
C2U9 
10.22UF 
0.22UF 
X7R 
16V 
10% 
2
1
C2U11 
0402 
2
1
X7R 
0402 
10% 
0.22UF 
C2U5 
16V 
1
2
10% 
0402 
X7R 
X7R 2
10.22UF 
10% 
C2U3 
0402 
C2U10 
16V 
1
2
10% 
C2U12 
10% 
16V 
0402 
X7R 
0.22UF 
2
1
10% 
16V 
0.22UF 
X7R 2
0402 
C2U8 
1
C2U6 
10% 
X7R 2
0402 
0402 
X7R 2
10% 
16V 
0.22UF 1
C3P39 
0.22UF 
10% 
16V 
0402 
X7R 
A36096-155 
10% 
16V 
0402 
X7R 
0.22UF 
A36096-155 
C3P30 
X7R 
C3P40 
0.22UF 
16V 
10% 
0402 
A36096-155 
C3P35 
0.22UF 
10% 
16V 
X7R 
0402 
A36096-155 
10% 
16V 
X7R 
0402 
0.22UF 
A36096-155 
C3P37 
16V 
0.22UF 
A36096-155 
10% 
0402 
C3P32 
C3P28 
0.22UF 
0402 
A36096-155 
X7R 
16V 
10% 
X7R 
16V 
0402 
10% 
0.22UF 
A36096-155 
C3P23 C3P15 
10% 
16V 
0.22UF 
X7R 
0402 
A36096-155 
X7R 
A36096-155 
0402 
16V 
10% 
0.22UF 
C3P27 
0.22UF 
10% 
16V 
X7R 
0402 
A36096-155 
10% 
A36096-155 
16V 
0402 
C3P20 
0.22UF 
10% 
X7R 
A36096-155 
16V 
X7R 
10% 
0402 
A36096-155 
0402 
16V 
16V 
0.22UF 
C3P13 
G21497-005 
GROUP=PCIE_RISER 
GROUP=PCIE_RISER 
GROUP=PCIE_RISER 
GROUP=PCIE_RISER 
0402 
G21497-005 
GROUP=PCIE_RISER 
CHIP 
1/16W 
5% 
R2U18 
P3E_CPU0_PE1_SS_RXN<7:0> 
GROUP=PCIE_RISER 
CHIP 
1/16W 
5% 
0.0 
R2U16 
G21497-005 
1/16W 
5% 
0.0 
R2U14 
GROUP=PCIE_RISER 
GROUP=PCIE_RISER 
GROUP=PCIE_RISER 
0.22UF 
X7R 
0.22UF 
16V 
X7R 
C2U14 
0402 
0.22UF 
A36096-155 
X7R 
10% 
16V 
0.22UF 
C3P31 
P3E_CPU0_PE1_SS_R_RXP<7:0> 
0402 
A36096-155 
16V 
0.22UF 
C3P14 
A36096-155 
A36096-155 
0402 
G21497-005 
CHIP 
1/16W 
5% 
GROUP=PCIE_RISER 
G21497-005 
CHIP 
1/16W 
5% 
R2U19 
GROUP=PCIE_RISER 
GROUP=PCIE_RISER GROUP=PCIE_RISER 
GROUP=PCIE_RISER 
GROUP=PCIE_RISER 
C3P21 
A36096-155 
GROUP=PCIE_RISER 
16V 
10% 
X7R 
0.22UF 
C3P10 
16V 
0.22UF 
0402 
A36096-155 
X7R 
0.22UF 
C3P19 
P3E_CPU0_PE1_SS_C_TXN<7:0> 
GROUP=PCIE_RISER GROUP=PCIE_RISER 
0402 
A36096-155 
X7R 
0.22UF 0402 
A36096-155 
X7R 
10% 
0.22UF 
GROUP=PCIE_RISER 
GROUP=PCIE_RISER 
GROUP=PCIE_RISER 
GROUP=PCIE_RISER 
GROUP=PCIE_RISER 
GROUP=PCIE_RISER 
GROUP=PCIE_RISER 
GROUP=PCIE_RISER 
GROUP=PCIE_RISER 
C2U4 
P3E_CPU0_PE1_PCH_RXN<7:0> 
0.22UF 
C3P25 
0.22UF 
0402 
10% 
10.22UF 
X7R 
A36096-155 
X7R 
10% 
X7R X7R 
A36096-155 
C3P18 
0.22UF 
16V 
P3E_CPU0_PE1_PCH_RXP<7:0> 
P3E_CPU0_PE1_SS_C_TXP<7:0> 
GROUP=PCIE_UPLINK 
0402 
16V 
GROUP=PCIE_UPLINK GROUP=PCIE_UPLINK 
GROUP=PCIE_UPLINK GROUP=PCIE_UPLINK GROUP=PCIE_UPLINK GROUP=PCIE_UPLINK 
A36096-155 
A36096-155 
A36096-155 
A36096-155 
4
5
A36096-155 
1
0
0
7
5
4
7
7
6
6
5
5
4
3
2
1
3
2
2
0
7
6
5
4
3
2
1
0
6
7
6
5
7
6
5
7
6
3
2
1
0
4
3
4
3
22
1
0
7
6
5
4
3
2
1
7
A36096-155 
6
A36096-155 
7
7
6
6
5
5
A36096-155 
7
6
5
3
A36096-155 
2
A36096-155 
0
4
3
3
2
A36096-155 
2
1
0
0
4
3
2
1
0
7
6
5
7
7
6
6
5
5
4
4
3
2
1
0
4
3
3
2
2
1
0
0
7
6
5
4
3
2
1
0
0
4
1
4
1
0
1
5
3
A36096-155 
1
A36096-155 
4
A36096-155 
1
A36096-155 
BOM NOTE: 
CAD NOTE: 
CAD NOTE: 
BOM NOTE: 
DO NOT SCALE DRAWING SHEET 
B
AA
B
B
SIZE 
SCALE: 
234
1234
DEPARTMENT CODE 
1
DOCUMENT NUMBER REV 
IN 
IN 
OUT 
OUT IN 
OUT 
OUT 
IN 
IN 
IN 
OUT 
OUT 
IN 
OUT 
OUT 
IN 
TO CPU0 
FROM X24 SUPER SLOT 
CPU0 TO PCIE X24 SLOT TX CAPS 
FROM CPU 0 
DE NOTE: 
FROM CPU 0 
TO X24 SUPER SLOT 
TO PCH PCIEUP 
TO CPU0 
FROM PCH PCIEUP 
107 OF 270 
Wed Feb 08 16:34:59 2017 
PLACE CLOSE TO PCH 
UNSTUFF FOR X24 SS SUPPORT 
STUFF FOR X24 SS SUPPORT 
PLACE CLOSE TO X24 SLOT 
PCIE STEERING 
WIWYNN CORPORATION 
CPU0 <-> X24 SUPER SLOT 
CPU0 <-> PCH PCIEUP 



SMB_SLOTX24_BMC_STBY_LVC3_SCL 
G21796-173 
SMB_SLOTX24_PCH_STBY_LVC3_SDA 
SMB_SLOTX24_STBY_LVC3_SCL_R2 
14 
CLK_100M_PCH_SLOTX24_S2_DP 
SMB_SLOTX24_PCH_STBY_LVC3_SCL 
CLK_100M_PCH_SLOTX24_S0_DP 
CLK_100M_PCH_SLOTX24_S3_DP 
CLK_100M_PCH_SLOTX24_S3_DN 
TP_SLOTX24_RSVD63 
CLK_100M_PCH_SLOTX24_S1_DN 
CLK_100M_PCH_SLOTX24_S4_DN 
CLK_100M_PCH_SLOTX24_S1_DP 
TP_SLOTX24_RSVD66 
CLK_100M_PCH_SLOTX24_S2_DN 
CLK_100M_PCH_SLOTX24_S0_DN 
CLK_100M_PCH_SLOTX24_S5_DN 
CLK_100M_PCH_SLOTX24_S4_DP 
FM_PWRBRK_N 
SMB_SLOTX24_STBY_LVC3_SDA_R2 
CLK_100M_PCH_SLOTX24_S5_DP 
RST_PCIE_RISER1_PERST_N 
SMB_SLOTX24_BMC_STBY_LVC3_SDA 
1
C2U25 
16V 
0.1UF 
A36096-030 
0402V 
10% 
X7R 2A36096-030 
X7R 
16V 
10% 
C2U21 
0.1UF 1
2
0402V 
EMPTY G21796-173 1/16W 0402 
2
R2U36 
1
1% 20.0 
G21796-173 EMPTY 0402 
2
1% R2U35 1/16W 20.0 
1
9
9
8
R7E21 
4.75K 
1% 
1/16W 
G21796-072 
CHIP 
0402 
2
1
1/16W 0.0 CHIP 0402 G21497-005 5% 
R7E22 
21
CHIP 1/16W 0402 1% R2U32 
21
20.0 
0402 1/16W G21796-173 CHIP 1% 
2
R2U31 
1
20.0 
A36096-030 
0402V 
16V 
10% 
X7R 
0.1UF 
C2U22 1
2
C2U23 
0402V 
0.1UF 
A36096-030 
16V 
1
10% 
X7R 2
10 
10 
11 
11 
12 
12 
13 
13 
14 
14 
15 
15 
8
8
9
9
10 
10 
11 
11 
12 
12 
13 
13 
14 
15 
15 
23 
19 
15 16 
26 
4
27 
25 
47 
37 
39 
85 
88 
43 
55 
5
13 
11 
9
7
3
1
46 
48 
50 
52 
32 
30 
64 
33 
8
6
2
10 
12 
14 
18 
20 
22 
28 
34 
36 
42 
44 
31 
29 
45 
51 
56 
58 
62 
70 
72 
68 
66 
82 
84 
90 
92 
53 
61 
65 
63 
67 
71 
69 
73 
77 
79 
83 
87 
91 
94 
100 
MH2 
98 97 
99 
MH1 
49 
81 
76 
93 
59 
86 
40 
38 
CONN 
J8G1 
24 
74 
H68296-001 
95 
54 
80 
78 
75 
89 
96 
21 
60 
57 
35 
41 
17 
A36096-030 
C2U24 
0.1UF 
10% 
16V 
X7R 
1
2
0402V 
0.0 0402 CHIP G21497-005 
2
R2U37 5% 
1
1/16W 
A36096-030 
C2U20 1
0.1UF 
10% 
16V 
X7R 2
0402V 
119 
138 
108 
108 
160 
114 
119 
138 
114 
114 
114 
114 
114 
114 
114 
114 
114 
114 
138 
138 
142 
119 
133 119 147 
157 119 145 
125 119 
108 
114 
190 
133 119 147 
108 
160 
244 
109 244 
244 
244 
SMB_SLOTX24_STBY_LVC3_SDA_R2 
SMB_HOST_STBY_LVC3_SCL_R5 
SMB_HOST_STBY_LVC3_SDA_R5 
FM_PE_SLOTX24_WAKE_N 
FM_PWRBRK_SLOT_N 
FM_SLT_CFG1 
IRQ_OOB_MGMT_RISER_ALERT_N 
PU_PCH_TLS_ENABLE_STRAP 
RST_PCIE_RISER1_PERST_R_N 
FM_SLT_CFG0 
SMB_SLOTX24_STBY_LVC3_SCL_R2 
P3E_CPU0_PE1_PCH_CON_RXN<15:8> 
P3E_CPU0_PE1_PCH_CON_RXP<15:8> 
P3E_CPU0_PE1_PCH_CON_TXP<15:8> 
P3E_CPU0_PE1_PCH_CON_TXN<15:8> 
CAD NOTE: 
PLACE CLOSE TO X24 SLOT 
USE SHARED PADS FOR THESE RESISTORS 
DO NOT SCALE DRAWING SHEET 
B
AA
B
B
SIZE 
SCALE: 
234
1234
DEPARTMENT CODE 
1
DOCUMENT NUMBER REV 
P12V 
IN 
BI 
IN 
IN 
P3V3 
IN 
OUT 
OUT 
IN OUT 
BI BI 
P3V3_STBY 
OUT 
OUT 
OUT 
OUT 
IN 
IN 
IN 
IN 
IN 
IN 
IN 
IN 
IN 
IN 
IN 
IN 
P3V3_STBY 
OUT 
BI 
IN 
P3V3 
OUT 
P3V3 
IN 
IN 
IN 
P3V3 
P12V 
P12V 
108 OF 270 
Wed Feb 08 16:35:00 2017 
SCONN200_H68296001 
1/2 MH2 
IO98 IO96 
IO94 IO92 IO90 IO88 
MH1 
IO65 
IO67 
IO69 
IO100 
IO73 
IO99 
IO78 
IO74 IO72 IO71 IO70 
IO68 IO66 IO64 IO63 IO62 IO61 IO60 IO59 IO58 IO57 IO56 IO55 IO54 IO53 IO52 IO50 IO48 IO46 IO45 IO44 IO43 
IO41 IO40 IO39 IO37 IO36 IO35 IO34 IO33 IO32 IO31 IO30 IO29 IO28 IO27 IO25 IO23 IO21 IO19 
IO16 IO14 IO12 IO10 IO8 IO6 IO4 IO2 
IO9 
IO38 
IO18 
IO20 
IO22 
IO24 
IO26 
IO7 IO5 IO3 IO1 
IO76 
IO80 
IO75 
IO82 
IO84 
IO86 
IO77 
IO95 
IO97 
IO93 IO91 IO89 IO87 IO85 IO83 IO81 IO79 
IO51 IO49 IO47 
IO42 
IO15 
IO17 
IO13 IO11 
TP FAB1 CHANGE CONNECTION 0309 
TP FAB1 PUT RES BACK 0310 
TP FAB1 DELETE RES (NO USE IE) 0118 
TP FAB1 CONNECT TO PCH 0227 
TP FAB1 RENAME 0307 
ROOM=IO_SLOT 
TP FAB1 MODIFY PCIE TOPOLOGY AND FOR ROUTING SMOOTH CHANGE CLOCK PIN DEFINE 1116 
TP FAB1 RENAME 0307 
X24 SLOT (1 OF 2) 
WIWYNN CORPORATION 



111 
FM_PRSNT_2_6_N 
P3E_CPU0_PE2_SS_RXP<7:0> 
P3E_CPU0_PE2_SS_RXN<7:0> 
6
7
7
2
2
4
4
1
1
2
2
7
123 
J8G1 
CONN 
113 
110 
112 
114 
102 
104 
106 
166 
182 
180 
178 
176 
170 
174 
164 
172 
168 
162 
154 
150 
161 
145 
143 
137 
135 
133 
131 
129 
127 
125 
121 
119 
117 
115 
132 
130 
126 
109 
134 
171 
199 
191 
189 
118 
120 
116 
107 
139 
141 
193 
197 
195 
185 
181 
177 
179 
108 
128 
124 
200 
169 
167 
165 
163 
149 
173 
151 
175 
122 
105 
103 
101 
155 
153 
156 
184 
186 
188 
190 
194 
196 
198 
158 
160 
187 
H68296-001 
148 
146 
144 
140 
138 
136 
183 
159 
157 
152 
192 
142 
147 
1
3
7
6
5
6
4
3
8
7
6
5
4
3
7
6
5
3
2
6
5
3
2
0
1
0
1
4
1
0
0
3
4
6
5
7
6
5
7
0
0
1
2
4
3
0
0
1
2
3
4
5
5
107 
133 121 
105 
105 31 
31 
107 
107 
108 244 
107 
P3E_CPU0_PE1_SS_C_TXP<7:0> 
P3E_CPU0_PE2_SS_C_TXN<7:0> 
P3E_CPU0_PE2_SS_C_TXP<7:0> 
P3E_CPU0_PE1_SS_C_TXN<7:0> 
P3E_CPU0_PE1_SS_R_RXN<7:0> 
P3E_CPU0_PE1_PCH_CON_RXP<15:8> 
P3E_CPU0_PE1_SS_R_RXP<7:0> 
DO NOT SCALE DRAWING SHEET 
B
AA
B
B
SIZE 
SCALE: 
234
1234
DEPARTMENT CODE 
1
DOCUMENT NUMBER REV 
OUT 
OUT 
OUT 
IN 
OUT 
OUT 
IN 
IN 
IN 
OUT 
109 OF 270 
Wed Feb 08 16:35:00 2017 
2/2 
SCONN200_H68296001 
IO102 
IO110 
IO119 IO117 IO115 IO113 IO111 IO109 
IO103 
IO114 
IO104 
IO106 
IO108 
IO112 
IO116 
IO118 
IO120 IO121 IO122 
IO123 IO124 
IO125 IO126 
IO127 IO128 
IO129 IO130 
IO131 IO132 
IO133 IO134 
IO135 IO136 
IO137 IO138 
IO139 IO140 
IO141 IO142 
IO143 IO144 
IO145 IO146 
IO147 IO148 
IO149 IO150 
IO151 IO152 
IO153 IO154 
IO155 IO156 
IO157 IO158 
IO159 IO160 
IO161 IO162 
IO163 IO164 
IO165 IO166 
IO167 IO168 
IO169 IO170 
IO171 IO172 
IO173 IO174 
IO175 IO176 
IO177 IO178 
IO179 IO180 
IO181 IO182 
IO183 IO184 
IO185 IO186 
IO187 IO188 
IO189 IO190 
IO191 IO192 
IO193 IO194 
IO195 IO196 
IO197 IO198 
IO199 IO200 
IO101 
IO105 
IO107 
X24 SLOT (2 OF 2) 
TP FAB1 CHANGE PCIE TOPOLOGY 1116 
WIWYNN CORPORATION ROOM=IO_SLOT 



DO NOT SCALE DRAWING SHEET 
B
AA
B
B
SIZE 
SCALE: 
234
1234
DEPARTMENT CODE 
1
DOCUMENT NUMBER REV 
110 OF 270 
Wed Feb 08 16:35:00 2017 
BOM_COST=TEST_MFG 
ROOM=LABELS TP FAB1 DELETE ANCHORS 0321 
TP FAB1 DEL LABLES 0310 
ANCHORS - LABELS 
WIWYNN CORPORATION 



2
0.1UF 
1
G21796-072 
1.0UF 
475.0 
1/16W 
0402 
G21796-074 0402 
1% 
G21796-077 
VCC=P3V3_STBY;GND=GND 
C88419-001 
FM_DEBUG_RST_BTN_R1_N 
CHIP 
CPU_XDP_PRESENT_N 
150.0 
XDP_CPU_PWR_DEBUG_N 
TP_XDP_OBSDATA_A2 
TP_XDP_OBSDATA_B2 
FM_DEBUG_RST_BTN_N 
TP_XDP_CPU_OBSDATA_D1 
TP_XDP_CPU_OBSDATA_D2 
XDP_PREQ_N 
XDP_TDO 
XDP_TRST_N 
XDP_TMS 
XDP_PRESENT_N 
XDP_SPI_PCH_MOSI_BOOT_HALT_N 
TP_XDP_CPU_OBSDATA_C1 
TP_XDP_CPU_OBSDATA_C0 
TP_XDP_CPU_OBSDATA_C2 
SPI_PCH_MOSI 
TP_XDP_CPU_OBSDATA_C3 
XDP_TDI 
TP_XDP_OBSDATA_B1 
XDP_PCH_TCK1 
SMB_HOST_STBY_LVC3_SDA 
SMB_HOST_STBY_LVC3_SCL 
XDP_CPU_PWR_DEBUG_N 
XDP_PWRGD_RST_N 
XDP_PRDY_N 
TP_XDP_OBSDATA_A0 
TP_XDP_OBSDATA_A1 
XDP_DEBUG_CONSENT_N 
XDP_CPU_GTL_TCK_R2 
TP_XDP_CPU_OBSFN_C0 
TP_XDP_OBSFN_B0 
TP_XDP_OBSFN_B1 
XDP_OBSFN_B0_MBP6_N 
XDP_OBSFN_B1_MBP7_N 
TP_XDP_CPU_OBSDATA_D0 
TP_XDP_CPU_OBSDATA_D3 
CLK_100M_PCH_XDP_DP 
CLK_100M_PCH_XDP_DN 
XDP_RST_CO_N 
XDP_ITP_PMODE 
TP_XDP_OBSDATA_B3 
TP_XDP_OBSDATA_B0 
TP_XDP_OBSDATA_A3 
XDP_RSMRST_N 
XDP_PCH_CPU_TCK0 
XDP_CPU_TCK0 
XDP_CPU_TCK_BUF 
XDP_ITP_PMODE 
XDP_PWRGD_RST_N 
XDP_RST_CO_N 
R1L28 
4.75K 
1/16W 
1% 
EMPTY 
0402 2G21796-026 
1/16W 
1% 
1 EMPTY 
R9A1 
1.00K 
5
EMPTY 
C52264-001 
4
MBT3904 
3Q9A1 
6
EMPTY 
MBT3904 
1
Q9A1 
C52264-001 
2
1% 
CHIP 1/16W 
1.00K 
1
R8E2 
G21796-026 
2
0402 
A36096-030 
0.1UF 
16V 
C1L11 
10% 
0402V 
X7R 2
1
74LVC1G07 
42
IC 
U1L4 
EMPTY 
1/16W 
1% 
33.2 
R9A2 
1
2
0402 R9A3 5% 210.0 1/16W CHIP 
G21497-005 
R1L29 
33.2 1% 
1/16W CHIP 
1 2
G21796-074 
0402 
1.00K 1% 1/16W 
G21796-026 
R9A15 
CHIP 
0402 
21
1.00K 1/16W CHIP 0402 
R1L13 
21
1% 
G21796-026 
A36096-030 
10% 16V 1
C9A4 
20.1UF X7R 0402V 
G21796-026 
0402 
CHIP 
1.00K 
1
1/16W 
R9A17 
2
1% 
0402 
G21796-009 R1L17 
2
CHIP 
1% 
1/16W 
1
R9A4 
1
0402 
2
CHIP 
0402 G21796-026 
1.00K 1% 
R2P2 
1/16W 
C1L5 
6.3V 
10% 
D97712-004 
2
1
X6S 
0402V 
2
4
6
8
10 
12 
14 
16 
18 
20 
22 
24 
CONN 
SMLF 
J9A3 
C21100-002 
1
3
5
7
9
11 
13 
15 
17 
19 
21 
23 
42 
46 
44 
26 
28 
30 
32 
34 
36 
38 
40 
48 
50 
56 
58 
60 
52 
54 
25 
27 
29 
31 
33 
35 
37 
39 
41 
43 
45 
47 
49 
51 
53 
55 
57 
59 
C9A6 
1.0UF 
10% 
6.3V 
X6S 
1
2
0402V 
D97712-004 
C1L8 
10% 1
A36096-030 
16V 0.1UF X7R 2 0402V 
2 G21796-026 
0402 
R1L23 
1
1.00K 1/16W 1% CHIP 
0402V 
C9A5 
10% 
A36096-030 
0.1UF X7R 2 116V 
G21796-026 
1% 1/16W 
1
1.00K 
2
R9A14 
0402 CHIP 
C9A2 
10% 16V 
A36096-030 
X7R 
2 1
0402V 
255 22 56 
111 118 254 22 56 
155 247 175 190 
118 254 112 
112 118 255 
118 254 112 
118 254 112 
146 255 
121 125 154 184 
118 254 112 254 112 118 
101 102 138 156 159 247 
138 159 101 102 156 247 
111 144 190 
111 118 254 22 56 
111 190 
112 118 255 
112 
112 
114 
114 
111 
111 118 
121 125 154 
190 192 118 147 
118 112 
254 21 55 112 
118 111 
111 190 
111 
111 144 190 
T POINT WHERE IT CONNECTS TO SPI 
XDP_SYSPWROK 
SPI_PCH_IO2 
RST_RSMRST_N 
XDP_SYSPWROK 
PLACE XDP SERIES R CLSOE TO 
T POINT WHERE IT CONNECTS TO SPI 
PLACE XDP SERIES R CLSOE TO 
CAD NOTE: 
CAD NOTE: 
CAD NOTE: 
CAD NOTE: 
1
2
DO NOT SCALE DRAWING SHEET 
B
AA
B
B
SIZE 
SCALE: 
234
1234
DEPARTMENT CODE 
1
DOCUMENT NUMBER REV 
P3V3 
BI 
BI 
OUT 
P3V3_STBY 
IN 
P1V05_PCH_STBY P1V05_PCH_STBY 
P1V05_PCH_STBY 
P3V3_STBY 
P3V3_STBY 
OUT 
OUT 
OUT 
IN 
PVCCIO_CPU0 
OUT 
IN 
OUT 
BI 
OUT 
OUT 
OUT 
OUT 
OUT 
IN 
OUT 
OUT 
OUT 
SCONN60_C21100002 
OUT 
OUT 
OUT 
OUT 
OUT 
OUT 
IN 
IN 
IN 
IN 
(HOOK7) (HOOK3) 
(HOOK6) 
(HOOK4) 
(HOOK5) 
(HOOK2) 
(HOOK1) 
(HOOK0) 
TTL1G07_A 
ROOM=DEBUG 
111 OF 270 
Wed Feb 08 16:35:00 2017 
TP FAB1 CHANGE TO NOPOP  FOR CONTROL BOM 0128 
TP FAB3 RECONNECT 0921 
ON TTL1G07_A 
PLACE 0.1UF CAP NEXT TO VCC PIN 
PLACE BUFFER CIRCUITRY WITHIN 1.1'' OF XDP CONN 
CPU & PCH XDP (1-2) 
WIWYNN CORPORATION 



PLACE CAP NEXT TO FET SWITCH 
PLACE CAP NEXT TO FET SWITCH 
74CBTLV1G125 
G21796-009 
U1M7 
C99406-001 
SMLF IC 
5
6
2
1
3
4
C1M37 
6.3V 
10% 
U1M4 
C88177-001 
VCC=P3V3_STBY;GND=GND; 
G21796-017 
1% 
CHIP 
R1L15 
0402 
XDP_CPU_TDO 
XDP_CPU1_TDO 
CHIP 
1% 
FM_CPU1_SKTOCC_LVT3_N 
XDP_CPU0_TDO 
XDP_CPU1_TDI 
FM_CPU1_SKTOCC_LVT3_N 
XDP_CPU0_TDO 
XDP_CPU_OBSFN_B0_MBP6_N 
XDP_CPU_MBP1_N 
XDP_CPU_MBP0_N 
XDP_CPU_OBSFN_B1_MBP7_N 
XDP_CPU_MBP1_N 
XDP_CPU1_TDO 
XDP_CPU_MBP0_N 
XDP_CPU0_TDO 
XDP_CPU_TDI 
XDP_CPU1_TDI 
XDP_CPU_TMS 
XDP_CPU_PREQ_N 
XDP_CPU_PRDY_N 
XDP_CPU_TCK0 
XDP_TDO 
XDP_TDI 
XDP_TMS 
XDP_PREQ_N 
XDP_PRDY_N 
XDP_CPU_TRST_N 
XDP_CPU_TMS 
XDP_CPU_TDO 
XDP_CPU_TDI 
XDP_CPU_OBSFN_B0_MBP6_N 
XDP_CPU_PRDY_N 
XDP_CPU_PREQ_N 
XDP_CPU_OBSFN_B1_MBP7_N 
XDP_TRST_N 
XDP_PCH_TCK1 
XDP_TRST_N 
XDP_TMS 
XDP_TDO 
XDP_TDI 
PWRGD_PVCCIN_CPU0 
XDP_OBSFN_B1_MBP7_N 
XDP_OBSFN_B0_MBP6_N 
XDP_PRDY_N 
XDP_PREQ_N 
XDP_CPU_TRST_N 
XDP_PCH_CPU_TCK0 
1
2
1/16W 
CHIP 
0402 
1.0% 
51.1 
G21796-208 
R8B1 
1
2
1/16W 
CHIP 
0402 
1% 
1.00K 
G21796-026 
R8B2 
1
2
1/16W 
CHIP 
0402 
1% 
1.00K 
G21796-026 
R3M10 
G21796-009 
1
2
1/16W 
CHIP 
0402 
1% 
150.0 
R8A14 
1
2
1/16W 
CHIP 
0402 
1% 
150.0 
R8A13 
1
2
1/16W 
CHIP 
1% 
150.0 
G21796-009 
R9A11 
1
2
1/16W 
CHIP 
0402 
1% 
100.0 
G21796-017 
R1L41 
1
2
1/16W 
0402 
100.0 
G21796-017 
R1L39 
1
2
1/16W 
CHIP 
0402 
1% 
1.00K 
G21796-026 
R6T5 
1
2
1/16W 
CHIP 
0402 
1.0% 
51.1 
G21796-208 
R7P29 
1
2
1/16W 
CHIP 
0402 
1% 
150.0 
G21796-009 
1
2
1/16W 
CHIP 
0402 
1% 
150.0 
G21796-009 
R4P24 
1
2
1/16W 
CHIP 
0402 
1% 
150.0 
G21796-009 
R4P23 
1
2
1/16W 
CHIP 
0402 
1% 
100.0 
G21796-017 
R4P12 
1
2
1/16W 
CHIP 
0402 
1% 
150.0 
G21796-009 
R6T6 
1
2
1/16W 
CHIP 
0402 
1% 
150.0 
G21796-009 
R6T7 
1
2
1/16W 
CHIP 
0402 
1% 
100.0 
G21796-017 
R1M4 
1
2
1/16W 
CHIP 
0402 
1% 
100.0 
G21796-017 
R4P15 
1
2
1/16W 
CHIP 
0402 
1% 
100.0 
G21796-017 
R1M3 
1
2
1/16W 
0402 
100.0 
G21796-017 
R7P30 
1
2
1/16W 
CHIP 
0402 
1% 
100.0 
R6P46 
2
1
X6S 
0402V 
1.0UF 
D97712-004 
2
1
X7R 
25V 
0402V 
10% 
0.01UF 
A36096-045 
C1M36 
1
2 X6S 
16V 
0402 
10% 
1.0UF 
D97712-011 
C1L19 
1
2 X6S 
16V 
0402 
10% 
1.0UF 
D97712-011 
C1L1 
2
1
X7R 
25V 
0402V 
10% 
0.01UF 
A36096-045 
C1M30 
2 4
1
IC 
SMLF 
1
2
1/16W 
CHIP 
0402 
1% 
100.0 
G21796-017 
R6T8 
1
2
1/16W 
CHIP 
0402 
1% 
100.0 
G21796-017 
R6T9 
12 
9
5
2
11 
8
6
3
13 
10 
4
1
IC 
74CBTLV3126 
D18317-001 
U1L5 
VCC=P3V3_STBY;GND=GND 
12 
9
5
2
11 
8
6
3
13 
10 
4
1
IC 
74CBTLV3126 
D18317-001 
U1L1 
VCC=P3V3_STBY;GND=GND 
112 
55 112 
55 112 118 
146 190 
21 112 
55 112 
55 112 118 
146 190 
21 112 
21 55 112 
21 55 112 
21 55 112 
21 55 112 
21 55 112 
55 112 
21 55 112 
21 112 
112 21 
112 55 
112 21 55 
112 21 55 
21 55 112 
111 254 21 55 
112 118 111 
255 
111 118 254 
112 
111 118 254 
112 
111 118 254 
112 
112 118 111 
255 
21 55 112 
21 55 112 
112 
21 112 
21 55 112 
21 55 112 
21 55 112 
21 55 112 
111 118 254 
112 
111 254 118 
111 118 254 
112 
111 118 254 
112 
118 111 112 
255 
111 118 254 
112 
201 190 
111 
111 
118 111 112 
255 
111 118 254 
112 
112 21 55 
118 111 
B
B
OE 
OE 
OE 
B
OE 
B
A
A
A
A
B
B
OE 
OE 
OE 
B
OE 
B
A
A
A
A
PLACE PD RESISTORS WITHIN 1.1'' OF CPU PACKAGE 
PLACE PULL-UP RESISTORS WITHIN 1.5'' OF PCH 
PLACE PULL-DOWN RESISTORS WITHIN 1.1'' OF PCH 
PLACE PULL-UP RESISTORS WITHIN 1.5'' OF CPU0 
PLACE PULL-UP RESISTORS WITHIN 1.5'' OF CPU1 
CAD NOTE: 
CAD NOTE: 
CAD NOTE: 
CAD NOTE: 
CAD NOTE: 
CAD NOTE: 
CAD NOTE: 
CAD NOTE: 
74CBTLVG125 VCC PIN
PLACE NEAR 
DO NOT SCALE DRAWING 
A B
OE_N 
S
B0 
B1 
VCC 
A
GND 
SHEET 
B
AA
B
B
SIZE 
SCALE: 
234
1234
DEPARTMENT CODE 
1
DOCUMENT NUMBER REV 
IN 
IN 
IN 
OUT 
OUT 
IN 
OUT 
OUT 
OUT 
IN 
OUT 
IN 
IN 
IN 
IN 
IN 
IN 
IN 
IN 
IN 
IN 
IN 
IN 
IN 
IN 
IN 
PVCCIO_CPU0 
OUT 
NC7SB3157 IN 
P3V3_STBY 
P3V3_STBY 
PVCCIO_CPU0 
IN 
IN 
P3V3_STBY 
P3V3_STBY 
PVCCIO_CPU1 PVCCIO_CPU0 
OUT 
IN 
IN 
P1V05_PCH_STBY 
PVCCIO_CPU0 PVCCIO_CPU0 
IN 
IN 
IN 
OUT 
IN 
IN 
IN 
OUT 
IN 
IN 
IN 
IN 
IN 
IN 
ROOM=DEBUG 
112 OF 270 
Wed Feb 08 16:35:00 2017 
PCH XDP TERMINATIONS 
CPU0 XDP TERMINATIONS 
CPU1 XDP TERMINATIONS 
CPU & PCH XDP (2-2) 
WIWYNN CORPORATION 



74CBTLV1G125 
74CBTLV1G125 
74CBTLV1G125 
74CBTLV1G125 
74CBTLV1G125 
JTAG_MCP_TCK 
TP_JTAG_MCP_IO8_RSVD 
JTAG_MCP_MUX_TDO 
CHIP 
JTAG_MCP_TMS_R 
0402 
P1V8_MCP_CPU0 
P1V8_MCP_CPU0 
P1V8_MCP_CPU1 
P1V8_MCP_CPU0 
P1V8_MCP_CPU0 
JTAG_MCP_CPU0_TDO 
FM_CPU1_CD_PRES_N 
JTAG_MCP_CPU1_TDO 
FM_CPU0_PKGID1 
JTAG_MCP_TCK 
JTAG_MCP_TMS 
JTAG_MCP_CPU1_TDI 
JTAG_MCP_CPU0_TDI_R 
JTAG_MCP_TMS_R1 
JTAG_MCP_CPU1_TDI_R 
JTAG_MCP_TRST_N 
PWRGD_CPU0_G_R 
JTAG_MCP_MUX_TDI 
JTAG_MCP_CPU1_TDI 
JTAG_MCP_TRST_N 
JTAG_MCP_TMS 
JTAG_MCP_MUX_TDO 
JTAG_MCP_MUX_TDI 
JTAG_MCP_TRST_N 
PWRGD_CPU0_G 
JTAG_MCP_TMS 
FM_CPU0_AND_CPU1_MCP_PRES 
JTAG_MCP_CPU0_TDO 
JTAG_MCP_MUX_TDI 
FM_CPU0_OR_CPU1_MCP_PRES 
FM_CPU0_CD_PRES 
JTAG_MCP_CPU1_TDI 
JTAG_MCP_CPU0_TDI 
JTAG_MCP_CPU0_TDI 
FM_CPU1_PKGID1 
JTAG_MCP_MUX_TDO 
JTAG_MCP_TCK_R 
FM_CPU0_OR_CPU1_MCP_PRES 
JTAG_MCP_TCK_R1 
1/16W 
0402 
5% 
R5W2 
0.0 
G21497-005 
CHIP 
1
0.0 1/16W 
2
R5W1 
0402 
5% CHIP 
G21497-005 
0402 
1% 
1.00K 
1/16W 
CHIP 
R6M8 
G21796-026 
R4R6 
0402 
CHIP 
1/16W 
G21796-026 
1% 
1.00K 
X7R 
1
2
10% 
0402V 
A36096-045 
C1L20 
0.01UF 
25V 
C1M35 
0.01UF 
A36096-045 
0402V 
X7R 2
10% 
25V 
1
X7R 
A36096-045 
1
2
25V 
10% 
0402V 
C1M34 
0.01UF 
2
4
SMLF 
C99406-001 
IC 
6
5
1
3
U2M1 
X7R 
0402V 
10% 
0.1UF 
A36096-030 
C6M6 
2
1
16V 
16V 
10% 
2
1C1M33 
0.1UF 
X7R 
A36096-030 
0402V 
2
16V 
0402V 
A36096-030 
X7R 
10% 
0.1UF 
1C4R2 
0.0 5% 
0402 
1 2
CHIP 
G21497-005 
1/16W 
R9B13 
R9B11 
1/16W 
G21497-005 
2
CHIP 
1
5% 0.0 
1
C88177-001 
VCC=P3V3_STBY;GND=GND; 
42
U4R1 
SMLF 
IC 
G21796-026 
1.00K 
1% 
1/16W 
1
CHIP 2
0402 
R1M21 R1M20 
G21796-026 
1.00K 
1% 
0402 
CHIP 
1
2
1/16W 
1.00K 
1% 
1/16W 
1
G21796-026 
0402 
CHIP 2
R9B12 R1M19 
1.00K 
1% 
1/16W 
1
G21796-026 
CHIP 2
0402 
1
2
R1M23 
0402 
G21796-026 
EMPTY 
1/16W 
1.00K 
1% 
4
IC 
SMLF 
U1M5 
C88177-001 
VCC=P3V3_STBY;GND=GND; 
1
2
2
49.9 
R1M22 
1
1% 
0402 
G21796-047 
1/16W 
1
2
IC 
C88177-001 
4
VCC=P3V3_STBY;GND=GND; 
SMLF 
U6M1 
IC 
VCC=P3V3_STBY;GND=GND; 
SMLF 
U9A5 
C88177-001 
4
1
2
0402 
R9B10 
21
1/16W 
49.9 1% 
CHIP 
G21796-047 
G21796-026 
CHIP 2
R9B9 
1
1% 
1.00K 
1/16W 
0402 
7
1
3
5
9
C12536-004 
10 
8
6
4
2
CONN 
J9B4 
0402 G21796-026 
1.00K 1% 
1
1/16W CHIP 
2
R9B14 
2 X7R 
0402V 
A36096-030 
10% 
1
16V 
0.1UF 
C1M29 
2
1
U1M6 
C88177-001 
VCC=P3V3_STBY;GND=GND; 
4
SMLF 
IC A36096-045 
X7R 
25V 
0402V 
10% 
0.01UF 
C1M28 
2
1
2D97712-004 
X6S 
6.3V 
0402V 
10% 
1.0UF 
C1M32 1
0402V 
A36096-045 
10% 
25V 
X7R 2
C1M31 
0.01UF 
1
C99406-001 
4
2
SMLF IC 
1
5
3
6
U1M2 
TP FAB1 CHANGE NET NAME TO LOW ACTIVE 0216 
NC7SB3157 FM_CPU1_CD_PRES_N FM_CPU0_CD_PRES 
TP FAB1 CHANGE CONNECTION 0330 
29 63 113 
113 
29 113 
63 
21 190 
113 29 63 
113 29 63 
113 63 
113 29 63 
113 
113 63 
113 29 63 
113 29 63 
113 
113 
29 63 113 
96 21 
113 29 63 
191 
29 113 
113 
191 113 
191 
113 63 
29 113 
113 29 
55 190 
113 
191 113 
NOPOP 
NOPOP 
NOPOP 
NOPOP 
NOPOP 
NOPOP 
NOPOP 
NOPOP 
NOPOP 
NOPOP 
CAD NOTE: 
DESIGN NOTE: 
CAD NOTE: 
BOM NOTE: 
DESIGN NOTE: 
BOM NOTE: 
DESIGN NOTE: 
CAD NOTE: 
CAD NOTE: 
CAD NOTE: 
CAD NOTE: 
CAD NOTE: 
1
2
2
1
PLACE CAP NEAR 74CBTLV1G125 
PLACE U6M1 AND R6M8 NEAR CPU1 PKG PIN 
PLACE U4R1 AND R4R6 NEAR CPU0 PKG PIN 
INCHES OF CORRESPONDING RESISTOR 
PLACE DECOUPLING CAPS WITHIN 0.5 
PLACE U9A5 AND R9B9 NEAR CPU1 PKG PIN 
TCK AND TMS SERIES RES VALUE TBD 
R1M23 MUST BE UNPOPPED IN DEBUG 
R1M23 MUST BE POPPED IN VOLUME 
PLACE U1M5 AND R1M22 NEAR CPU1 PKG PIN 
PLACE CAP NEAR 74CBTLV1G125 
R1M21 MUST BE DEPOPPED IN VOLUME 
DO NOT SCALE DRAWING 
A B
OE_N 
A B
OE_N 
A B
OE_N 
A B
OE_N 
A B
OE_N 
S
B0 
B1 
VCC 
A
GND 
S
B0 
B1 
VCC 
A
GND 
SHEET 
B
AA
B
B
SIZE 
SCALE: 
234
1234
DEPARTMENT CODE 
1
DOCUMENT NUMBER REV 
P3V3_STBY 
OUT 
P3V3_STBY 
IN 
IN 
IN NC7SB3157 
OUT 
OUT 
OUT 
IN 
IN 
IN 
IN 
IN 
IN 
IN 
IN 
OUT IN 
IN 
OUT 
IN 
P3V3_STBY 
P3V3_STBY 
IN 
IN 
OUT 
IN 
IN 
OUT 
OUT 
IN 
OUT 
IN NC7SB3157 
SCONN10 
113 OF 270 
Wed Feb 08 16:35:01 2017 ROOM=DEBUG 
0
1
0
1
B0 
B1 
JTAG 
CPU1 
CPU0 
TP FAB1 ADD R5W1 AND R5W2 0113 
TP FAB1 CHANGE R4R6 AND R6M8 TO 1K OHM RES 0113 
C1M33, R1M22, U6M1, C6M6, U9A5, R9B10 0113 
TP FAB1 NOPOP U4R1, C4R2, R1M20, U1M5 
ADDITIONAL LOGIC WILL BE REQUIRED 
ON THE ADAPTER BOARD FOR RC CPU SKU TO CD CPU SKU MCP JTAG 
MCP OR WFR PULL UPS AND PULL DOWNS 
WIWYNN CORPORATION 
MCP JTAG FOR DEBUG USE ONLY 



1/16W 
1/16W 
TP_PCH_RSVD65 
CLK_100M_MEZZ2_DP 
CLK_100M_MEZZ2_DN 
CLK_100M_MEZZ1_DP 
CLK_100M_MEZZ1_DN 
CLK_100M_PCH_SLOTX24_S5_DN 
A26 
MANTAIN 0603 PACKAGE FOR 
200 KOHM AND 10 MOHM RESISTORS. 
50V 
0402LF 
A36095-047 
C7C4 
D71700-058 
IC 
1
5% 
50V 
A36095-047 
3
* CAP VALUE MAY NEED TUNING. 
* NC RECOMMENDED COMPONENTS 
0402LF 
A36095-047 
2 COG 
0402LF 
IC 
48.000MHZ 
Y7C1 
CHIP 
0.1% 
C7C5 
1
1
5% 
COG 
2
G21497-005 
CLK_100M_PCH_SLOTX24_S0_DN 
XTAL_33K_RTC1 
CLK_100M_SPRV_DN 
CLK_100M_M2_DN 
XTAL_PCH_48M_OUT 
XTAL_PCH_48M_IN 
H_PMSYNC_CLK_24M_R 
CLK_100M_BMC_PE_R_DN 
A_PCH_XCLK_BIASREF 
CLK_100M_BMC_PE_R_DP 
XTAL_33K_RTC2 
XTAL_PCH_48M_IN 
XTAL_PCH_48M_OUT 
CLK_100M_SPRV_DP 
CLK_100M_BMC_PE_DN 
TP_CLK_100M_NSSCC0_DP 
TP_CLK_100M_PLAT1_DP 
TP_CLK_100M_PLAT1_DN 
TP_CLK_100M_NSSCC1_DN 
CLK_100M_PCH_XDP_DP 
XTAL_33K_RTC2 
XTAL_33K_RTC1 
CLK_100M_PCH_XDP_DN 
TP_CLK_100M_NSSCC1_DP 
TP_CLK_100M_NSSCC0_DN 
* NC RECOMMENDED COMPONENTS 
* CAP VALUE MAY NEED TUNING. 
AND VALUE. 
AND VALUE. 
CLK_48M_USB_BMC 
1
32.768KHZ 
Y7C2 
2
0603 
1
CHIP 
10M 
1/10W 
1.0% 
G22026-112 
R7C6 
2
1/10W 
200K 
R7C1 
0603 
1 2
G22369-010 
B40 
H27 
K27 
G26 
BV51 
A39 
H17 
H91415-002 
U7C1 
D35 
B35 
G44 
C26 
D40 
B29 
C32 
A32 
C39 
BY51 
BW50 
H38 
H35 
G33 
H42 
C28 
K38 
K35 
J33 
K42 
A28 
J40 
B33 
K31 
B31 
D23 
D33 
H31 
D31 
J26 
C20 
G40 
IC 
K17 
D38 
D29 
R7C2 
0402 5% 
1 2
R7C4 
2
0402 
1
0.0 5% R3N1 
G21796-276 
0402 
169 
1.0% 
1/16W 
CHIP 
2 EMPTY 
1/16W 
49.9 1
G21796-047 
0402 
1% 
R8B21 G21796-066 
1/16W 
R8B20 
110.0 
1% CHIP 
2
0402 
1
0402LF 
COG 
5% 
2
A36095-047 
C7C13 
50V 
15.0PF 
5% 
2 COG 
50V 
15.0PF 1
C13544-023 
C7C15 
B38 
G21497-005 
CLK_100M_BMC_PE_DP 
TP_PCH_RSVD64 
0.0 
CLK_100M_DB1200_DN 
CLK_100M_PCH_SLOTX24_S0_DP 
CLK_100M_PCH_SLOTX24_S1_DP 
CLK_100M_PCH_SLOTX24_S1_DN 
CLK_100M_DB1200_DP 
CLK_100M_AIRMAX8_PE1_DP 
CLK_100M_AIRMAX8_PE1_DN 
TP_CLK_24M_PMSYNC2 
H_PMSYNC_CLK_24M 
CLK_100M_PCH_SLOTX24_S2_DN 
CLK_100M_PCH_SLOTX24_S2_DP 
CLK_100M_PCH_SLOTX24_S3_DP 
CLK_100M_PCH_SLOTX24_S4_DN 
CLK_100M_PCH_SLOTX24_S4_DP 
CLK_100M_PCH_SLOTX24_S5_DP 
CLK_100M_MEZZ3_DN 
CLK_100M_MEZZ3_DP 
CLK_100M_MEZZ4_DN 
CLK_100M_MEZZ4_DP 
CLK_100M_PCH_SLOTX24_S3_DN 
C24 
H24 
K24 
D21 
A20 
B23 
B21 
A24 
CLK_100M_M2_DP 
TP FAB3 CHANGE CAPS TO 6.8PF 0815 
TP FAB4 DISCONNECT 20170111 
186 
186 
186 
186 
108 
108 
114 
139 
185 
114 
114 
145 
145 
114 
114 
114 
139 
111 
114 
114 
111 
144 
102 
108 
108 
108 
102 
181 
181 
21 55 
108 
108 
108 
108 
108 
108 
187 
187 
187 
187 
108 
185 
NEW_VALUE=6.8PF NEW_VALUE=6.8PF 
CONFIG=78.6R864.1FL CONFIG=78.6R864.1FL 
D97712-004 
EMPTY 
1.0UF 
6.3V 
10% 
0402 
C3W1 
GROUP=AST2500 
GROUP=AST2500 
DESIGN NOTE: 
DESIGN NOTE: 
CAD NOTE: 
CAD NOTE: 
DESIGN NOTE: 
ROOM=SB 
2
1
2
1
PLACE BIAS RESISTOR WITHIN 1 INCH OF PCH 
DO NOT SCALE DRAWING SHEET 
B
AA
B
B
SIZE 
SCALE: 
234
1234
DEPARTMENT CODE 
1
DOCUMENT NUMBER REV 
OUT 
OUT 
OUT 
OUT 
OUT 
OUT 
OUT 
OUT 
OUT 
IN 
OUT 
IN 
OUT 
IN 
OUT 
OUT 
OUT 
OUT 
OUT 
OUT 
OUT 
OUT 
OUT 
OUT 
OUT 
OUT 
OUT 
OUT 
OUT 
OUT 
OUT 
OUT 
OUT 
OUT 
OUT 
OUT 
OUT 
IN 
OUT 
OUT 
OUT 
OUT 
PLACE ON TOP LAYER ONLY 
114 OF 270 
Wed Feb 08 16:35:01 2017 
CLKOUT_ITPXDPN CLKOUT_ITPXDPP 
CLKOUT_NSSCCAP0N CLKOUT_NSSCCAP0P 
CLKOUT_NSSCCAP1N CLKOUT_NSSCCAP1P 
CLKOUT_PLAT0N 
CLKOUT_PLAT0P 
CLKOUT_PLAT1N CLKOUT_PLAT1P 
CLKOUT_SRCN<15> 
CLKOUT_SRCN<14> 
CLKOUT_SRCN<13> 
CLKOUT_SRCN<12> 
CLKOUT_SRCN<11> 
CLKOUT_SRCN<10> 
CLKOUT_SRCN<9> 
CLKOUT_SRCN<8> 
CLKOUT_SRCN<7> 
CLKOUT_SRCN<6> 
CLKOUT_SRCN<5> 
CLKOUT_SRCN<4> 
CLKOUT_SRCN<3> 
CLKOUT_SRCN<2> 
CLKOUT_SRCN<1> 
CLKOUT_SRCN<0> 
CLKOUT_SRCP<15> 
CLKOUT_SRCP<14> 
CLKOUT_SRCP<13> 
CLKOUT_SRCP<12> 
CLKOUT_SRCP<11> 
CLKOUT_SRCP<10> 
CLKOUT_SRCP<9> 
CLKOUT_SRCP<8> 
CLKOUT_SRCP<7> 
CLKOUT_SRCP<6> 
CLKOUT_SRCP<5> 
CLKOUT_SRCP<4> 
CLKOUT_SRCP<3> 
CLKOUT_SRCP<2> 
CLKOUT_SRCP<1> 
CLKOUT_SRCP<0> 
CLOCKSE_BMCCLK CLOCKSE_PMSYNCCLK1 CLOCKSE_PMSYNCCLK2 
RSVD<65> 
RSVD<64> 
RTCX1 
RTCX2 
XCLK_BIASREF 
XTAL_IN 
XTAL_OUT 
TP FAB1 ADD CAP C3W1 0121 
TP FAB3 CHANGE CAP 0826 
POP RES R7C4 AND R7C2 WHEN USE BMC AST2500 0106 
LEWISBURG 1/11 CLOCKS 
LBG_CORE_QAT_EXT_D 
WIWYNN CORPORATION 
1/14 



TP_USB2_P06_DN 
USB3_P01_RXP BK69 
TP_USB2_P12_DN 
TP_USB3_P02_RXP 
USB2_P02_DP_R 
TP_PCH_RSVD55 
TP_USB2_P10_DP 
TP_USB2_P07_DN 
TP_USB3_P04_TXP 
TP_USB3_P06_TXP 
TP_USB3_P05_TXP 
TP_USB3_P05_TXN 
TP_USB2_P12_DP 
TP_USB3_P02_TXP 
TP_USB3_P03_TXN 
TP_USB3_P04_TXN 
TP_USB3_P03_TXP 
TP_USB3_P02_TXN 
TP_USB2_P10_DN 
TP_USB2_P13_DN 
USB3_P01_TXP 
USB3_P01_TXN 
TP_USB3_P06_RXN 
TP_USB3_P04_RXN 
TP_USB2_P13_DP 
TP_USB2_P14_DN 
TP_USB2_P14_DP 
TP_USB3_P06_RXP 
TP_USB3_P05_RXP 
TP_USB3_P04_RXP 
TP_USB3_P03_RXP 
TP_USB3_P03_RXN 
TP_USB3_P02_RXN 
TP_USB2_P11_DN 
USB2_PCH_BMC_P5_DP_R 
USB_PCH_BMC_P4_DN_R 
USB_PCH_BMC_P4_DP_R 
TP_USB2_P11_DP 
TP_USB2_P9_DP 
TP_USB2_P8_DN 
TP_USB2_P07_DP 
A_USB2_VBUS 
USB3_P01_RXN 
TP_USB3_P05_RXN 
TP_USB3_P06_TXN 
A_USB2_COMP 
TP_USB2_P9_DN 
TP_USB2_P8_DP 
USB2_PCH_BMC_P5_DP 
USB2_PCH_BMC_P5_DN_R USB2_PCH_BMC_P5_DN 
TP_USB2_P06_DP 
USB_PCH_BMC_P4_DP 
TP_USB2_P03_DP 
TP_USB2_P03_DN 
USB_PCH_BMC_P4_DN 
USB2_P02_DP 
USB2_P02_DN_R 
USB2_P01_DP 
USB2_P02_DN 
USB2_P01_DN 
113 
1% 
1/16W 
R8B9 
0402 
G21796-341 
CHIP 2
1
BL56 
BV62 
BW57 
CA54 
BV64 
BH58 
BN70 
BL59 
BD70 
BD72 
BJ59 
BK58 
BE69 
BE71 
BG56 BF70 
BF72 
BH71 
BJ56 BJ70 
BJ72 
BK54 
BL52 BK71 
BW63 
BV58 
BU67 
BY55 
BY64 
CA63 
BN68 
IC 
U7C1 
BY53 
BY58 
BV60 
CA57 
BW61 
BH69 
BW65 
BW54 
BW67 
BV66 
BM61 
BM54 
BN56 
BV53 
BW68 
BR67 
BU65 
BV55 
CA59 
BY62 
BW59 
BY60 
CA61 
H91415-002 
0.0 
CHIP 1/16W 
0402 R1W18 
G21497-005 5% 
1/16W 
0402 R1W19 
G21497-005 5% CHIP 
0.0 
0402 CHIP 0.0 G21497-005 1/16W R1W16 5% 
G21497-005 CHIP 
0402 0.0 
5% 
1/16W R1W17 
0402 CHIP G21497-005 0.0 5% R1W15 1/16W 0402 
1/16W CHIP 
0.0 
G21497-005 
R1W14 
5% 
0402 
G21796-016 
CHIP 
10.0K 
1% 
1/16W 
R8B32 
2
1
253 253 
253 253 
146
146
146
146
245
176
245
176
CAD NOTE: 
ROOM=SB 
21
1 2
21
1 2
21
1 2
DO NOT SCALE DRAWING SHEET 
B
AA
B
B
SIZE 
SCALE: 
234
1234
DEPARTMENT CODE 
1
DOCUMENT NUMBER REV 
IN 
IN OUT 
OUT 
BI 
BI 
BI 
BI 
BI 
BI 
BI 
BI 
PLACE USB2_COMP RES ON TOP 
115 OF 270 
Wed Feb 08 16:35:01 2017 
USB3_6_TXP USB3_6_TXN USB3_6_RXP 
USB3_6_RXN USB3_5_TXP USB3_5_TXN USB3_5_RXP 
USB3_5_RXN 
USB3_4_TXP USB3_4_TXN USB3_4_RXP 
USB3_4_RXN USB3_3_TXP USB3_3_TXN USB3_3_RXP 
USB3_3_RXN USB3_2_TXP USB3_2_TXN USB3_2_RXP 
USB3_2_RXN USB3_1_TXP USB3_1_TXN USB3_1_RXP 
USB3_1_RXN 
USB2_VBUS 
USB2_COMP 
USB2P_9 
USB2P_8 
USB2P_7 
USB2P_6 
USB2P_5 
USB2P_4 
USB2P_3 
USB2P_2 
USB2P_14 
USB2P_13 
USB2P_12 
USB2P_11 
USB2P_10 
USB2P_1 
USB2N_9 
USB2N_8 
USB2N_7 
USB2N_6 
USB2N_5 
USB2N_4 
USB2N_3 
USB2N_2 
USB2N_14 
USB2N_13 
USB2N_12 
USB2N_11 
USB2N_10 
USB2N_1 
RSVD<55> 
TP FAB1 ADD ROW OF USB TYPE C CONNECTOR 0223 
TP FAB1 ADD ROW OF PCIE X8 CONNECTOR 0104 
PRONT PANEL 
PCH TO DEVICE 
USB HUB CHIP ON RISER CARD PORT 2 
OCB_0 
N/A 
PORT 5 BMC_AST2520 ON BOARD 
BMC_AST2520 ON BOARD PCH TO DEVICE 
N/A 
N/A 
N/A 
PORT 1 
PORT 4 
PORT 1 
FRONT PANEL R/A CONNECTOR 
USB TYPE C CONN. (FOR DEBUG) 
PCH TO DEVICE 
PRONT PANEL 
TP FAB1 RENAME BACK AS CRB 0113 
TP FAB1 RENAME BACK AS CRB 0113 
WITHIN 0.5 INCH OF PCH 
LEWISBURG 2/11 USB 
USB 3.0 PORT OVER CURRENT 
OVER CURRENT TOPOLOGY 
USB PORT ASSIGNMENT 
USB 2.0 PORT 
LOCATION 
LOCATION 
TOPOLOGY 
LBG_CORE_QAT_EXT_D 
WIWYNN CORPORATION 
2/14 



SATA6G_PCH_PCIE_UP_SATA_TXN<7:0> 
AF72 
P2E_SSB_BMC_TX_C_DP 
P2E_SSB_BMC_TX_C_DN 
SATA6G_S0_TX_DP 
SATA6G_S1_TX_DN 
C2M4 
P3E_PCH_M2_TX_DP<2> 
P3E_PCH_M2_TX_DN<2> 
P3E_PCH_M2_TX_DP<1> 
P3E_PCH_M2_TX_DN<1> 
AK65 
AH65 
AF65 
AL63 
AP63 
AJ63 
AV66 
BA65 
BA61 
AY59 
BD61 
AT66 
AG63 
AH61 
AR61 
AY66 
AE69 
2
1
0
V70 
V72 
T69 
AF70 
AH71 
AC71 
AC69 
P2E_SSB_BMC_TX_DP 
P2E_SSB_BMC_TX_DN 
10% 
10% 
0402V 
0402 
G21796-017 
R3M11 
100.0 
CHIP 
1/16W 
1% 
1
2
5
4
7
6
6
7
3
1
5
4
3
2
0
0
1
2
3
1
2
3
4
5
6
5
4
7
6
7
G21796-017 
100.0 
1% 
CHIP 2
1
R3M12 
1/16W 
0402 
P3E_PCH_M2_RX_DP<2> 
P3E_PCH_M2_RX_DN<3> 
AJ70 
L72 
L70 
P71 
N70 
N72 
M69 
M71 
T71 
R70 
R72 
P69 
AD72 
W69 
W71 
AH69 
AJ72 
BG66 
BL66 
BK65 
BR65 
BM65 
BN63 
BR61 
BK61 
BH61 
H69 
AA69 
AA71 
G67 
D66 
E67 
IC 
AA61 
AD61 
AN61 
AP59 
AN65 
AL66 
AW65 
AV63 
AT63 
BD65 
AN70 
AN72 
BB63 
AV72 
AV70 
BA71 
BA69 
AY72 
AY70 
AW71 
AW69 
BB56 
BD58 
AH58 
AF58 
BJ63 
AM69 
AM71 
BJ66 
BH65 
U7C1 
AU65 
1
1% 
R7B8 
10.0K 
1/16W 
EMPTY 2
0402 
G21796-016 
2
0402 
1% 
R7B7 
1 10.0K 
G21796-016 
EMPTY 
1/16W 
0.1UF 
21
A36096-030 
X7R 
16V 
2
A36096-030 
SATA6G_PCH_PCIE_UP_SATA_TXP<7:0> SATA6G_PCH_PCIE_UP_SATA_RXP<7:0> 
P3E_PCH_M2_RX_DN<2> 
P3E_PCH_TX_0_DP 
P3E_PCH_TX_0_DN 
P3E_PCH_RX_0_DP 
TP_PCH_RSVD49 
A_PCIE_RCOMP_N 
SATA6G_S1_RX_DP 
SATA6G_S1_RX_DN 
SATA6G_S0_RX_DP 
SATA6G_S0_RX_DN 
PE_PCH_SPRV_RX_C_DP 
PE_PCH_SPRV_RX_C_DN 
P2E_SSB_BMC_RX_C_DN 
A_EXTCLKP A_PCIE_RCOMP_P 
A_PCIEUP_RCOMP_N 
A_PCIEUP_RCOMP_P 
TP_PCH_RSVD47 
P3E_PCH_RX_0_DN 
P3E_PCH_M2_RX_DN<1> 
P3E_PCH_M2_RX_DP<1> 
P2E_SSB_BMC_RX_C_DP 
TP_PCH_RSVD50 
TP_PCH_RSVD52 
TP_PCH_RSVD51 
A_EXTCLKN 
P3E_PCH_M2_TX_DN<3> 
P3E_PCH_M2_TX_DP<3> 
16V 
1
C2M3 
PE_PCH_SPRV_TX_DN 
PE_PCH_SPRV_TX_DP 
SATA6G_S0_TX_DN 
X7R 0402V 0.1UF 
SATA6G_PCH_PCIE_UP_SATA_RXN<7:0> 
P2E_SSB_BMC_RX_C_DN 
R3M8 
P2E_SSB_BMC_RX_C_DP 
100.0K 
R3M9 
CHIP 
1/16W 
1% 
AP71 
AP69 
TP_PCH_RSVD48 
H91415-002 
0402 
1% 
G21796-010 
1/16W 
100.0K 
CHIP 
G21796-010 
0402 
AE71 
0
SATA6G_S1_TX_DP 
AD70 
P3E_PCH_M2_RX_DP<3> TP FAB1 POP WHEN AST2500 0106 
TP FAB3 NOPOP RES 0913 
173 
145 
145 
185 
172 
185 
185 
185 
185 
185 
185 
173 173 
185 
185 
185 
185 
172 
172 
185 
185 
139 
139 
145 116 
185 
185 
185 
145 116 
185 
185 
139 
139 
185 
173 
145 116 
145 116 
172 
185 
GROUP=AST2500 
GROUP=AST2500 
NOPOP NOPOP 
CAD NOTE: 
CAD NOTE: 
CAD NOTE: 
DESIGN NOTE: 
PLACE BMC PCIE TX 
CAPS CLOSE TO PCH 
DO NOT SCALE DRAWING SHEET 
B
AA
B
B
SIZE 
SCALE: 
234
1234
DEPARTMENT CODE 
1
DOCUMENT NUMBER REV 
IN 
OUT 
OUT 
OUT 
OUT 
OUT 
OUT 
OUT 
IN 
IN 
IN 
IN OUT 
OUT 
IN 
IN 
IN 
IN 
IN 
IN 
IN 
IN 
OUT 
OUT 
OUT 
OUT 
OUT 
OUT 
OUT 
OUT 
OUT 
IN 
IN 
IN 
IN 
IN 
IN 
IN 
116 OF 270 
Wed Feb 08 16:35:02 2017 
USB3_9_PCIE2_TXP USB3_9_PCIE2_TXN USB3_9_PCIE2_RXP 
USB3_9_PCIE2_RXN USB3_8_PCIE1_TXP USB3_8_PCIE1_TXN USB3_8_PCIE1_RXP 
USB3_8_PCIE1_RXN USB3_7_PCIE0_TXP USB3_7_PCIE0_TXN USB3_7_PCIE0_RXP 
USB3_7_PCIE0_RXN 
USB3_10_PCIE3_GBE_TXP USB3_10_PCIE3_GBE_TXN USB3_10_PCIE3_GBE_RXP 
USB3_10_PCIE3_GBE_RXN 
RSVD<47> RSVD<48> RSVD<49> RSVD<50> 
RSVD<51> RSVD<52> 
PCIE_RCOMPP 
PCIE_RCOMPN 
PCIEUP_RCOMPP 
PCIEUP_RCOMPN 
PCIE9_SSATA3_TXP PCIE9_SSATA3_TXN PCIE9_SSATA3_RXP 
PCIE9_SSATA3_RXN PCIE8_SSATA2_GBE_TXP PCIE8_SSATA2_GBE_TXN PCIE8_SSATA2_GBE_RXP 
PCIE8_SSATA2_GBE_RXN PCIE7_SSATA1_TXP PCIE7_SSATA1_TXN PCIE7_SSATA1_RXP 
PCIE7_SSATA1_RXN PCIE6_SSATA0_TXP PCIE6_SSATA0_TXN PCIE6_SSATA0_RXP 
PCIE6_SSATA0_RXN PCIE5_GBE_TXP PCIE5_GBE_TXN PCIE5_GBE_RXP 
PCIE5_GBE_RXN PCIE4_GBE_TXP 
PCIE4_GBE_TXN 
PCIE4_GBE_RXP 
PCIE4_GBE_RXN 
PCIE19_UP7_SATA7_TXP PCIE19_UP7_SATA7_TXN PCIE19_UP7_SATA7_RXP 
PCIE19_UP7_SATA7_RXN PCIE18_UP6_SATA6_TXP PCIE18_UP6_SATA6_TXN PCIE18_UP6_SATA6_RXP 
PCIE18_UP6_SATA6_RXN PCIE17_UP5_SATA5_TXP PCIE17_UP5_SATA5_TXN PCIE17_UP5_SATA5_RXP 
PCIE17_UP5_SATA5_RXN 
PCIE16_UP4_SATA4_TXP PCIE16_UP4_SATA4_TXN PCIE16_UP4_SATA4_RXP 
PCIE16_UP4_SATA4_RXN PCIE15_UP3_SATA3_TXP PCIE15_UP3_SATA3_TXN PCIE15_UP3_SATA3_RXP 
PCIE15_UP3_SATA3_RXN PCIE14_UP2_SATA2_TXP PCIE14_UP2_SATA2_TXN PCIE14_UP2_SATA2_RXP 
PCIE14_UP2_SATA2_RXN PCIE13_UP1_SATA1_TXP PCIE13_UP1_SATA1_TXN PCIE13_UP1_SATA1_RXP 
PCIE13_UP1_SATA1_RXN PCIE12_UP0_SATA0_TXP PCIE12_UP0_SATA0_TXN PCIE12_UP0_SATA0_RXP 
PCIE12_UP0_SATA0_RXN PCIE11_SSATA5_GBE_TXP PCIE11_SSATA5_GBE_TXN PCIE11_SSATA5_GBE_RXP 
PCIE11_SSATA5_GBE_RXN 
PCIE10_SSATA4_TXP PCIE10_SSATA4_TXN PCIE10_SSATA4_RXP 
PCIE10_SSATA4_RXN 
EXTCLKP EXTCLKN 
TP FAB3 DELETE NET 0920 TP FAB3 DELETE NET 0920 
MINI-SAS X8 VERTICAL 
MINI-SAS X8 VERTICAL 
M.2 PCIE 
M.2 SATA 
SATA CONN 
BMC 
SPRV 
ROOM=SB 
M.2 SATA 
SATA CONN 
BMC 
SPRV 
M.2 PCIE 
PLACE RCOMP RESISTORS WITHIN 2 INCHES OF PCH 
IF AST2400 IS USED, UNSTUFF THESE RESISTORS 
PLACE PULL DOWNS NEAR PCH 
PCIE ON AST1250 NOT USED. PULL DOWNS 
USED TO AVOID NOISE INTO LBG PINS 
LEWISBURG 3/11 IO 
LBG_CORE_QAT_EXT_D 
WIWYNN CORPORATION 
3/14 



P3E_CPU0_PE1_PCH_TXN<7:0> 
K58 
P3E_CPU0_PE1_PCH_R_RXN<15:8> 
P3E_CPU0_PE1_PCH_R_RXP<15:8> 
P3E_CPU0_PE1_PCH_RXP<7:0> 
P3E_CPU0_PE1_PCH_RXN<7:0> 
DMI_CPU0_PCH_TX_C_DN<3:0> 
P3E_CPU0_PE1_PCH_C_TXN<15:8> 
P3E_CPU0_PE1_PCH_C_TXP<15:8> 
P3E_CPU0_PE1_PCH_TXP<7:0> 
DMI_CPU0_PCH_RX_DP<3:0> 
DMI_CPU0_PCH_RX_DN<3:0> 
DMI_CPU0_PCH_TX_C_DP<3:0> 
10 
9
8
7
6
M66 
J66 
B58 
D58 
M63 
K65 
A57 
C57 
R61 
P59 
B55 
D55 
J63 
H61 
A54 
C54 
K61 
N61 
B53 
D53 
M59 
N58 
A52 
C52 
J56 
B51 
D51 
G56 
H54 
A50 
C50 
M56 
P56 
B49 
D49 
AA65 
Y66 
B64 
D64 
V63 
W65 
A63 
C63 
U61 
T63 
B62 
D62 
U65 
R65 
A61 
C61 
V59 
T59 
B60 
D60 
P66 
N65 
A59 
C59 
G52 
J52 
A48 
C48 
K46 
H50 
M52 
N54 
H46 
J48 
K50 
P52 
B42 
A43 
B44 
A45 
D42 
C43 
D44 
C45 
IC 
H91415-002 
U7C1 
7
6
5
4
5
3
2
0
1
4
3
2
1
0
7
6
4
5
3
2
1
0
7
6
5
4
2
3
1
0
0
1
2
0
1
2
3
3
0
1
2
3
0
1
2
3
11 
11 
15 
14 
13 
12 
11 
10 
9
8
15 
14 
13 
12 
11 
10 
9
8
15 
14 
13 
12 
10 
9
8
15 
14 
13 
12 
107 
105 
105 
107 
107 
129 
105 
105 
107 
129 
129 
129 
DESIGN NOTE: 
DESIGN NOTE: DESIGN NOTE: 
DO NOT SCALE DRAWING SHEET 
B
AA
B
B
SIZE 
SCALE: 
234
1234
DEPARTMENT CODE 
1
DOCUMENT NUMBER REV 
OUT 
OUT IN 
IN 
OUT 
OUT 
IN 
IN 
OUT 
OUT 
IN 
IN 
117 OF 270 
Wed Feb 08 16:35:02 2017 
PCIEUP_9_TXP PCIEUP_9_TXN PCIEUP_9_RXP 
PCIEUP_9_RXN PCIEUP_8_TXP 
PCIEUP_8_TXN 
PCIEUP_8_RXP 
PCIEUP_8_RXN PCIEUP_7_TXP PCIEUP_7_TXN PCIEUP_7_RXP 
PCIEUP_7_RXN PCIEUP_6_TXP PCIEUP_6_TXN PCIEUP_6_RXP 
PCIEUP_6_RXN PCIEUP_5_TXP PCIEUP_5_TXN PCIEUP_5_RXP 
PCIEUP_5_RXN PCIEUP_4_TXP PCIEUP_4_TXN PCIEUP_4_RXP 
PCIEUP_4_RXN PCIEUP_3_TXP PCIEUP_3_TXN PCIEUP_3_RXP 
PCIEUP_3_RXN PCIEUP_2_TXP PCIEUP_2_TXN PCIEUP_2_RXP 
PCIEUP_2_RXN 
PCIEUP_1_TXP PCIEUP_1_TXN PCIEUP_1_RXP 
PCIEUP_1_RXN 
PCIEUP_15_TXP PCIEUP_15_TXN PCIEUP_15_RXP 
PCIEUP_15_RXN 
PCIEUP_14_TXP PCIEUP_14_TXN PCIEUP_14_RXP 
PCIEUP_14_RXN PCIEUP_13_TXP PCIEUP_13_TXN PCIEUP_13_RXP 
PCIEUP_13_RXN PCIEUP_12_TXP PCIEUP_12_TXN PCIEUP_12_RXP 
PCIEUP_12_RXN PCIEUP_11_TXP PCIEUP_11_TXN PCIEUP_11_RXP 
PCIEUP_11_RXN PCIEUP_10_TXP PCIEUP_10_TXN PCIEUP_10_RXP 
PCIEUP_10_RXN 
PCIEUP_0_TXP PCIEUP_0_TXN PCIEUP_0_RXP 
PCIEUP_0_RXN 
DMI_TXP<0> 
DMI_TXP<1> 
DMI_TXP<2> 
DMI_TXP<3> 
DMI_TXN<0> 
DMI_TXN<1> 
DMI_TXN<2> 
DMI_TXN<3> 
DMI_RXP<0> 
DMI_RXP<1> 
DMI_RXP<2> 
DMI_RXP<3> 
DMI_RXN<0> 
DMI_RXN<1> 
DMI_RXN<2> 
DMI_RXN<3> 
ROOM=SB 
CPU0 
CPU0 
CPU0 DMI 
CPU0 
CPU0 
CPU0 DMI 
CPU0 HAS THE STEERING OPTION TO GO 
TO PCH PCIEUP OR X24 SUPSERSLOT TO PCH PCIEUP OR X24 SUPSERSLOT 
CPU0 HAS THE STEERING OPTION TO GO 
LANES 15:12, 10:8 ARE POLARITY 
INVERTED FOR EASE OF ROUTING 
LEWISBURG 4/11 DMI, PCIE 
LBG_CORE_QAT_EXT_D 
WIWYNN CORPORATION 
4/14 



74CBTLV1G125 
R7W19 
4.75K 1
2
1% 
4.75K 
1/16W 
0402 
CHIP 
G21796-072 
R7W21 
G21796-072 
CHIP 
0402 
1/16W 
1% 
2
1
FM_BMC_CPLD_MP_RST_N 
FM_CPU0_RC_ERROR_R_N 
TP_PCH_GDP8_SUSCLK 
FM_BATTERY_SENSE_EN_R_N 
FM_PCH_LVC1_THERMTRIP_N 
H_PM_SYNC1_GTL_R 
TP_PM_SYNC_GTL 
U13 
V7 
BM31 
TP_PCH_RSVD54 
V15 
TP_PCH_RSVD53 
PECI_PCH 
TP_10GBE_KR1_MON_DN 
TP_PCH_RSVD42 
TP_PCH_RSVD41 
XTAL_KR_25M_OUT 
FM_SLPS4_N 
FM_SLPS3_R_N 
FM_PCH_PWRBTN_N 
RST_BMC_SRST_R_N 
FM_CPU1_SKTOCC_LVT3_N 
XDP_PCH_PWR_DEBUG_N 
TP_PCH_RSVD45 
G15 
G11 
A13 
U7C1 
0402 
G21497-005 
FM_CPU0_SKTOCC_LVT3_N 
FM_GBE_LOM_DISABLE_N 
D14 
P22 
1/16W 
1.0K 
R2M6 
G85996-004 
G21497-005 
2
AA54 
CHIP 
1/16W 
TP_CPU_PCH_TRIGGER_OUT 
AN54 
BR31 
H19611-001 
Y8C1 
25.000MHZ 
XTAL_KR_25M_OUT 3
TP_10GBE_KR0_MON_DN 
KR_P0_OCP_RX_C_DN 
BJ29 
CHIP 
0402 R7W9 
1/16W 
U54 
AF54 
AH54 
AP56 
M7 
XDP_TDI 
XDP_TDO 
XDP_PRDY_N 
XDP_PREQ_N 
XDP_PCH_CPU_TCK0 
XDP_TMS 
W54 
AK54 
KR_P1_OCP_RX_C_DP 
KR_P1_OCP_RX_C_DN 
KR_P0_OCP_RX_C_DP 
TP_10GBE_KR0_MON_DP 
TP_PCH_RSVD38 
TP_PCH_RSVD37 
XTAL_KR_25M_IN 
BN26 
IC 
1/16W G21497-005 CHIP 
0402 5% 
R8C24 
1
0.0 
2
1/16W 
0.0 5% 
2
R8C23 
1
0402 
G21497-005 EMPTY 
10.0K 
R2N6 
1
1% 
2
1/16W 
CHIP 
0402 
1 0.1UF 
C7D1 
2 X7R 
16V 
0402V 
10% 
A36096-030 
SMLF 
C88177-001 
1
2
IC U7D1 
4
G21796-016 
1/16W 
2
1
CHIP 
0402 
1% 
10.0K 
R7C23 
G21497-005 0402 
1/16W 
EMPTY 
R1W30 0.0 5% 
G21796-066 
1/16W 
10.0 
CHIP 
0402 
2
R3N9 
1
1% 
0402 
G21796-047 
EMPTY 
1/16W 
49.9 1
2
1% 
R3N14 
G21796-072 
0402 
CHIP 
1/16W 
2
1% 
1
R3N13 
4.75K 
BG37 
BJ37 
BF35 
BH31 
AD54 
AR54 
BM24 
BR24 
BM27 
BN33 
BL33 
K13 
K9 
BV19 
AT56 
BY16 
BN29 
BV16 
BL26 
Y56 
V56 
H13 
BJ40 
BG40 
BD42 
P26 
R24 
P15 
U17 
U9 
BR35 
BY19 
R9 
BL29 
H91415-002 
BB29 
M15 
P7 
R17 
BG29 
BR27 
BM35 
BF31 
BH35 
1
R2N4 
1.0K 
0.1% 
1/16W 
G85996-004 
0402 
2
1
CHIP 
1
0402 0.1% 
2
CHIP 
KR_P1_OCP_TX_DN 
XDP_TRST_N 
KR_P1_OCP_TX_DP 
KR_P0_OCP_TX_DN 
KR_P0_OCP_TX_DP 
A_KR1_RBIAS 
XDP_CPU_PWR_DEBUG_N 
FM_10GBE_LOM_DISABLE_N 
TP_10GBE_KR1_MON_DP 
A_KR0_RBIAS 
RST_RSMRST_N 
TP_PLTRST_CPU_N 
RST_BMC_SYSRST_BTN_OUT_B_N 
H_PM_SYNC_GTL 
PWRGD_PVCCIO_CPU0 
TP_SLP_LAN_N 
FM_SLP_SUS_N 
PWRGD_SYS_PWROK 
PWRGD_PCH_PWROK 
IRQ_LVC3_WAKE_N 
PWRGD_DSW_PWROK 
PWRGD_CPUPWRGD_GTL 
XTAL_KR_25M_IN 
XDP_PCH_TCK1 
IC 
C13 
A15 
H9 
1
5% 
1
1
CHIP 
FM_SLPS3_N 
2RST_BMC_SRST_N 
B14 
B16 
C15 
M11 
AL56 
R13 
TP_CPU_PCH_TRIGGER_IN 
0.0 R7W6 
FM_BATTERY_SENSE_EN_N 
FM_CPU0_RC_ERROR_N 
1/16W 
0.0 
2
FM_1GB_LOM_DISABLE_N 
G21796-016 
FM_GBE_LOM_DISABLE_N 
VCC=P3V3_STBY;GND=GND; 
XDP_PCH_PWR_DEBUG_N 
XDP_ITP_PMODE 
2
0402 
G21497-005 
5% 
R7W1 0.0 5% 
G21497-005 
1/16W 
TP_PCH_RSVD32 
TP_PCH_RSVD33 
TP_PCH_RSVD34 
TP_PCH_RSVD35 
TP_PCH_RSVD36 
0402 
5% 0.0 
1
R7D23 
CHIP 
TP FAB3 CHANGE CAPS TO 15PF 0815 
TP FAB3 CHANGE CAPS TO 33PF 20161221 
TP FAB4 NOPOP R7D23 20170207 
TP FAB1 ADD RES R7W1 0114 
TP FAB3-DVT ADD RES R7W6 20161128 
TP FAB4 ADD R7W21 20170207 
TP FAB4 ADD R7W19 20170116 
TP FAB3-DVT CHANGE CONNECTION 20161117 
TP FAB3-DVT ADD RES R7W9 20161201 
147 157 190 
134 
166 
118 
148 191 
156 191 
55 112 146 190 
118 
21 144 
190 
118 
188 
111 254 112 
112 111 255 
112 111 255 
111 254 112 
111 112 
111 254 112 
188 
188 
118 
175 
111 254 112 
188 
188 
188 
111 254 22 56 
120 
190 192 111 147 
156 191 
21 55 
211 190 
191 
133 191 144 247 
133 191 144 
142 
196 200 157 191 247 
92 
118 
111 254 112 
148 190 247 
135 157 145 
145 169 
22 133 120 145 
139 118 
118 
111 
NOPOP 
5% 
A36095-031 
33.0PF 
C8C2 
33.0PF 
50V 
0402LF 
A36095-031 
COG 
C8C1 
50V 
5% 
0402LF 
COG 
RST_SYSTEM_BTN_BUF_N 
NOPOP 
NOPOP 
CAD NOTE: 
CAD NOTE: 
CAD NOTE: 
CAD NOTE: CAD NOTE: 
TP FAB1 PUT KR1 BACK 0322 
TP FAB1 DELETE CONNECTION TO MEZZC 0106 
TP FAB1 PUT KR1 BACK 0322 
TP FAB1 DELETE CONNECTION TO MEZZ C 1230 
2
1
2
1
21
DO NOT SCALE DRAWING 
A B
OE_N 
SHEET 
B
AA
B
B
SIZE 
SCALE: 
234
1234
DEPARTMENT CODE 
1
DOCUMENT NUMBER REV 
OUT IN 
OUT 
OUT 
P3V3_STBY 
OUT OUT 
OUT 
OUT 
IN 
IN 
IN 
OUT 
IN 
IN 
IN 
OUT 
IN 
BI 
OUT 
BI 
BI 
BI 
IN 
IN 
OUT 
OUT 
P3V3_STBY 
IN 
IN OUT 
OUT 
IN 
OUT 
IN 
IN 
OUT 
OUT 
IN 
IN 
P3V3_STBY 
BI 
OUT IN 
P3V3_STBY 
OUT 
IN 
OUT 
P3V3_STBY 
OUT 
IN 
OUT 
OUT 
OUT 
P1V05_PCH_STBY_KR_PLL 
P1V05_PCH_STBY_KR_PLL 
IN 
PLACE ON TOP LAYER ONLY 
WITHIN 3 INCHES OF PCH 
MUST PLACE LAN_RBIAS RES 
WITHIN 3 INCHES OF PCH 
MUST PLACE LAN_BIAS RES 
PLACE RST_BMC_SRST# RES CLOSE TO PCH 
118 OF 270 
Wed Feb 08 16:35:02 2017 
WAKE_N 
TRIGGER_OUT TRIGGER_IN 
THRMTRIP_N 
SYS_RESET_N 
SYS_PWROK 
SLP_SUS_N SLP_GBE_N 
RSVD<32> 
RSVD<33> 
RSVD<34> 
RSVD<35> 
RSVD<36> 
RSVD<37> RSVD<38> 
RSVD<39> 
RSVD<40> 
RSVD<41> RSVD<42> 
RSVD<43> 
RSVD<44> 
RSVD<45> 
RSVD<53> 
RSVD<54> 
RSMRST_N 
PROC_PWRGD 
PREQ_N 
PRDY_N 
PM_SYNC2 PM_SYNC 
PLTRST_CPU_N 
PECI 
PCH_PWROK 
LAN_XTAL_OUT LAN_XTAL_IN 
LAN_TX_P3P LAN_TX_P3N LAN_TX_P2P LAN_TX_P2N 
LAN_TX_P1P LAN_TX_P1N LAN_TX_P0P LAN_TX_P0N 
LAN_RX_P3P 
LAN_RX_P3N 
LAN_RX_P2P 
LAN_RX_P2N 
LAN_RX_P1P 
LAN_RX_P1N 
LAN_RX_P0P 
LAN_RX_P0N 
LAN_RBIAS_1 LAN_RBIAS_0 
JTAG_TMS JTAG_TDO JTAG_TDI JTAG_TCK 
JTAGX 
ITP_PMODE 
GPD9 
GPD8_SUSCLK 
GPD7 
GPD6_SLP_A_N 
GPD5_SLP_S4_N 
GPD4_SLP_S3_N 
GPD3_PWRBTN_N 
GPD2_GBE_WAKE_N 
GPD1_ACPRESENT 
GPD11_GBEPHY 
GPD10_SLP_S5_N 
GPD0 
DSW_PWROK 
CPU_TRST_N 
TP FAB1 ADD RES 0226 
BOM_COST=SB ROOM-SB 
PLACE CAP CLOSE TO VCC PIN 
LEWISBURG 5/11 LAN 
LBG_CORE_QAT_EXT_D 
WIWYNN CORPORATION 
5/14 



1/16W 
BY42 
BR38 
CA45 
BW41 
BM38 
BM42 
BW45 
IRQ_HSC_FAULT_N 
IRQ_BMC_PCH_NMI_STBY_R_N 
R7W22 
4.75K 1
1/16W 
CHIP 
G21796-072 
BR42 
BK46 
BJ44 
IRQ_MEZZ_LAN_ALERT_N 
FM_PCH_PLD_DATA_R 
FM_BMC_ENABLE_N 
G21796-074 
0402 
2
1% 
CHIP 1% 
33.2 
FM_CPLD_BMC_PWRDN_N 
FM_BMC_CPLD_GPO 
IRQ_FORCE_NM_THROTTLE_N 
H_CPU0_FAST_WAKE_LVT3_N 
BN40 
BL44 
FM_PCH_PLD_DATA 
BR46 
BV44 
FM_BMC_HEARTBEAT_N 
FM_ADR_MODE_SEL_R 
FM_XRC_READY_N 
FM_XRC_PRESENT_N 
SGPIO_PCH_SSATA_DOUT0 
FM_BMC_FAULT_LED_N 
FM_BMC_ENABLE_N 
FM_PWR_LED_N 
BY44 
BV47 
1/16W 
Q9A2 
FM_PWR_LED_A 
FM_PWR_LED_N 
FM_PWR_LED_K 
FM_PWR_LED 
0402 
2
1
1/16W 
CHIP 
4.75K 
1% 
G21796-072 
R9A18 
2 CHIP 
0402 
1% 
G21796-072 
1/16W 
1
R9A21 
4.75K 
R9A20 
G21796-271 1.0% 
CHIP 
2
221 
1/16W 
1
0402 
2
1
6
Q9A2 
NTJD4001N 
FET 
E40049-001 
GREEN 
IC 
DS9A5 
C97278-010 
12
5
4
3
E40049-001 
NTJD4001N 
FET 
IRQ_LOM_ALERT_N 
FM_CPU_CATERR_DLY_LVT3_N 
G21497-005 
FM_THROTTLE_N 
2
0402 
0.0 R2W3 FM_PWRBRK_SLOT_N 
FM_PMBUS_ALERT_BUF_EN_N 
FM_CPU0_THERMTRIP_LATCH_LVT3_N 
FM_ADR_MODE_SEL 
G21796-074 
FM_PMBUS_ALERT_BUF_EN_R_N 
G21497-005 
PU_PCH_TLS_ENABLE_STRAP 
SMB_SMLINK0_STBY_LVC3_SCL_R1 
SMB_SMLINK0_STBY_LVC3_SDA_R1 
SMB_PMBUS_BMC_STBY_LVC3_SCL_R1 
SMB_PMBUS_BMC_STBY_LVC3_SDA_R1 
FM_PCH_SATA_RAID_KEY 
FM_BOARD_REV_ID1 
FM_SLT_CFG2_R 
FM_BB_BMC_MP_GPIO 
R2U50 
5% 0.0 
IRQ_BMC_PCH_SCI_LPC_N 
1
IRQ_SML0_ALERT_N 
SMB_HOST_STBY_LVC3_SDA_R1 
SMB_HOST_STBY_LVC3_SCL_R1 
1/16W 
R7W13 IC 
U7C1 
FM_BIOS_POST_CMPLT_N 
1
2
R7W15 
5% 
FM_OCP_MEZZA_PRES 
R2M7 
2
1
FM_PMBUS_ALERT_BUF_EN_N 
G21497-005 
5% 
1
0402 0.0 
2
R2W4 
0
1
2
2
0402 
1
R2M3 
2133.2 
1% CHIP 
1
1/16W 
4.75K 
R2U48 
BL18 
BN18 
BK20 
BJ22 
BH17 
BL11 
BM20 
BK13 
BH20 
BK9 
BL15 
BW48 
BN11 
BW37 
BV42 
BW43 
BW34 
BW30 
BH13 
CA34 
BY33 
CA39 
BY35 
BY29 
BW32 
CA30 
BV33 
BV31 
CA28 
BV29 
BY27 
CA41 
AB3 
T4 
R1 
AB1 
AC2 
Y1 
BG22 
BR13 
BG18 
BK17 
H91415-002 
BW39 
CA32 
BG15 
BR17 
VID_PCH_CORE_PVNN_AUX_VID_0 
RST_SYSTEM_BTN_N 
FM_PMBUS_ALERT_BUF_EN_R2_N 
FM_GLOBAL_RST_WARN_N 
RST_PLTRST_N 
FM_BIOS_TOP_SWAP_SPKR 
FM_UART_ALERT_N 
IRQ_PCH_NIC_ALERT_N 
FM_PCH_PWRBTN_OUT_N 
VID_PCH_CORE_PVNN_AUX_VID_1 
PU_IRQ_VRALERT_N 
FM_QAT_EN_N 
IRQ_PVDDQ_ABC_VRHOT_LVT3_N 
IRQ_PVDDQ_DEF_VRHOT_LVT3_N 
IRQ_PVDDQ_GHJ_VRHOT_LVT3_N 
IRQ_PVDDQ_KLM_VRHOT_LVT3_N 
FP_NMI_BTN_N 
FM_PWR_BTN_N 
FM_BOARD_REV_ID2 
FM_PASSWORD_CLEAR_N 
FM_CPU1_RC_EN 
CA48 
P4 
LPC_LAD2_IO2 
R3 
33.2 
FM_UART_PRES_N 
FM_MB_SLOT_ID2 
FM_CPU_BMC_INIT 
CHIP 
V3 FM_ME_RECOVER_N 
W4 
2
5% 
1
0.0 
BV27 
BW28 
BY47 
Y3 
LPC_LAD3_IO3 
P2 
AD3 
BL7 
BH9 
BN15 
BR9 
BN7 
CA43 
1% 
1
FM_MB_SLOT_ID0 
FM_MB_SLOT_ID1 
PU_LPC_PME_N 
CLK_24M_BMC_LPC 
PU_LPC_CLKRUN_N 
IRQ_PIRQA_SPI_TPM_N 
IRQ_LPC_SERIRQ_N 
LPC_LAD_IO<3:0> 
PU_FM_RCIN_N 
FM_FAST_PROCHOT_EN_N 
FM_UV_ADR_TRIGGER_EN 
FM_BIOS_PREFRB2_GOOD 
FM_BIOS_POST_CMPLT_N 
FM_USB_P0_EN_BOOT_BIOS_STRAP_N 
FM_PCH_BMC_THERMTRIP_EXI_STRAP_N 
G21796-074 
1/16W 
2
R7C26 
PU_IRQ_PCH_SCI_WHEA_N 
AE4 
N3 
LPC_LAD0_IO0 
LPC_LFRAME_N_CS0_N 
0402 
AA4 
BV38 
FM_SLT_CFG1 
LPC_LAD1_IO1 N1 
W2 
BV35 
FM_SLT_CFG0 
2
1% 
FM_BOARD_REV_ID0 
BY38 
0402 
CA37 
IRQ_BMC_PCH_SMI_LPC_N 
G21796-072 
0402 
R2N1 1/16W 1% 
CHIP 
BY31 
FM_CPU_CATERR_DLY_LVT3_R_N 2
G21796-074 
CHIP 
FM_THROTTLE_R2_N 1
AE2 
BN44 
0402 
AA2 
CLK_24M_BMC_LPC_R 
0402 
0.0 
FM_BMC_READY_R_N 
FM_OCP_MEZZA_PRES_R 
AC4 
T2 
AD1 
V1 
3
RST_PCH_SYSRST_BTN_OUT_N 
FM_TPM_PRES_N 
FM_BMC_READY_N 
0402 
G21497-005 
G21497-005 
1
0402 
2
R7W17 0.0 
33.2 
5% 0402 
G21497-005 
5% 
TP FAB3-DVT DELETE 0OHM RES R7W7 20161206 
TP FAB3-DVT ADD RES R7W7 20161201 
TP FAB3-DVT RESERVE 0OHM R7W13 20161205 
TP FAB3-DVT ADD RES R7W15 20161206 
TP FAB3-DVT POP R7W13 20161222 
TP FAB3 NOPOP R2W4 1031 
TP FAB3-DVT POP R7W17 20161222 
TP FAB3 NOPOP R2W3 1031 
TP FAB3-DVT ADD RESERVE R7W17 20161206 
TP FAB4 POP R2W3 20170116 
TP FAB1 CHANGE CONNECTION 0310 
TP FAB4 RESERVE R7W22 20170207 
133 199 146 
156 
157 185 186 145 
157 119 
145 157 190 
146 157 190 
145 120 170 
157 144 
133 190 
146 151 
133 182 147 
133 182 147 
108 157 145 
178 
108 138 
138 108 
157 184 249 
147 177 
119 
119 
139 146 
190 
133 170 95 146 
108 
119
145
170
145 191 
190 
108 125 
138 
138 
247 
247 
135 
164 145 
182 
147 
120 133 146 
126 146 
138 
138 
119 133 146 133 250 
146 
235 
136 175 
183 190 
120 133 145 
156 
235 
133 
135 
215 94 145 
218 94 146 
223 94 144 
226 94 145 
157 145 
175 145 190 
164 145 
136 
133 190 
137 
181 164 
164 156 
136 
181 164 
181 164 
146 
133 
133 184 
133 146 
146 
133 
147 170 
125 144 191 
147 
133 119 146 
125 176 
126 134 
133 
146 
108 133 147 
164 145 
120 133 144 
156 
133 
249 
146 120 133 
146 182 
NOPOP 
IRQ_OOB_MGMT_RISER_ALERT_N 
SMB_SLOTX24_PCH_STBY_LVC3_SDA 
SMB_SLOTX24_PCH_STBY_LVC3_SCL 
FM_TPM_PRES_RST_N 
1/16W 
1/16W 
NOPOP 
1/16W 
NOPOP 
1/16W 
NOPOP 1/16W 
157 
119 
S
D
G
S
D
G
CAD NOTE: 
CAD NOTE: 
CAD NOTE: 
DESIGN NOTE: 
TP FAB1 NC 0309 
TP FAB1 NC (NO USE IE) 0118 
TP FAB1 PUT BACK NET 0227 
TP FAB1 PUT BACK NET 0310 
TP FAB1 NC (NO USE IE) 0118 
TP FAB1 PUT BACK NET 0310 
TP FAB1 NC (NO USE IE) 0118 
PLACE SERIES TERM RES CLOSE TO PCH 
DO NOT SCALE DRAWING SHEET 
B
AA
B
B
SIZE 
SCALE: 
234
1234
DEPARTMENT CODE 
1
DOCUMENT NUMBER REV 
IN 
IN 
OUT 
OUT 
IN 
OUT 
IN 
OUT 
OUT 
BI 
IN 
OUT 
BI 
IN 
IN 
IN 
IN 
IN 
OUT 
IN 
IN 
BI 
IN 
OUT 
BI 
OUT 
IN 
OUT 
OUT 
P3V3_STBY 
OUT 
OUT 
IN 
OUT 
OUT 
BI 
OUT 
OUT 
IN 
P3V3_STBY 
OUT 
OUT 
IN 
OUT 
OUT 
IN 
IN 
IN 
IN 
IN 
IN 
IN 
OUT 
OUT 
OUT 
P3V3_STBY 
P3V3_STBY 
P3V3_STBY 
IN 
OUT 
IN 
OUT 
IN 
OUT 
IN 
OUT 
OUT 
IN 
IN 
OUT 
OUT 
IN 
IN 
IN 
IN 
IN 
OUT 
IN 
OUT 
IN 
OUT 
IN 
IN 
IN 
IN 
OUT 
IN 
IN 
IN 
IN 
IN 
BI 
OUT 
IN 
IN 
119 OF 270 
Wed Feb 08 16:35:02 2017 
GPP_D9_SSATA_DEVSLP3 GPP_D8 
GPP_D7 
GPP_D6 
GPP_D5 
GPP_D4 
GPP_D3 
GPP_D23 GPP_D22_IE_UART_TX GPP_D21_IE_UART_RX GPP_D20 
GPP_D2 
GPP_D19 
GPP_D18 
GPP_D17 GPP_D16_SML0BALERT_IE_N GPP_D15_SSATA_SDATAOUT0 GPP_D14_SML0BDATA_IE GPP_D13_SML0BCLK_IE GPP_D12_SSATA_SDATAOUT1 GPP_D11_SSATA_DEVSLP5 
GPP_D10_SSATA_DEVSLP4 
GPP_D1 GPP_D0 
GPP_C9 
GPP_C8 GPP_C7_SML1DATA_IE GPP_C6_SML1CLK_IE GPP_C5_SML0ALERT_IE_N GPP_C4_SML0DATA_IE GPP_C3_SML0CLK_IE GPP_C2_SMBALERT_N 
GPP_C23 
GPP_C22 GPP_C21 GPP_C20 
GPP_C1_SMBDATA 
GPP_C19 
GPP_C18 
GPP_C17 
GPP_C16 
GPP_C15 
GPP_C14 
GPP_C13 
GPP_C12 GPP_C11 GPP_C10 
GPP_C0_SMBCLK 
GPP_B9_SRCCLKREQ4_N 
GPP_B8_SRCCLKREQ3_N 
GPP_B7_SRCCLKREQ2_N 
GPP_B6_SRCCLKREQ1_N 
GPP_B5_SRCCLKREQ0_N 
GPP_B4_CPU_GP3 
GPP_B3_CPU_GP2 
GPP_B23_MEIE_SML1ALRT_N_PHOT_N 
GPP_B22 
GPP_B21 
GPP_B20 
GPP_B2 
GPP_B1_CORE_VID1 
GPP_B19 
GPP_B18 
GPP_B17 
GPP_B16 
GPP_B15 
GPP_B14_SPKR 
GPP_B13_PLTRST_N 
GPP_B12_GLB_RST_WARN_N 
GPP_B11 
GPP_B10_SRCCLKREQ5_N 
GPP_B0_CORE_VID0 
GPP_A9_CLKOUT_LPC0_ESPI_CLK 
GPP_A8_CLKRUN_N 
GPP_A7_PIRQA_N_ESPI_ALERT0_N 
GPP_A6_SERIRQ_ESPI_CS1_N 
GPP_A5_LFRAME_N_ESPI_CS0_N 
GPP_A4_LAD3_ESPI_IO3 
GPP_A3_LAD2_ESPI_IO2 
GPP_A2_LAD1_ESPI_IO1 
GPP_A23 
GPP_A22 
GPP_A21 
GPP_A20 
GPP_A1_LAD0_ESPI_IO0 
GPP_A19 
GPP_A18 
GPP_A17 
GPP_A16_CLKOUT_LPC2 
GPP_A15_SUSACK_N 
GPP_A14_ESPI_RESET_N 
GPP_A13_SUSWARN_N_SUSPWRDNACK 
GPP_A12_BMBUSY_N_SXEXITHLDOFF_N 
GPP_A11_PME_N 
GPP_A10_CLKOUT_LPC1 
GPP_A0_RCIN_N_ESPI_ALERT1_N 
TP FAB1 NC (NO USE IE) 0118 
ROOM=SB 
PLEASE PLACE LED NEAR POWER BUTTON S9A2 
SMBUS PULL UP AND SERIES RESISTORS ON SEPARATE PAGE
PLACE DAMPENING RESISTOR ON LPC CLOCK CLOSE TO PCH 
LEWISBURG 6/11 GPIO A-D 
LBG_CORE_QAT_EXT_D 
WIWYNN CORPORATION 
6/14 



1/16W 1/16W 
1/16W 
1/16W 
1/16W 
TP FAB3-DVT CHANGE CONNECTION 20161117 
TP FAB3-DVT RESERVE 0OHM R7W16 20161206 
TP FAB3-DVT POP R7W16 20161222 
TP FAB3-DVT RESERVE RES R7W11 20161201 
TP FAB3-DVT POP R7W11 20161222 
TP FAB1 NC (NO USE IE) 0118 
TP FAB1 NC (NO USE IE) 0118 
TP FAB3-DVT ADD 0OHM R7W18 20161207 
TP FAB3-DVT POP R7W14 20161222 
TP FAB3-DVT RESERVE RES R7W14 20161206 
TP FAB3-DVT RESERVE RES R7W8, R7W10, R7W12 20161201
TP FAB4 POP R7W8 20170117 
TP FAB4 POP R7W10 20170116 
TP FAB3-DVT POP R7W12 20161222 
TP FAB4 NOPOP R7W20 20170117 
TP FAB4 ADD R7W20 20170116 
IRQ_BMC_PCH_SCI_LPC_N 
189 
200 145 170 
133 144 119 
133 146 119 
177 
89 156 157 
191 145 156 
191 
92 144 
133 119 145 
135 190 
89 
145 
147 154 
145 
133 120 145 
157 
89 191 
164 147 
188 
188 
126 
125 
189 
133 146 119 182 
185 
134 144 
120 133 145 
157 146 
133 146 175 
126 145 200 
138 
138 
138 
138 
188 
188 
188 
188 
188 
188 
188 
188 
188 
164 147 
164 147 
164 147 
164 147 
191 145 
118 
133 
188 
188 
188 
188 
188 
189 
189 
190 144 158 
189 
188 
133 190 
146 157 181 
157 181 144 190 
199 146 170 
190 144 158 
168 145 190 
119 145 170 
188 
188 
188 
200 145 
200 145 170 
189 
189 
189 
178 
178 
144 191 
136 145 157 
191 145 
138 
176 190 
138 
92 147 190 
247 
168 146 
22 133 118 
145 
JTAG_PCH_GBE_CLK 
R7W20 
IRQ_UV_DETECT_N 
IRQ_BMC_PCH_SMI_LPC_N 
LED_PCH_SATA_HDD_N 
FM_ADR_SMI_GPIO_N 
IRQ_BMC_PCH_NMI_STBY_N 
FM_CPLD_ADR_TRIGGER_N 
FM_CPU1_RC_ERROR_N 
G21497-005 
1R7W12 
0.0 
FM_CPU_ERR2_LVT3_N 
IC 
G21796-074 
FM_CPLD_ADR_TRIGGER_R_N 
R7W8 
SGPIO_PCH_SSATA_CLOCK 
SGPIO_PCH_SSATA_LOAD 
G21497-005 
FM_CPU0_RC_ERROR_R1_N 
IRQ_PCH_NIC_ALERT_N 
0402 
0402 1/16W 
5% 
FM_IE_DISABLE_N 
2
0.0 
AU17 
BE52 
AU20 
AR17 
AP18 
BH50 
BG52 
AV52 
AV56 
1
CHIP 
2
1
33.2 
1% 
2
0.0 
AW54 
FM_CPU1_RC_ERROR_N 
IRQ_DIMM_SAVE_LVT3_N 
G21497-005 
1/16W 
G21796-074 
5% 
R7W11 
FM_BACKUP_BIOS_SEL_N 
100.0 
1
FM_BIOS_MRC_DEBUG_MSG_DIS_N 
0.0 0402 1/16W 
FM_BIOS_SMI_ACTIVE_N 
FM_NMI_EVENT_N 
FM_ADR_COMPLETE 
FM_BOARD_SKU_ID4 
BL3 
AH17 
2
R7W14 
SMB_PCH_MEZZ_LOM1_SCL 
SMB_PCH_MEZZ_LOM0_SCL 
BV12 
BY12 
AV7 
FM_ADR_COMPLETE_R1 
AH13 
0402 
2
FM_FLASH_ATTACH_CFG_STRAP 
PU_ADR_TIMER_HOLD_OFF_N 
1/16W 1% 
JTAG_PCH_GBE_TRST_N 
BW20 
AP15 
AK17 
FM_BMC_READY_N 
BA13 
AU9 
AT2 
CA22 
FM_SSATA_PCIE_M2_SEL 
FM_PCH_BMC_THERMTRIP_N 
FM_BIOS_SMI_ACTIVE_N 
FM_BMC_NMI_N 
FP_PWR_ID_LED_N 
FM_OC_DETECT_EN_N 
SMB_LAN_STBY_LVC3_SDA_R1 
SMB_LAN_STBY_LVC3_SCL_R1 
SMB_VR_STBY_LVC3_SDA_R1 
SMB_VR_STBY_LVC3_SCL_R1 
SMB_PCH_MEZZ_LOM3_SCL 
SMB_PCH_MEZZ_LOM2_SCL 
SMB_PCH_MEZZ_LOM2_SDA 
SMB_PCH_MEZZ_LOM1_SDA 
LED_GBE_P3_1 
LED_GBE_P3_0 
LED_GBE_P2_1 
LED_GBE_P2_0 
LED_GBE_P1_1 
FM_BOARD_SKU_ID2 
FM_BOARD_SKU_ID3 
FM_BOARD_SKU_ID1 
FM_BOARD_SKU_ID0 
FM_CPU1_THERMTRIP_LATCH_LVT3_N 
TP_PCH_GPP_J17 
2
1/16W 
R2N26 
1
1% 0402 
33.2 
CHIP 
AP11 
AW2 
AT4 
AR1 
BV25 
BY21 
AW20 
AV18 
AY15 
BA20 
AY18 
BE18 
BD17 
BE7 
BG7 
BD20 
AV3 
AY3 
AR3 
H91415-002 
AY11 
BE22 
BV14 
BF3 
BW5 
BN3 
BD1 
BE2 
BA4 
BB1 
BY25 
BN48 
AU58 
AL7 
AL15 
AH9 
BD9 
AV15 
AY7 
BA9 
AY1 
BC2 
BB3 
BF1 
BE4 
BC4 
BD3 
AW4 
BA2 
BH2 
BH4 
AV1 
BV21 
BY23 
BV23 
CA24 
BW22 
BL1 
BV8 
BT5 
BW11 
BW6 
BW9 
BV10 
CA11 
BY10 
BK4 
BW13 
BP4 
BU6 
CA13 
BM2 
BM4 
BE15 
CA20 
BA17 
U7C1 
5% 
TP_PCH_GPP_J19 
BG11 
AV11 
BE11 
AK20 
2
AK9 
AG7 
1
FM_10GBE_LOM_DISABLE_N 
PU_10GBE_LOM_PCI_DISABLE_N 
BW24 AL18 
AL11 
AR13 
AU13 
FM_GBE1_LVC3_MOD_ABS 
FM_GBE0_LVC3_MOD_ABS 
SMB_PCH_MEZZ_LOM3_SDA 
BY14 
FM_GBE2_LVC3_MOD_ABS 
TP_PCH_GPP_J21 
FM_GBE3_LVC3_MOD_ABS 
5% 
BB52 
2
JTAG_PCH_GBE_TMS 
TP_PCH_GPP_J23 
JTAG_PCH_GBE_TDO 
FM_UARTSW_LSB_N 
A_RCOMP_3P3 
0402 
FM_CPU1_RC_ERROR_R_N 
0402 
AR9 
1 AP7 
AR20 
G21497-005 
R7W18 
R8C21 
2
G21796-017 
0402 CHIP 
JTAG_PCH_GBE_TDI 
IRQ_DIMM_SAVE_LVT3_R_N 
IRQ_BOARD_BMC_ALERT_N 
SMB_PCH_MEZZ_LOM0_SDA 
1
R7W16 
0.0 
5% G21497-005 
FM_CPU0_RC_EN 
FM_BMC_READY_R1_N 
FM_MP_PS_REDUNDANT_LOST_N 
FM_MP_PS_FAIL_N 
1
0.0 
0402 
R7W10 
IRQ_SML1_PMBUS_ALERT_N 
0.0 
5% 
5% 
G21497-005 
FM_UARTSW_MSB_N 
FM_SOL_UART_CH_SEL 
IRQ_FORCE_NM_THROTTLE_N 
1
BJ48 
AT52 
FM_BIOS_USB_RECOVERY 
AK13 
BK2 
LED_GBE_P1_0 
LED_GBE_P0_1 
LED_GBE_P0_0 
BD13 
IRQ_OC_DETECT_N 
FM_HSC_TIMER_EXP_N 
JTAG_PCH_PLD_TDI 
JTAG_PCH_PLD_TCK 
JTAG_PCH_PLD_TMS 
JTAG_PCH_PLD_TDO 
SGPIO_PCH_SATA_CLOCK 
SGPIO_PCH_SATA_LOAD 
LED_PCH_SSATA_HDD_N 
FM_FORCE_ADR_N 
FM_BIOS_TOP_SWAP 
FM_MEM_THERM_EVENT_PCH_N 
SMB_LAN_STBY_LVC3_SDA_R2 
0402 
G21497-005 FM_POST_CARD_PRES_BMC_R1_N 
AY52 1 2 FM_CPU1_RC_ERROR_R1_N 
SGPIO_PCH_SATA_DOUT0 
IRQ_SML1_PMBUS_ALERT_R1_N 
BL48 FM_OC0_USB_N 
1% 
0402 
NOPOP 
G21796-072 
SMB_LAN_STBY_LVC3_SCL_R2 
FM_CPU_MSMI_LVT3_N 
4.75K 
1/16W 
CHIP 2
R2M1 
FM_POST_CARD_PRES_BMC_N 
FM_CPU0_RC_ERROR_N CAD NOTE: 
CAD NOTE: 
DESIGN NOTE: 
DO NOT SCALE DRAWING SHEET 
B
AA
B
B
SIZE 
SCALE: 
234
1234
DEPARTMENT CODE 
1
DOCUMENT NUMBER REV 
IN 
IN 
IN 
IN 
IN 
OUT 
OUT 
OUT 
BI 
IN 
IN 
IN 
OUT 
BI 
OUT 
OUT 
P3V3_STBY 
IN 
IN 
IN 
IN 
OUT 
IN 
IN 
OUT 
BI 
BI 
OUT 
OUT 
OUT 
OUT 
IN 
IN 
IN 
IN 
BI 
BI 
OUT 
OUT 
OUT 
OUT 
OUT 
OUT 
OUT 
OUT 
OUT 
OUT 
OUT 
OUT 
OUT 
OUT 
OUT 
OUT 
IN 
IN 
OUT 
OUT 
OUT 
IN 
IN 
OUT 
IN 
IN 
IN 
IN 
BI 
OUT 
OUT 
OUT 
IN 
IN 
IN 
OUT 
IN 
IN 
IN 
OUT 
OUT 
IN 
IN 
IN 
IN 
OUT 
OUT 
IN 
OUT 
OUT 
IN 
IN 
IN 
IN 
IN 
IN 
IN 
OUT 
IN 
ROOM=SB 
TP FAB1 NC (NO USE IE) 0118 
120 OF 270 
Wed Feb 08 16:35:03 2017 
SMBUS PULL UP AND SERIES RESISTORS ON SEPARATE PAGE
PLACE SERIES TERM RES CLOSE TO PCH 
PLACE RCOMP RES 
CLOSE TO PCH 
GPP_J9_LAN_I2C_SDA_MDIO_P0 GPP_J8_LAN_I2C_SCL_MDC_P0 GPP_J7_LAN_LED_P3_1 GPP_J6_LAN_LED_P3_0 GPP_J5_LAN_LED_P2_1 GPP_J4_LAN_LED_P2_0 GPP_J3_LAN_LED_P1_1 GPP_J2_LAN_LED_P1_0 
GPP_J23_LAN_SDP_P3_1 GPP_J22_LAN_SDP_P3_0 GPP_J21_LAN_SDP_P2_1 GPP_J20_LAN_SDP_P2_0 
GPP_J1_LAN_LED_P0_1 
GPP_J19_LAN_SDP_P1_1 GPP_J18_LAN_SDP_P1_0 GPP_J17_LAN_SDP_P0_1 GPP_J16_LAN_SDP_P0_0 GPP_J15_LAN_I2C_SDA_MDIO_P3 GPP_J14_LAN_I2C_SCL_MDC_P3 GPP_J13_LAN_I2C_SDA_MDIO_P2 GPP_J12_LAN_I2C_SCL_MDC_P2 GPP_J11_LAN_I2C_SDA_MDIO_P1 GPP_J10_LAN_I2C_SCL_MDC_P1 
GPP_J0_LAN_LED_P0_0 
GPP_I9_LAN_DIS_N GPP_I8_PCI_DIS_N GPP_I7_LAN_TRST_N GPP_I6_RESET_DONE GPP_I5_DO_RESET_OUT_N GPP_I4_DO_RESET_IN_N GPP_I3_LAN_TDI GPP_I2_LAN_TMS GPP_I1_LAN_TCK 
GPP_I10 
GPP_I0_LAN_TDO 
GPP_H9_SRCCLKREQ15_N 
GPP_H8_SRCCLKREQ14_N 
GPP_H7_SRCCLKREQ13_N 
GPP_H6_SRCCLKREQ12_N 
GPP_H5_SRCCLKREQ11_N 
GPP_H4_SRCCLKREQ10_N GPP_H3_SRCCLKREQ9_N 
GPP_H2_SRCCLKREQ8_N 
GPP_H23_SSATAXPCIE5_SSATAGP5 
GPP_H22_SSATAXPCIE4_SSATAGP4 
GPP_H21_SSATAXPCIE3_SSATAGP3 
GPP_H20_SSATAXPCIE2_SSATAGP2 
GPP_H1_SRCCLKREQ7_N 
GPP_H19_SSATAXPCIE1_SSATAGP1 GPP_H18_SML4ALERT_N_IE_N GPP_H17_SML4DATA_IE GPP_H16_SML4CLK_IE GPP_H15_SML3ALERT_N_IE_N GPP_H14_SML3DATA_IE GPP_H13_SML3CLK_IE GPP_H12_SML2ALERT_N_IE_N GPP_H11_SML2DATA_IE GPP_H10_SML2CLK_IE 
GPP_H0_SRCCLKREQ6_N 
GPP_G9_FANPWM1_FAMPWM1IE 
GPP_G8_FANPWM0_FANPWM0IE 
GPP_G7_FANTACH7_FANTACH7IE 
GPP_G6_FANTACH6_FANTACH6IE 
GPP_G5_FANTACH5_FANTACH5IE 
GPP_G4_FANTACH4_FANTACH4IE 
GPP_G3_FANTACH3_FANTACH3IE 
GPP_G2_FANTACH2_FANTACH2IE 
GPP_G23_SSATAXPCIE0_SSATAGP0 
GPP_G22_SSATA_DEVSLP2 
GPP_G21_SSATA_DEVSLP1 
GPP_G20_SSATA_DEVSLP0 
GPP_G1_FANTACH1_FANTACH1IE 
GPP_G19_SMI_N 
GPP_G18_NMI_N 
GPP_G17_ADR_COMPLETE 
GPP_G16 
GPP_G15 
GPP_G14 
GPP_G13 
GPP_G12 
GPP_G11_FANPWM3_FANPMW3IE 
GPP_G10_FANPWM2_FANPWM2IE 
GPP_G0_FANTACH0_FANTACH0IE 
GPP_F9_SATA_DEVSLP7 
GPP_F8_SATA_DEVSLP6 
GPP_F7_SATA_DEVSLP5 
GPP_F6_SATA_DEVSLP4 
GPP_F5_SATA_DEVSLP3 
GPP_F4_SATAXPCIE7_SATAGP7 
GPP_F3_SATAXPCIE6_SATAGP6 
GPP_F2_SATAXPCIE5_SATAGP5 
GPP_F23_SSATA_SLOAD 
GPP_F22_SSATA_SCLOCK 
GPP_F21_LAN_SMBALRT_N 
GPP_F20_LAN_SMBDATA 
GPP_F1_SATAXPCIE4_SATAGP4 
GPP_F19_LAN_SMBCLK 
GPP_F18_USB2_OC7_N 
GPP_F17_USB2_OC6_N 
GPP_F16_USB2_OC5_N 
GPP_F15_USB2_OC4_N 
GPP_F14_SSATA_LED_N 
GPP_F13_SATA_SDATAOUT0 
GPP_F12_SATA_SDATAOUT1 
GPP_F11_SATA_SLOAD 
GPP_F10_SATA_SCLOCK 
GPP_F0_SATAXPCIE3_SATAGP3 
GPP_E9_USB2_OC0_N 
GPP_E8_SATA_LED_N 
GPP_E7_CPU_GP1 
GPP_E6_SATA_DEVSLP2 
GPP_E5_SATA_DEVSLP1 
GPP_E4_SATA_DEVSLP0 
GPP_E3_CPU_GP0 
GPP_E2_SATAXPCIE2_SATAGP2 
GPP_E1_SATAXPCIE1_SATAGP1 
GPP_E12_USB2_OC3_N 
GPP_E11_USB2_OC2_N 
GPP_E10_USB2_OC1_N 
GPP_E0_SATAXPCIE0_SATAGP0 
GPIO_RCOMP_3P3 
LEWISBURG 7/11 GPIO E-J 
LBG_CORE_QAT_EXT_D 
WIWYNN CORPORATION 
7/14 



TP_PCH_RSVD2 
RMII_BMC_PCH_SPRNGVLLE_CRSDV_R1 
AA13 
A_1P8_3P3_RCOMP 
H4 
RMII_SPRNGVLLE_BMC_PCH_RXD1_R1 
TP_PCH_RSVD12 
SPI_PCH_CS0_N 
SPI_PCH_MOSI 
FM_WBG_PRSNT_N 
TP_PCH_RSVD46 
TP_PCH_RSVD27 
TP_PCH_RSVD26 
TP_SPI_PCH_CS1_R1_N 
TP_PCH_HDA_SDI_0 
TP_PCH_RSVD8 
TP_PCH_RSVD7 
TP_PCH_RSVD6 
TP_PCH_RSVD5 
TP_PCH_RSVD3 
TP_PCH_RSVD1 
TP_PCH_RSVD0 
TP_PCH_RSVD23 
TP_PCH_RSVD21 
TP_PCH_RSVD20 
TP_PCH_RSVD22 
TP_PCH_RSVD19 
TP_PCH_RSVD18 
TP_PCH_RSVD17 
TP_PCH_RSVD15 
TP_PCH_RSVD4 
TP_PCH_RSVD13 
TP_PCH_RSVD14 
RST_PCIE_PCH_PERST_N 
TP_PCH_RSVD16 
RMII_PCH_SPRNGVLLE_ARB_OUT_R 
RMII_PCH_SPRNGVLLE_ARB_IN 
RMII_BMC_PCH_SPRNGVLLE_RXER_R 
CLK_50M_CKMNG_PCH_10GBE 
RMII_BMC_PCH_SPRNGVLLE_TXEN 
RMII_BMC_PCH_SPRNGVLLE_TXD0 
CLK_50M_CKMNG_PCH_10GBE 
RMII_BMC_PCH_SPRNGVLLE_TXD1 
RMII_SPRNGVLLE_BMC_PCH_RXD0_R1 
TP_PCH_RSVD24 
TP_PCH_GPP_L10 
TP_PCH_GPP_L11 
TP_PCH_RSVD25 
H_CPU0_MEMDEF_MEMHOT_PCH_N 
H_CPU1_MEMGHJ_MEMHOT_PCH_N 
FM_CPU1_PROCHOT_PCH_N 
FM_CPU0_PROCHOT_PCH_N 
H_CPU1_MEMKLM_MEMHOT_PCH_N 
H_CPU0_MEMABC_MEMHOT_PCH_N 
FM_CPU_ERR0_PCH_N 
FM_CPU_ERR1_PCH_N 
FM_PRSNT_2_1_N 
FM_PRSNT_2_2_N 
FM_PRSNT_2_3_N 
FM_PRSNT_2_4_N 
FM_PRSNT_2_5_N 
FM_PRSNT_2_6_N 
TP_PCH_RSVD9 
FM_SINT_PRSNT_N 
TP_PCH_HDA_BCLK 
TP_PCH_HSA_RST_N 
TP_PCH_HDA_SYNC 
TP_PCH_DISPA_BCLK 
TP_PCH_DISPA_SDI 
TP_PCH_DISPA_SDO 
SPI_PCH_MOSI_R 
SPI_PCH_CS0_R_N 
SPI_PCH_CLK 
SPI_PCH_IO3 
SPI_PCH_IO2 
SPI_PCH_MISO 
FM_FLASH_DESC_OVERRIDE 
TP_PCH_HDA_SDI_1 
FM_OCP_MEZZB_PRES_1V05_PCH_N 
FM_OCP_MEZZC_PRES_1V05_PCH_N 
FM_INTRUDER_HDR_PCH_N 
RMII_SPRNGVLLE_BMC_PCH_RXD0 
RMII_SPRNGVLLE_BMC_PCH_RXD1 
RMII_BMC_PCH_SPRNGVLLE_CRSDV 
RMII_PCH_SPRNGVLLE_ARB_OUT 
RMII_BMC_PCH_SPRNGVLLE_RXER RMII_BMC_PCH_SPRNGVLLE_R XER_R 
RMII_PCH_SPRNGVLLE_ARB_OUT_R 
RMII_BMC_PCH_SPRNGVLLE_CRSDV_R1 
RMII_SPRNGVLLE_BMC_PCH_RXD1_R1 
RMII_SPRNGVLLE_BMC_PCH_RXD0_R1 
SPI_PCH_TPM_CS_N 
1/16W 
R7C14 
CHIP 0402 G21796-074 
133.2 
1% 
2
1/16W CHIP G21497-005 5% 
R2P1 
0.0 1 2
0402 
1/16W CHIP G21497-005 0402 
R3P2 
0.0 
5% 
21
1/16W G21497-005 CHIP 0402 
2
R3P3 
0.0 
5% 
1
1/16W 
CHIP 
G21796-016 
10.0K 
1% 
0402 
2
1
R7C20 
G21796-016 
R3N10 
10.0K 
1% 
CHIP 
1/16W 
2
1
0402 
G21796-017 
CHIP 
1/16W 
100.0 
1% 
0402 
2
1
R8C26 
H91415-002 
P18 
AF20 
AD17 
AD9 
AA20 
C5 
AL1 
AL3 
AN3 
Y7 
AG11 
U7C1 
IC 
Y18 
AD20 
C70 
AM4 
AJ1 
AH4 
AJ3 
AE18 
AE15 
AE11 
M18 
K20 
V18 
U24 
H20 
AG18 
V22 
R20 
U20 
BW3 
BG26 
BH24 
P48 
P40 
AT71 
A11 
D10 
C9 
C11 
B10 
C6 
E18 
C67 
C68 
C18 
D8 
F66 
F69 
F8 
AT69 
AG15 
P37 
V11 
AA58 
AC56 
AF61 
P11 
K2 
J3 
G7 
F5 
L1 
L3 
K4 
G18 
AH2 
AK4 
AM2 
AK2 
Y11 
AA17 
AN1 
AD13 
AA9 
AE7 
Y15 
P44 
33.2 1/16W G21796-074 
R7C16 
1% CHIP 
21
0402 
0.0 G21497-005 
R7C15 
5% 0402 CHIP 1/16W 
21
FM_PCH_PRSNT_N 
RST_SRTCRST_N 
RST_RTCRST_N 
CHIP 0402 1/16W G21796-074 
R8D11 
133.2 
1% 
2
TP FAB1 RENAME 0307 
INSTALLED WRONG DIRECTION 
121 
121 
154 
111 125 154 184 
133 191 
190 
121 
139 
121 
101 121 
139 147 150 
147 139 
101 121 
147 139 
121 
152 
152 
93 
93 
152 
152 
93 
93 
133 
133 
133 
133 
133 
109 133 
133 191 
154 184 
125 154 
111 125 154 
154 184 
125 147 
133 250 
133 250 
139 147 
139 147 
139 147 
125 139 
125 147 121 
121 
121 
121 
121 
184 
133 191 
137 
137 
CAD NOTE: 
CAD NOTE: 
CAD NOTE: 
LBG 
RSVD 
WBG 
RMII_SPRNGVLLE_BMC_PCH_RXD0_R1 
NETS WITHIN TWO INCHES OF THE PCH: 
RMII_BMC_PCH_SRNGVLLE_CRSDV_R1 
RMII_BMC_PCH_SPRNGVLLE_RXER_R 
PLACE CLK_50M_CKMNG_PCH_10GBE 
RES NEAR PCH 
RMII_PCH_SPRNGVLLE_ARB_OUT_R 
PLACE SERIES RESISTORS ON THE FOLLOWING 
RMII_SPRNGVLLE_BMC_PCH_RXD1_R1 
DO NOT SCALE DRAWING SHEET 
B
AA
B
B
SIZE 
SCALE: 
234
1234
DEPARTMENT CODE 
1
DOCUMENT NUMBER REV 
OUT 
IN 
IN 
IN 
OUT 
OUT 
OUT 
IN 
IN 
IN 
IN 
IN IN 
IN 
IN 
IN 
IN 
IN 
OUT 
OUT 
OUT 
IN 
IN 
IN 
IN 
IN 
OUT 
OUT 
OUT 
IN 
P3V3_STBY 
OUT 
OUT 
OUT 
OUT 
IN 
IN 
IN 
IN 
IN 
IN 
IN 
IN 
IN 
IN 
OUT 
OUT 
OUT 
OUT 
OUT 
OUT 
IN 
121 OF 270 
Wed Feb 08 16:35:03 2017 
CGC_DUT_DETECT_N 
GPIO_RCOMP_1P8_3P3 
GPP_K0_LAN_NCSI_CLK_IN 
GPP_K10_PE_RST_N 
GPP_K1_LAN_NCSI_TXD0 GPP_K2_LAN_NCSI_TXD1 GPP_K3_LAN_NCSI_TX_EN GPP_K4_LAN_NCSI_CRS_DV GPP_K5_LAN_NCSI_RXD0 GPP_K6_LAN_NCSI_RXD1 GPP_K7 GPP_K8_LAN_NCSI_ARB_IN GPP_K9_LAN_NCSI_ARB_OUT 
GPP_L10_TESTCH0_CLK GPP_L11_TESTCH1_D0 GPP_L12_TESTCH1_D1 GPP_L13_TESTCH1_D2 GPP_L14_TESTCH1_D3 GPP_L15_TESTCH1_D4 GPP_L16_TESTCH1_D5 GPP_L17_TESTCH1_D6 GPP_L18_TESTCH1_D7 GPP_L19_TESTCH1_CLK 
GPP_L2_TESTCH0_D0 GPP_L3_TESTCH0_D1 GPP_L4_TESTCH0_D2 GPP_L5_TESTCH0_D3 GPP_L6_TESTCH0_D4 
GPP_L7_TESTCH0_D5 GPP_L8_TESTCH0_D6 GPP_L9_TESTCH0_D7 
HDA_BCLK HDA_RST_N HDA_SDI_0 HDA_SDI_1 HDA_SDO HDA_SYNC 
INTRUDER_N 
RSVD<68> 
RSVD<67> 
RSVD<66> 
RSVD<46> 
RSVD<27> 
RSVD<26> 
RSVD<25> 
RSVD<24> 
RSVD<23> 
RSVD<22> 
RSVD<21> 
RSVD<20> 
RSVD<19> 
RSVD<18> 
RSVD<17> 
RSVD<16> 
RSVD<15> 
RSVD<14> 
RSVD<13> 
RSVD<12> 
RSVD<11> 
RSVD<10> RSVD<9> 
RSVD<8> 
RSVD<7> 
RSVD<6> 
RSVD<5> 
RSVD<4> 
RSVD<3> 
RSVD<2> 
RSVD<1> 
RSVD<0> 
RTCRST_N 
SPI0_CLK 
SPI0_FLASH_CS0_N SPI0_FLASH_CS1_N 
SPI0_IO2 
SPI0_IO3 
SPI0_MISO_IO1 SPI0_MOSI_IO0 
SPI0_TPM_CS_N 
SRTCRST_N 
SINT_PRSNT 
TP FAB1 RENAME 1218 
0
X
1
COMMENT PIN D8 
WBG_PRSNT 
1
0
PIN C18 CGC_DUT_DETECT# 
X
1
1
1
0
0
0
ROOM=SB 
PLACE SPI SERIES RES CLOSE TO PCH 
LEWISBURG 8/11 RMII, SPI 
PCH DETECTION 
LBG_CORE_QAT_EXT_D 
WIWYNN CORPORATION 
8/14 



AK45 
A_PVCCRTC_EXT_CAP 
TP_PCH_RSVD59 
TP_PCH_RSVD58 
TP_PCH_RSVD31 
TP_PCH_RSVD30 
TP_PCH_RSVD29 
TP_PCH_RSVD28 
AG22 
AK50 
AW48 
BA46 
BA45 
AD24 
BD46 
AE26 
AK29 
AG29 
AJ27 
BF46 
BE48 
AU39 
AU37 
AT39 
AM27 
AJ29 
AC26 
AA46 
AA45 
Y46 
Y45 
V44 
U46 
T44 
R46 
R42 
AA24 
Y26 
AG27 
AU29 
AW29 
AT29 
AM29 
AP29 
AW27 
AK24 
AU24 
BB26 
BA24 
BA26 
AU27 
BE44 
BA43 
BE40 
BE26 
AW24 
BB37 
BB33 
BA37 
BA36 
BA34 
BA32 
BA30 
BA29 
BA27 
BD38 
BB40 
BA41 
BA39 
AW45 
AW43 
AJ43 
AU45 
AU43 
AT45 
AT43 
AP45 
AP43 
AD50 
AH50 
U50 
W50 
AG45 
AJ46 
AJ48 
AE46 
R35 
P33 
R31 
P29 
AP27 
AT27 
AK27 
AE45 
AG48 
AP48 
AU48 
AT48 
AN50 
AM48 
AM45 
AM43 
AK43 
BA48 
AH24 
AN24 
AR24 
IC 
H91415-002 
U7C1 
130 
DO NOT SCALE DRAWING SHEET 
B
AA
B
B
SIZE 
SCALE: 
234
1234
DEPARTMENT CODE 
1
DOCUMENT NUMBER REV 
P1V05_PCH_STBY_VCCA_PLL1 
P1V05_PCH_STBY_VCCA_PLL0 
P1V05_PCH_STBY 
P3V3_RTC_STBY 
P1V05_PCH_STBY_VCCA_XTAL 
P1V05_PCH_STBY_ISCLK_PLL 
P1V05_PCH_STBY_KR_PLL 
P1V05_PCH_STBY_WM20_PLL 
P1V05_PCH_STBY_WM26_PLL P3V3_STBY 
OUT 
P1V05_PCH_STBY 
P1V8_PCH_STBY 
122 OF 270 
Wed Feb 08 16:35:03 2017 
RSVD<59> 
RSVD<58> 
RSVD<31> 
RSVD<30> RSVD<29> 
RSVD<28> 
VCCA_CLKFILT_1P05<4> 
VCCA_CLKFILT_1P05<3> 
VCCA_CLKFILT_1P05<2> 
VCCA_CLKFILT_1P05<1> 
VCCA_CLKFILT_1P05<0> 
VCCA_CLKUNF_1P05<1> 
VCCA_CLKXTAL_1P05 
VCCA_PLL0_1P05 VCCA_PLL1_1P05 
VCCMPHY_1P05<12> 
VCCMPHY_1P05<11> 
VCCMPHY_1P05<10> 
VCCMPHY_1P05<9> 
VCCMPHY_1P05<8> 
VCCMPHY_1P05<4> 
VCCMPHY_1P05<3> 
VCCMPHY_1P05<2> 
VCCMPHY_1P05<1> 
VCCMPHY_1P05<0> 
VCCP10GBEPLL_1P05<3> 
VCCP10GBEPLL_1P05<2> 
VCCP10GBEPLL_1P05<1> 
VCCP10GBEPLL_1P05<0> 
VCCP10GBE_HV_1P8<1> 
VCCP10GBE_HV_1P8<0> 
VCCP10GBE_LV_1P05<6> 
VCCP10GBE_LV_1P05<5> 
VCCP10GBE_LV_1P05<4> 
VCCP10GBE_LV_1P05<3> 
VCCP10GBE_LV_1P05<2> 
VCCP10GBE_LV_1P05<1> 
VCCP10GBE_LV_1P05<0> 
VCCPDSW_3P3 
VCCPGPPA 
VCCPGPPB VCCPGPPC 
VCCPGPPD VCCPGPPE VCCPGPPF VCCPGPPG VCCPGPPH 
VCCPGPP_1P8<6> 
VCCPGPP_1P8<5> 
VCCPGPP_1P8<4> 
VCCPGPP_1P8<3> 
VCCPGPP_1P8<2> 
VCCPGPP_1P8<1> 
VCCPGPP_1P8<0> 
VCCPHDA_1P8 
VCCPRIM_1P05<16> 
VCCPRIM_1P05<15> 
VCCPRIM_1P05<14> 
VCCPRIM_1P05<13> 
VCCPRIM_1P05<12> 
VCCPRIM_1P05<11> 
VCCPRIM_1P05<10> 
VCCPRIM_1P05<9> 
VCCPRIM_1P05<8> 
VCCPRIM_1P05<7> 
VCCPRIM_1P05<6> 
VCCPRIM_1P05<5> 
VCCPRIM_1P05<4> 
VCCPRIM_1P05<3> 
VCCPRIM_1P05<2> 
VCCPRIM_1P05<1> 
VCCPRIM_1P05<0> 
VCCPRTC 
VCCPRTCPRIM_3P3 
VCCPSPI 
VCCPSPI_1P8 
VCCPUSBDSW_3P3 
VCCP_1P8<1> 
VCCP_1P8<0> 
VCCP_3P3<5> 
VCCP_3P3<0> 
VCCP_HSIOPLLUNF_1P05 
VCCP_HSIOPLL_1P05<3> 
VCCP_HSIOPLL_1P05<2> 
VCCP_HSIOPLL_1P05<0> 
VCCP_UPPLLUNF_1P05 VCCP_UPPLL_1P05<2> 
VCCP_UPPLL_1P05<0> 
VCCRTCEXT 
VCCA_CLKUNF_1P05<0> 
VCCPRIM_1P05<17> 
VCCMPHY_1P05<5> VCCMPHY_1P05<6> 
VCCMPHY_1P05<7> 
VCCP_3P3<1> 
VCCP_3P3<2> VCCPRIM_1P05<18> VCCPRIM_1P05<19> 
VCCPGPPK VCCPGPPJ 
ROOM=SB 
LEWISBURG 9/11 PWR 
LBG_CORE_QAT_EXT_D 
WIWYNN CORPORATION 
9/14 



V29 
VSENSE_PVNN_PCH_STBY_FPK 
VSENSE_PVNN_PCH_STBY_QAT 
AK36 
V37 
AU36 
AU34 
AU32 
AT36 
AT34 
AT32 
AP39 
AP37 
AP36 
AP34 
AP32 
AM39 
AM37 
AM36 
AM34 
AM32 
AK39 
AK37 
AK34 
AG39 
AG37 
AG36 
AG34 
AG32 
AE41 
AE39 
AE37 
AE36 
AE34 
AE32 
AE30 
U27 
AC41 
AC39 
AC37 
AC36 
AC34 
AC32 
AC30 
AC29 
AA41 
AA39 
AA37 
AA36 
AA34 
AA32 
AA30 
AA29 
Y41 
Y39 
Y37 
Y36 
Y34 
Y32 
Y30 
Y29 
V40 
V33 
U38 
U35 
U31 AK32 
AE27 
IC 
H91415-002 
U7C1 
A41 
BP69 
BT69 
BU70 
BR70 
F70 
E70 
BU3 
BR3 
F3 
E3 
A5 
A7 
A9 
A65 
A66 
A68 
J1 
J72 
BN1 
BN72 
CA68 
CA66 
CA65 
CA9 
CA7 
CA5 
A70 
CA3 
BW1 
BU1 
BR1 
C3 
C72 
E1 
E72 
G1 
G72 
BR72 
BU72 
BW70 
BW72 
CA70 
BB48 
AT37 
Y72 
Y70 
A18 
A22 
A30 
A34 
A37 
B12 
B19 
B25 
B27 
B47 
C22 
C30 
C34 
C37 
C41 
C65 
D12 
D16 
D19 
D25 
D27 
E59 
E65 
D47 
E11 
E13 
E15 
E20 
E22 
E24 
E26 
E28 
E30 
E32 
E34 
E37 
E39 
E41 
E43 
E45 
E48 
E50 
E52 
E54 
E57 
E6 
E61 
E63 
G59 
E9 
G22 
G29 
G37 
G48 
G6 
G63 
G66 
H58 
J29 
J5 
J7 
H65 
J11 
J15 
J22 
J37 
J44 
J59 
J68 
J70 
K54 
K69 
K71 
L5 
L68 
M2 
M22 
M26 
M29 
M33 
M37 
M4 
M40 
N42 
N50 
M44 
M48 
N13 
N17 
N20 
N24 
N27 
N31 
IC 
H91415-002 
U7C1 
236 
236 
DO NOT SCALE DRAWING SHEET 
B
AA
B
B
SIZE 
SCALE: 
234
1234
DEPARTMENT CODE 
1
DOCUMENT NUMBER REV 
P1V05_PCH_STBY 
PVNN_PCH_STBY 
OUT 
OUT 
PVNN_PCH_STBY 
123 OF 270 
Wed Feb 08 16:35:03 2017 
VCCPRIM_AVID_SENSE 
VCCPRIM_AVID_QAT_SENSE 
VCCPRIM_AVID<0> VCCPRIM_AVID<1> VCCPRIM_AVID<2> VCCPRIM_AVID<3> VCCPRIM_AVID<4> 
VCCPRIM_AVID<5> VCCPRIM_AVID<6> VCCPRIM_AVID<7> VCCPRIM_AVID<8> VCCPRIM_AVID<9> VCCPRIM_AVID<10> VCCPRIM_AVID<11> VCCPRIM_AVID<12> VCCPRIM_AVID<13> VCCPRIM_AVID<14> VCCPRIM_AVID<15> VCCPRIM_AVID<16> VCCPRIM_AVID<17> 
VCCPRIM_AVID<18> VCCPRIM_AVID<19> VCCPRIM_AVID<20> VCCPRIM_AVID<21> VCCPRIM_AVID<22> VCCPRIM_AVID<23> VCCPRIM_AVID<24> VCCPRIM_AVID<25> VCCPRIM_AVID<26> VCCPRIM_AVID<27> VCCPRIM_AVID<28> VCCPRIM_AVID<29> VCCPRIM_AVID<30> 
VCCPRIM_AVID<31> 
VCCPRIM_AVID<32> VCCPRIM_AVID<33> VCCPRIM_AVID<34> VCCPRIM_AVID<35> VCCPRIM_AVID<36> VCCPRIM_AVID<37> VCCPRIM_AVID<38> VCCPRIM_AVID<39> VCCPRIM_AVID<40> VCCPRIM_AVID<41> VCCPRIM_AVID<42> VCCPRIM_AVID<43> 
VCCPRIM_AVID<44> VCCPRIM_AVID<45> VCCPRIM_AVID<46> VCCPRIM_AVID<47> VCCPRIM_AVID<48> VCCPRIM_AVID<49> VCCPRIM_AVID<50> VCCPRIM_AVID<51> VCCPRIM_AVID<52> VCCPRIM_AVID<53> VCCPRIM_AVID<54> VCCPRIM_AVID<55> 
VCCPRIM_AVID<56> VCCPRIM_AVID<57> VCCPRIM_AVID<58> VCCPRIM_AVID<59> VCCPRIM_AVID<60> VCCPRIM_AVID<61> VCCPRIM_AVID<62> 
VCCMPHY_1P05<13> 
VSS<494> 
VSS<493> 
VSS<492> 
VSS<491> 
VSS<490> 
VSS<489> 
VSS<488> 
VSS<487> 
VSS<486> 
VSS<485> 
VSS<484> 
VSS<483> 
VSS<482> 
VSS<481> 
VSS<480> 
VSS<479> 
VSS<478> 
VSS<477> 
VSS<476> 
VSS<475> 
VSS<474> 
VSS<473> 
VSS<472> 
VSS<471> 
VSS<470> 
VSS<469> 
VSS<468> 
VSS<467> 
VSS<466> 
VSS<465> 
VSS<464> 
VSS<463> 
VSS<462> 
VSS<461> 
VSS<460> 
VSS<459> 
VSS<458> 
VSS<457> 
VSS<456> 
VSS<455> 
VSS<454> 
VSS<453> 
VSS<452> 
VSS<451> 
VSS<450> 
VSS<449> 
VSS<448> 
VSS<447> 
VSS<446> 
VSS<445> 
VSS<444> 
VSS<443> 
VSS<442> 
VSS<441> 
VSS<440> 
VSS<439> 
VSS<438> 
VSS<437> 
VSS<436> 
VSS<435> 
VSS<434> 
VSS<433> 
VSS<432> 
VSS<431> 
VSS<430> 
VSS<429> 
VSS<428> 
VSS<427> 
VSS<426> 
VSS<425> 
VSS<424> 
VSS<423> 
VSS<422> 
VSS<421> 
VSS<420> 
VSS<419> 
VSS<418> 
VSS<417> 
VSS<416> 
VSS<415> 
VSS<414> 
VSS<413> 
VSS<412> 
VSS<411> 
VSS<410> 
VSS<409> 
VSS<408> 
VSS<407> 
VSS<406> 
VSS<405> 
VSS<404> 
VSS<403> 
VSS<402> 
VSS<401> 
VSS<400> 
VSS<399> 
VSS<398> 
VSS<397> 
VSS<396> 
VSS<395> 
VSS<394> 
VSS<393> 
VSS<392> 
VSS<391> 
VSS<390> 
VSS<389> 
VSS<388> 
VSS<387> 
VSS<386> 
VSS<385> 
VSS<384> 
VSS<383> 
VSS<382> 
VSS<381> 
VSS<380> 
VSS<379> 
VSS<378> 
VSS<377> 
VSS<376> 
VSS<375> 
VSS<374> 
VSS<373> 
VSS<372> 
VSS<371> 
VSS<370> 
VSS<369> 
VSS<368> 
VSS<367> 
VSS<366> 
VSS<365> 
VSS<364> 
VSS<363> 
VSS<362> 
VSS<361> 
VSS<360> 
VSS<359> 
VSS<358> 
VSS<357> 
VSS<356> 
VSS<355> 
ROOM=SB 
LEWISBURG 10/11 PWR, GND 
LBG_CORE_QAT_EXT_D 
LBG_CORE_QAT_EXT_D 
WIWYNN CORPORATION 
10/14 
11/14 



V26 AT22 
U7C1 
AC48 
AB72 
AK61 
AB68 
AB5 
AA48 
AC45 
N35 
N38 
N46 
N5 
R38 
N68 
N9 
AE43 
P63 
R27 
U42 
R5 
R50 
R54 
T56 
R58 
R68 
T11 
T15 
T18 
T22 
T26 
T29 
T33 
T37 
T40 
AJ45 
T48 
T52 
T66 
T7 
AF50 
AG46 
U58 
V48 
V5 
V52 
W58 
V66 
V68 
W13 
W17 
W20 
W24 
AA50 
Y43 
W61 
W9 
Y22 
Y27 
Y48 
Y5 
Y52 
Y59 
Y63 
Y68 
AA26 
AA27 
AA43 
AB70 
AC11 
AC15 
AC18 
AC22 
AD58 
AC27 
AC43 
AC46 
AC52 
AC59 
AC63 
AC66 
AC7 
AD5 
AD65 
AD68 
AE29 
J18 
AE48 
AE52 
AE56 
AE59 
AE63 
AE66 
AF1 
AF13 
AF5 
AF9 
AF17 
AF24 
AF3 
AF68 
AG26 
AG30 
AG41 
AG43 
AG52 
AG56 
AG59 
AG66 
AH20 
AJ11 
AJ32 
AJ56 
AK30 
AJ15 
AJ18 
AJ22 
AJ26 
AJ30 
AJ34 
AJ36 
AJ37 
AJ39 
AJ41 
AJ5 
AJ52 
AJ59 
AJ66 
AJ7 
AK26 
AK41 
AK46 
AK48 
AK58 
AK69 
AK71 
AL22 
AL5 
AL52 
AL59 
IC 
H91415-002 
AJ68 
AN20 
AN17 
AL68 
AL70 
AL72 
AM26 
AM30 
AM41 
AM46 
AN13 
AN68 
AP22 
AN5 
AN58 
AN9 
AP2 
AP26 
AP30 
AP4 
AP41 
AP46 
AP52 
AP66 
AR5 
AR50 
AR58 
AR65 
AR68 
AR70 
AR72 
AT7 
AT11 
AT15 
AT18 
AT26 
AT30 
AT41 
AT46 
AT59 
AU26 
AU30 
AE22 
AU41 
AU46 
AU50 
AU54 
AU61 
AV5 
AV22 
AV59 
AV68 
AW9 
AW13 
AW17 
AW26 
AW30 
AW32 
AW34 
AW36 
AW37 
AW39 
AW41 
AW46 
AW50 
AW58 
AW61 
AY5 
AY22 
AY56 
AY63 
AY68 
BA50 
BA54 
BA58 
BB5 
BB7 
BB11 
BB15 
BB18 
BB22 
BB44 
BB59 
BB66 
BB68 
BB70 
BB72 
BC69 
BC71 
BD24 
BD27 
BD31 
BD35 
BD5 
BD50 
BD54 
BD68 
BE29 
BE33 
BE37 
BE56 
BE59 
BE63 
BE66 
BF13 
BF17 
BF54 
BG44 
BF20 
BF24 
BF27 
BF38 
BF42 
BF5 
BF50 
BF58 
BF61 
BF65 
BF68 
BF9 
BG33 
BG48 
BG59 
BG63 
BH27 
BH38 
BH42 
BH46 
BH54 
BJ1 
BJ11 
BJ5 
BJ7 
BJ15 
BJ18 
BJ26 
BJ3 
BJ33 
BJ52 
BJ68 
IC 
H91415-002 
U7C1 
BU9 
BW52 
BK24 
BK27 
BK31 
BK35 
BK38 
BK42 
BK50 
BL22 
BL40 
BL68 
BL37 
BL5 
BL63 
BL70 
BL72 
BM13 
BM17 
BN37 
BM46 
BM50 
BM58 
BM69 
BM71 
BM9 
BN22 
BN59 
BN5 
BN52 
BN66 
BR20 
BR50 
BT8 
BR54 
BR58 
BR6 
BT66 
BU13 
BU11 
BV49 
BU15 
BU18 
BU20 
BU22 
BU24 
BU26 
BU28 
BU30 
BU32 
BU34 
BU37 
BU39 
BU41 
BU43 
BU45 
BU48 
BU50 
BU52 
BU54 
BU57 
BU59 
BU61 
BU63 
BV40 
BW15 
BW18 
BW26 
BY40 
BY49 
CA15 
CA18 
CA26 
CA50 
CA52 
IC 
H91415-002 
U7C1 
DO NOT SCALE DRAWING SHEET 
B
AA
B
B
SIZE 
SCALE: 
234
1234
DEPARTMENT CODE 
1
DOCUMENT NUMBER REV 
124 OF 270 
Wed Feb 08 16:35:04 2017 
VSS<354> 
VSS<353> 
VSS<352> 
VSS<351> 
VSS<350> 
VSS<349> 
VSS<348> 
VSS<347> 
VSS<346> 
VSS<345> 
VSS<344> 
VSS<343> 
VSS<342> 
VSS<341> 
VSS<340> 
VSS<339> 
VSS<338> 
VSS<337> 
VSS<336> 
VSS<335> 
VSS<334> 
VSS<333> 
VSS<332> 
VSS<331> 
VSS<330> 
VSS<329> 
VSS<328> 
VSS<327> 
VSS<326> 
VSS<325> 
VSS<324> 
VSS<323> 
VSS<322> 
VSS<321> 
VSS<320> 
VSS<319> 
VSS<318> 
VSS<317> 
VSS<316> 
VSS<315> 
VSS<314> 
VSS<313> 
VSS<312> 
VSS<311> 
VSS<310> 
VSS<309> 
VSS<308> 
VSS<307> 
VSS<306> 
VSS<305> 
VSS<304> 
VSS<303> 
VSS<302> 
VSS<301> 
VSS<300> 
VSS<299> 
VSS<298> 
VSS<297> 
VSS<296> 
VSS<295> 
VSS<294> 
VSS<293> 
VSS<292> 
VSS<291> 
VSS<290> 
VSS<289> 
VSS<288> 
VSS<287> 
VSS<286> 
VSS<285> 
VSS<284> 
VSS<283> 
VSS<282> 
VSS<281> 
VSS<280> 
VSS<279> 
VSS<278> 
VSS<277> 
VSS<276> 
VSS<275> 
VSS<274> 
VSS<273> 
VSS<272> 
VSS<271> 
VSS<270> 
VSS<269> 
VSS<268> 
VSS<267> 
VSS<266> 
VSS<265> 
VSS<264> 
VSS<263> 
VSS<262> 
VSS<261> 
VSS<260> 
VSS<259> 
VSS<258> 
VSS<257> 
VSS<256> 
VSS<255> 
VSS<254> 
VSS<253> 
VSS<252> 
VSS<251> 
VSS<250> 
VSS<249> 
VSS<248> 
VSS<247> 
VSS<246> 
VSS<245> 
VSS<244> 
VSS<243> 
VSS<242> 
VSS<241> 
VSS<240> 
VSS<239> 
VSS<238> 
VSS<237> 
VSS<236> 
VSS<235> 
VSS<234> 
VSS<233> 
VSS<232> 
VSS<231> 
VSS<230> 
VSS<229> 
VSS<228> 
VSS<227> 
VSS<226> 
VSS<225> 
VSS<224> 
VSS<223> 
VSS<222> 
VSS<221> 
VSS<220> 
VSS<219> 
VSS<218> 
VSS<217> 
VSS<216> 
VSS<215> 
VSS<214> 
VSS<213> 
VSS<212> 
VSS<211> 
VSS<210> 
VSS<209> 
VSS<208> 
VSS<207> 
VSS<206> 
VSS<205> 
VSS<204> 
VSS<203> 
VSS<202> 
VSS<201> 
VSS<200> 
VSS<199> 
VSS<198> 
VSS<197> 
VSS<196> 
VSS<195> 
VSS<194> 
VSS<193> 
VSS<192> 
VSS<191> 
VSS<190> 
VSS<189> 
VSS<188> 
VSS<187> 
VSS<186> 
VSS<185> 
VSS<184> 
VSS<183> 
VSS<182> 
VSS<181> 
VSS<180> 
VSS<179> 
VSS<178> 
VSS<177> 
VSS<176> 
VSS<175> 
VSS<174> 
VSS<173> 
VSS<172> 
VSS<171> 
VSS<170> 
VSS<169> 
VSS<168> 
VSS<167> 
VSS<166> 
VSS<165> 
VSS<164> 
VSS<163> 
VSS<162> 
VSS<161> 
VSS<160> 
VSS<159> 
VSS<158> 
VSS<157> 
VSS<156> 
VSS<155> 
VSS<154> 
VSS<153> 
VSS<152> 
VSS<151> 
VSS<150> 
VSS<149> 
VSS<148> 
VSS<147> 
VSS<146> 
VSS<145> 
VSS<144> 
VSS<143> 
VSS<142> 
VSS<141> 
VSS<140> 
VSS<139> 
VSS<138> 
VSS<137> 
VSS<136> 
VSS<135> 
VSS<134> 
VSS<133> 
VSS<132> 
VSS<131> 
VSS<130> 
VSS<129> 
VSS<128> 
VSS<127> 
VSS<126> 
VSS<125> 
VSS<124> 
VSS<123> 
VSS<122> 
VSS<121> 
VSS<120> 
VSS<119> 
VSS<118> 
VSS<117> 
VSS<116> 
VSS<115> 
VSS<114> 
VSS<113> 
VSS<112> 
VSS<111> 
VSS<110> 
VSS<109> 
VSS<108> 
VSS<107> 
VSS<106> 
VSS<105> 
VSS<104> 
VSS<103> 
VSS<102> 
VSS<101> 
VSS<100> VSS<99> 
VSS<98> 
VSS<97> 
VSS<96> 
VSS<95> 
VSS<94> 
VSS<93> 
VSS<92> 
VSS<91> 
VSS<90> 
VSS<89> 
VSS<88> 
VSS<87> 
VSS<86> 
VSS<85> 
VSS<84> 
VSS<83> 
VSS<82> 
VSS<81> 
VSS<80> 
VSS<79> 
VSS<78> 
VSS<77> 
VSS<76> 
VSS<75> 
VSS<74> 
VSS<73> 
VSS<72> 
VSS<71> 
VSS<70> 
VSS<69> 
VSS<68> 
VSS<67> 
VSS<66> 
VSS<65> 
VSS<64> 
VSS<63> 
VSS<62> 
VSS<61> 
VSS<60> 
VSS<59> 
VSS<58> 
VSS<57> 
VSS<56> 
VSS<55> 
VSS<54> 
VSS<53> 
VSS<52> 
VSS<51> 
VSS<50> 
VSS<49> 
VSS<48> 
VSS<47> 
VSS<46> 
VSS<45> 
VSS<44> 
VSS<43> 
VSS<42> 
VSS<41> 
VSS<40> 
VSS<39> 
VSS<38> 
VSS<37> 
VSS<36> 
VSS<35> 
VSS<34> 
VSS<33> 
VSS<32> 
VSS<31> 
VSS<30> 
VSS<29> 
VSS<28> 
VSS<27> 
VSS<26> 
VSS<25> 
VSS<24> 
VSS<23> 
VSS<22> 
VSS<21> 
VSS<20> 
VSS<19> 
VSS<18> 
VSS<17> 
VSS<16> 
VSS<15> 
VSS<14> 
VSS<13> 
VSS<12> 
VSS<11> 
VSS<10> 
VSS<9> 
VSS<8> 
VSS<7> 
VSS<6> 
VSS<5> 
VSS<4> 
VSS<3> 
VSS<2> 
VSS<1> 
VSS<0> 
ROOM=SB 
LEWISBURG 11/11 GND 
LBG_CORE_QAT_EXT_D LBG_CORE_QAT_EXT_D LBG_CORE_QAT_EXT_D 
WIWYNN CORPORATION 
12/14 13/14 14/14 



10.0K 
RMII_BMC_PCH_SPRNGVLLE_RXER 
FM_USB_P0_EN_BOOT_BIOS_STRAP_N 
SPI_PCH_IO2 
PU_PCH_TLS_ENABLE_STRAP 
FM_UV_ADR_TRIGGER_EN 
FM_FLASH_DESC_OVERRIDE 
SPI_PCH_MOSI 
PU_ADR_TIMER_HOLD_OFF_N 
RMII_PCH_SPRNGVLLE_ARB_OUT 
SPI_PCH_IO3 
1.00K 
R2T1 
G21796-026 
EMPTY 
1% 
1/16W 
1
2
0402 
0402 
1
1/16W 
EMPTY 
G21796-072 
2
1% 
R2U30 
4.75K 
G21796-016 
R8D13 
1/16W 
EMPTY 
1
2
1% 
0402 
G21796-026 
EMPTY 
1/16W 
1.00K 
1% 2
1
0402 
R7D1 
0402 
G21796-016 
CHIP 
1/16W 
1% 
R8D16 
2
1 10.0K 
1/16W 
1.00K 
R2N14 
2
0402 
G21796-026 
EMPTY 
1
1% 
1.00K 
1/16W 
G21796-026 
EMPTY 
R3N17 
1% 
1
2
0402 
2 EMPTY 
G21796-072 
1/16W 
0402 
1
1% 
4.75K 
R3N2 
G21796-345 
1/16W 
1% 
8.2K 
R7D13 
0402 
EMPTY 
G21796-026 
0402 
R8D5 
2
1 1.00K 
1% 
1/16W 
EMPTY 
0402 
1/16W 
R8C17 
EMPTY 
1.00K 
2
1
1% 
G21796-026 
CHIP 
G21796-026 
2
0402 
R8C18 
1
1% 
1/16W 
1.00K G21796-026 
0402 
EMPTY 
1.00K 
R8E4 
2
1% 
1
1/16W 
G21796-026 
0402 
EMPTY 
1/16W 
2
1
1% 
1.00K 
R8E6 
1.00K 
0402 
2
1/16W 
EMPTY 
1
1% 
R2R11 
G21796-026 
121 147 
119 176 
111 121 154 
108 119 
119 144 191 
147 121 
111 121 154 184 
120 
121 139 
121 154 
DESIGN NOTE: 
DESIGN NOTE: 
DESIGN NOTE: 
DESIGN NOTE: 
DESIGN NOTE: 
DESIGN NOTE: 
DESIGN NOTE: 
DESIGN NOTE: 
DESIGN NOTE: 
DESIGN NOTE: 
NORMAL UV ADR TRIGGER ENABLE FUNCTIONALITY RESUMES AFTER PLTRST# DEASSERTS 
DO NOT SCALE DRAWING SHEET 
B
AA
B
B
SIZE 
SCALE: 
234
1234
DEPARTMENT CODE 
1
DOCUMENT NUMBER REV 
P3V3_STBY 
OUT 
P3V3_STBY 
OUT 
P3V3_STBY 
P3V3_STBY 
OUT 
OUT 
P3V3_STBY 
OUT 
BI 
P3V3_STBY 
OUT 
P3V3_STBY 
P3V3_STBY 
P3V3_STBY 
OUT 
OUT 
OUT 
125 OF 270 
Wed Feb 08 16:35:04 2017 
TP FAB1 NOPOP RES 0106 
TP FAB1 NOPOP R2U30 0111 
TP FAB1 NOPOP RES 0108 
TP FAB1 SET TO 1 
(TP FAB1 NOT INTERNAL PD 0203) 
TP FAB1 NOPOP RES 20160421 
PCH STRAPS (1/2) 
GBE AUX POWER IS ENABLED WHEN HIGH (DEFAULT) 
GBE DEBUG MODE IS DISABLED WHEN LOW (DEFAULT) 
PCH HAS INTERNAL PULL-DOWN 
NO REBOOT DISABLED WHEN LOW (DEFAULT) 
TLS DISABLED WHEN LOW 
LBG EDS R1.0: PCH INTERNAL PU 0108 
ADR TIMER HOLD OFF ENABLED WHEN LOW 
ADR TIMER HOLD OFF DISABLED WHEN HIGH (DEFAULT) 
BOOT SPI WHEN LOW (DEFAULT) 
BOOT LPC/ESPI WHEN HIGH 
GBE AUX POWER IS DISABLED WHEN LOW 
PCH INTERNAL PULL-DOWN. 
CONSENT STRAP DISABLED WHEN HIGH (DEFAULT) 
FLASH DESC OVERRIDE ENABLED WHEN LOW (DEFAULT) 
GBE DEBUG MODE IS ENABLED WHEN HIGH 
BOOT HALT DISABLE WHEN HIGH (DEFAULT) 
PCH INTERNAL PULL-UP. 
PCH INTERNAL PULL-UP. 
NO REBOOT ENABLED WHEN HIGH 
PCH INTERNAL PULL-DOWN. 
PCH INTERNAL PULL-DOWN. 
TLS ENABLED WHEN HIGH (DEFAULT) 
PERSONALITY STRAP ENABLE WHEN LOW (DEFAULT) 
PCH INTERNAL PULL-UP. 
PCH HAS INTERNAL PULL-DOWN 
CONSENT STRAP ENABLED WHEN LOW 
FLASH DESC OVERRIDE DISABLED WHEN HIGH 
BOOT HALT ENABLED WHEN LOW 
PERSONALITY STRAP DISABLE WHEN HIGH 
BOM_COST=SB 
ROOM=SB 
WIWYNN CORPORATION 
GBE DEBUG ENABLE 
BOOT HALT 
NO REBOOT 
ADR TIMER OFF FLASH DESCRIPTOR 
OVERRIDE 
GBE AUX POWER 
TLS CONFIDENTIALITY 
BOOT BIOS DEVICE 
PERSONALITY STRAP 
CONSENT STRAP 
1
1
1
0
0
1
1
00
0



4.75K 
RST_RSMRST_DLY 
FM_PCH_BMC_THERMTRIP_EXI_STRAP_N 
FM_FLASH_ATTACH_CFG_STRAP 
IRQ_SML0_ALERT_N 
FM_OC_DETECT_EN_N 
1
2
1/16W 
0402 
1% 
1.00K 
R7D19 
EMPTY 
G21796-026 
4.75K 
1% 
1/16W 
2
0402 
G21796-072 
EMPTY 
1
R2N10 
1
2
1/16W 
0402 
1% 
1.00K 
G21796-026 
R3P64 
EMPTY 
1
2
0402 
1% 
4.75K 
R3P62 
1/16W 
EMPTY 
G21796-072 
0402 
1
2
1/16W 
CHIP 
1% 
G21796-072 
R8C9 
3
2
1 FET 
2N7002 
C79254-001 
Q8E2 
1
2
0402 
1% 
G21796-072 
1/16W 
4.75K 
R1D35 
CHIP 
190 
119 134 
120 
119 146 
120 145 200 
S
D
G
DESIGN NOTE: 
DESIGN NOTE: DESIGN NOTE: 
DESIGN NOTE: 
DO NOT SCALE DRAWING SHEET 
B
AA
B
B
SIZE 
SCALE: 
234
1234
DEPARTMENT CODE 
1
DOCUMENT NUMBER REV 
P3V3_STBY 
OUT 
P3V3_STBY 
OUT 
P3V3_STBY 
IN 
OUT 
P3V3_STBY 
OUT 
126 OF 270 
Wed Feb 08 16:35:04 2017 
TP FAB1 NOPOP R2N10 0108 
CHANGE TO 1M FOR DCI FUNCTIONALITY (REAR USB3 DISABLED) 
PCH INTERNAL PULL-DOWN 
MASTER ATTACHED FLASH WHEN LOW (DEFAULT) 
SLAVE ATTACHED FLASH WHEN HIGH 
INTERNAL PULL DOWN DISABLED AFTER RSMRST# DEASSERTS
LT KEY DOWNGRADE ENABLED WHEN LOW 
PCH INTERNAL PULL-UP 
NORMAL OC DETECT ENABLE FUNCTIONALITY RESUMES AFTER RSMRST# DEASSERTS 
LT KEY DOWNGRADE DISABLED WHEN HIGH (DEFAULT) 
NORMAL SML ALERT# FUNCTIONALITY RESUMES AFTER RSMRST# DEASSERTS 
PCH INTERNAL PULL-DOWN 
LPC WHEN LOW (DEFAULT) 
ESPI WHEN HIGH 
DCI ENABLED WHEN LOW (DEFAULT), DCI DISABLED WHEN HIGH 
REAR USB3 PORT ENABLED BY DEFAULT (DCI DISABLED) 
PCH INTERNAL PULL-DOWN, DISABLED AFTER STRAP SAMPLING 
PCH STRAPS (2/2) 
WIWYNN CORPORATION 
DCI ENABLE 
BIOS FLASH ATTACHMENT 
LT KEY DOWNGRADE 
CONFIGURATION 
ESPI OR LPC 
0
0
0
1



X6S 
1.0UF 
10% 
6.3V 
0603LF 
1C3M21 
D97712-004 
1.0UF 
10% 
0402V 
6.3V 
X6S 
1
2
C3M19 
D97712-004 
10% 
0402V 
6.3V 
X6S 
2
C3M17 
E15431-001 
10UF 
20% 
0603LF 
4V 
X6S 
1
2
C3M18 
E15431-001 
10UF 
20% 
0603LF 
4V 
X6S 
2
1
X6S 
C3M20 
D97712-004 
1.0UF 
10% 
0402V 
6.3V 
2
1
C3M27 
D97712-004 
1.0UF 
10% 
0402V 
6.3V 
X6S 
1
2
C3M23 
E15431-001 
10UF 
20% 
0603LF 
4V 
X6S 
2
1
C3M24 
E15431-001 
10UF 
20% 
0603LF 
4V 
X6S 
2
1C3M29 
D97712-004 
1.0UF 
10% 
0402V 
6.3V 
X6S 
2
1
120 
FB3M1 
693286-027 
SM 
FB 
21
X6S 
C2M25 
D97712-004 
1.0UF 
10% 
0402V 
6.3V 
1
2
C2M6 
D97712-004 
1.0UF 
10% 
0402V 
6.3V 
X6S 
1
2
C2M8 
D97712-004 
1.0UF 
0402V 
X6S 
1
2
0.022UH 
L2M1 
721891-082 
SMT IND 
21
FB2M2 
693286-027 
120 
SM 
FB 
21
C2N5 
D97712-004 
1.0UF 
10% 
0402V 
6.3V 
X6S 
1
2
C2N6 
E15431-001 
10UF 
20% 
4V 
X6S 
2
1
C3M31 
D97712-004 
1.0UF 
10% 
0402V 
6.3V 
X6S 
1
2
FB3M4 
693286-027 
120 
SM 
FB 
21
C2M9 
D97712-004 
1.0UF 
10% 
0402V 
6.3V 
X6S 
1
2 2 E15431-001 
0603LF 
20% 
C2M10 
10UF 
4V 
X6S 
1
693286-027 
FB2M1 
120 
SM 
FB 
21
C2M7 
D97712-004 
1.0UF 
10% 
0402V 
6.3V 
X6S 
1
2
C2M5 
E15431-001 
10UF 
20% 
0603LF 
4V 
X6S 
2
1
C3M30 
D97712-004 
1.0UF 
10% 
0402V 
6.3V 
X6S 
1
2
FB3M3 
693286-027 
120 
SM 
FB 
21
C3M22 
D97712-004 
1.0UF 
10% 
0402V 
6.3V 
1
2
FB3M2 
693286-027 
120 
SM 
FB 
21
ROOM=SB_FILTER_XTAL 
ROOM=SB_FILTER_PLL1 
ROOM=SB_FILTER_PLL0 
DO NOT SCALE DRAWING SHEET 
B
AA
B
B
SIZE 
SCALE: 
234
1234
DEPARTMENT CODE 
1
DOCUMENT NUMBER REV 
P1V05_PCH_STBY_VCCA_PLL1 
P1V05_PCH_STBY_VCCA_PLL0 
P1V05_PCH_STBY 
P1V05_PCH_STBY 
P1V05_PCH_STBY 
P1V05_PCH_STBY_KR_PLL 
P1V05_PCH_STBY P1V05_PCH_STBY_ISCLK_PLL 
P1V05_PCH_STBY_WM26_PLL P1V05_PCH_STBY 
P1V05_PCH_STBY_WM20_PLL 
P1V05_PCH_STBY_VCCA_XTAL P1V05_PCH_STBY 
P1V05_PCH_STBY 
ROOM=SB_FILTER_WM26 
ROOM=SB_FILTER_WM20 
ROOM=SB_FILTER_KR_PLL ROOM=SB_FILTER_ISCLK 
127 OF 270 
ROOM=SB 
LBG PLL FILTERS Wed Feb 08 16:35:04 2017 
WIWYNN CORPORATION 



DO NOT SCALE DRAWING SHEET 
B
AA
B
B
SIZE 
SCALE: 
234
1234
DEPARTMENT CODE 
1
DOCUMENT NUMBER REV 
128 OF 270 
Wed Feb 08 16:35:04 2017 SPARE 
WIWYNN CORPORATION 



C7B28 
A36096-155 
A36096-155 
A36096-155 
DMI_CPU0_PCH_TX_C_DN<3:0> 
C3M41 
DMI_CPU0_PCH_RX_C_DP<3:0> 
DMI_CPU0_PCH_TX_C_DP<3:0> DMI_CPU0_PCH_TX_DN<3:0> DMI_CPU0_PCH_TX_DP<3:0> 
DMI_CPU0_PCH_RX_DP<3:0> DMI_CPU0_PCH_RX_DN<3:0> DMI_CPU0_PCH_RX_C_DN<3:0> 
10% 
1 2
X7R 
0402 
0.22UF 
A36096-155 
C3N13 
A36096-155 
1 2
X7R 
0402 
10% 
0.22UF 
C3M45 
1 2
X7R 
0402 
10% 
0.22UF 
A36096-155 
A36096-155 
21
X7R 
0402 
10% 
0.22UF 
C3M44 
0.22UF 
2
10% 
0402 
C7B26 
1
X7R 
0402 
X7R 
C7B29 
A36096-155 
0.22UF 
1 2
10% 
A36096-155 
C7C1 
0.22UF 
10% 
0402 
1 2
X7R 
X7R 
0.22UF 
10% 
0402 
2
A36096-155 
1
C7C3 
A36096-155 
C3N8 
1 2
X7R 
0402 
10% 
0.22UF 
A36096-155 
1 2
X7R 
0402 
10% 
0.22UF 
C3N9 
1 2
X7R 
0402 
10% 
0.22UF 
A36096-155 
C3M37 
A36096-155 
0402 
1 2
X7R 10% 
0.22UF 
C3M40 
0402 
10% X7R 
A36096-155 
C7C2 
1 2
0.22UF 
0402 
X7R 
1 2
10% 
0.22UF 
0402 
X7R 
2
A36096-155 
C7B27 
1
10% 
0.22UF 
1
0
2
3
0
1
2
3
0
1
0
2
3
1
1
0
2
3
X7R 
1 2
0402 
10% 
0.22UF 
C7B25 
0
1
2 2
3
0
1
2
3 3
1
0
2
3
117 
29 
117 29 29 
117 117 29 
16V 
16V 
16V 
16V 
16V 
16V 
16V 
16V 
16V 
16V 
16V 
16V 
16V 
16V 
16V 
16V 
DO NOT SCALE DRAWING SHEET 
B
AA
B
B
SIZE 
SCALE: 
234
1234
DEPARTMENT CODE 
1
DOCUMENT NUMBER REV 
IN 
IN 
OUT IN 
OUT IN 
OUT 
OUT 
129 OF 270 
Wed Feb 08 16:35:05 2017 
PLACE CAPS NEAR PCH 
BOM_COST=SB 
ROOM=DMI 
CAD NOTE: 
DMI AC COUPLING 
DMI AC CAPS 
WIWYNN CORPORATION 



E15431-002 
C3N23 
X6S 
10UF 
A_PVCCRTC_EXT_CAP 
1
2 X6S 
6.3V 
0603 
20% 
10UF 
E15431-002 
C2N22 1
2 X6S 
6.3V 
0603 
20% 
10UF 
E15431-002 
C2N24 
2
1
X6S 
6.3V 
0402V 
10% 
1.0UF 
D97712-004 
C2N19 
2
1
X6S 
6.3V 
0402V 
10% 
1.0UF 
D97712-004 
C3N22 
2
1
X6S 
6.3V 
0402V 
10% 
1.0UF 
D97712-004 
C2N16 
2
1
X6S 
6.3V 
0402V 
10% 
1.0UF 
D97712-004 
C3N25 
2
1
X6S 
6.3V 
0402V 
10% 
1.0UF 
D97712-004 
C3N21 
2
1
X6S 
6.3V 
0402V 
10% 
1.0UF 
D97712-004 
C2N15 
X6S 
4V 
0603V 
20% 
22.0UF 
E15431-004 
C2M2 
X6S 
4V 
0603V 
20% 
22.0UF 
E15431-004 
C2M1 
2
1
X6S 
6.3V 
0402V 
10% 
1.0UF 
D97712-004 
X6S 
4V 
0603V 
20% 
22.0UF 
E15431-004 
C8B1 
2
1
X6S 
6.3V 
0402V 
10% 
1.0UF 
D97712-004 
C2N26 
X6S 
4V 
0603V 
20% 
22.0UF 
E15431-004 
C8B4 
X6S 
4V 
0603V 
20% 
22.0UF 
E15431-004 
C7D3 
2
1
X6S 
6.3V 
0402V 
10% 
1.0UF 
D97712-004 
C2M16 
2
1
X6S 
6.3V 
0402V 
10% 
1.0UF 
D97712-004 
C2N25 
2
1
X6S 
4V 
0603V 
20% 
22.0UF 
E15431-004 
C8B3 
X6S 
4V 
0603V 
20% 
22.0UF 
E15431-004 
C8B2 
2
1
X6S 
6.3V 
0402V 
10% 
1.0UF 
D97712-004 
C2N18 1
2 X6S 
6.3V 
0603 
20% 
10UF 
E15431-002 
C2N17 
1
2 X6S 
0603 
20% 
E15431-002 
C2N14 
X6S 
6.3V 
0603 
20% 
10UF 
E15431-002 
C2N23 1
2
0603 
20% 
10UF 
E15431-002 
C8C6 
X6S 
6.3V 
0603 
20% 
10UF 
E15431-002 
C8C5 
X6S 
6.3V 
0603 
20% 
10UF 
C8C4 
1
2 X6S 
6.3V 
0603 
20% 
10UF 
E15431-002 
C7D2 
X6S 
6.3V 
0603 
20% 
10UF 
E15431-002 
C8C3 
2
1
X7R 
16V 
0402V 
10% 
0.1UF 
A36096-030 
C3N29 
1
2 X6S 
6.3V 
0603 
20% 
10UF 
E15431-002 
C2N21 
2
1
X6S 
6.3V 
0402V 
10% 
1.0UF 
D97712-004 
C2N20 
122 
CAD NOTE: 
DESIGN NOTE: 
CAD NOTE: 
CAD NOTE: 
DESIGN NOTE: 
CAD NOTE: 
CAD NOTE: 
DESIGN NOTE: 
DESIGN NOTE: 
DESIGN NOTE: 
CAD NOTE: 
CAD NOTE: 
CAD NOTE: 
CAD NOTE: 
DO NOT SCALE DRAWING SHEET 
B
AA
B
B
SIZE 
SCALE: 
234
1234
DEPARTMENT CODE 
1
DOCUMENT NUMBER REV 
P3V3_STBY 
P3V3_STBY 
P3V3_STBY 
P3V3_STBY 
P3V3_STBY P3V3_STBY 
P3V3_STBY 
P1V8_PCH_STBY 
P1V8_PCH_STBY 
P1V8_PCH_STBY 
IN 
130 OF 270 
Wed Feb 08 16:35:05 2017 
STYLE NEAR TO PIN 
PLACE CAPS BSC 
PLACE CAP 
NEAR TO PIN. 
P3V3_DSW 
DECOUPLING CAPS 
EDGE OF THE PKG. 
PLACE CAPS ON THE 
EDGE OF THE PKG. 
PLACE CAPS ON THE 
P3V3_STBY DECOUPLING CAPS 
DECOUPLING CAPS 
P1V8_PCH_STBY 
CAP ONLY, PIN SHOULD NOT 
BE DRIVEN 
VCCRTCEXT: RTC DECOUPLING 
PLACE CAPS BSC 
STYLE NEAR TO PIN. 
PLACE CAPS ON THE 
EDGE OF THE PKG. 
STYLE NEAR TO PIN. 
PLACE CAPS BSC 
PLACE CAPS ON THE 
EDGE OF THE PKG. 
PLACE CAPS BSC 
STYLE NEAR TO PIN. 
P3V3_STBY 
DECOUPLING CAPS 
PCH DECOUPLING 1/3 
WIWYNN CORPORATION ROOM=SB_DECOUPLING BOM_COST=SB 



6.3V 
22.0UF 
0402V 
20% 
22.0UF 
X6S 
C3M42 
0402V 
2
1
X6S 
4V 
0603V 
20% 
22.0UF 
E15431-004 
C8B10 
X6S 
4V 
0603V 
20% 
22.0UF 
E15431-004 
C7B23 
X6S 
4V 
0603V 
20% 
E15431-004 
C7B20 
2
1
X6S 
4V 
0603V 
20% 
22.0UF 
E15431-004 
C2M12 
2
1
X6S 
4V 
0603V 
20% 
22.0UF 
E15431-004 
C2N10 
2
1
X6S 
4V 
0603V 
20% 
22.0UF 
E15431-004 
C2M13 
2
1
X6S 
6.3V 
0402V 
10% 
1.0UF 
D97712-004 
C2N8 
2
1
X6S 
0402V 
10% 
D97712-004 
1.0UF 
2
1
X6S 
6.3V 
0402V 
10% 
1.0UF 
D97712-004 
C3M39 
2
1
X6S 
6.3V 
0402V 
10% 
1.0UF 
D97712-004 
C2N7 
2
1
X6S 
6.3V 
0402V 
10% 
1.0UF 
D97712-004 
C3M43 
D97712-004 2
1
X6S 
6.3V 
0402V 
10% 
1.0UF 
C2N2 
2
1
X6S 
6.3V 
10% 
1.0UF 
C2N13 
D97712-004 
X6S 
4V 
0603V 
20% 
22.0UF 
E15431-004 
C7B21 
2
1
X6S 
6.3V 
10% 
1.0UF 
D97712-004 
C2M20 
1
2 X6S 
4V 
0805 
20% 
47UF 
C95333-006 
C8A13 1
2 X6S 
4V 
0805 
20% 
47UF 
C95333-006 
C2M11 1
2 X6S 
4V 
0805 
20% 
47UF 
C95333-006 
C2M17 
2
1
X6S 
6.3V 
0402V 
10% 
1.0UF 
D97712-004 
C3M38 
2
1
X6S 
6.3V 
0402V 
10% 
1.0UF 
D97712-004 
C2M19 
X6S 
4V 
0603V 
20% 
E15431-004 
C7B16 
2
1
X6S 
6.3V 
0402V 
10% 
1.0UF 
D97712-004 
C2M18 
2
1
6.3V 
0402V 
10% 
1.0UF 
D97712-004 
C2M21 
2
1
X6S 
6.3V 
0402V 
10% 
1.0UF 
D97712-004 
C2M22 
1
2 X6S 
4V 
0805 
20% 
47UF 
C95333-006 
C8B15 1
2 X6S 
4V 
0805 
20% 
47UF 
C95333-006 
C8B16 
2
1
X6S 
4V 
0603V 
20% 
22.0UF 
E15431-004 
C8B13 
X6S 
4V 
0603V 
20% 
22.0UF 
E15431-004 
C7B19 
X6S 
4V 
0603V 
20% 
22.0UF 
E15431-004 
C7B17 
2
1
X6S 
4V 
0603V 
20% 
22.0UF 
E15431-004 
C8B14 
2
1
X6S 
4V 
0603V 
20% 
22.0UF 
E15431-004 
C8B11 
2
1
X6S 
4V 
0603V 
22.0UF 
E15431-004 
C8B9 
X6S 
4V 
0603V 
20% 
22.0UF 
E15431-004 
C7B18 
X6S 
4V 
0603V 
20% 
22.0UF 
E15431-004 
C7B24 
X6S 
4V 
0603V 
20% 
22.0UF 
E15431-004 
C7B22 
X6S 
4V 
0603V 
20% 
22.0UF 
E15431-004 
C7B15 
CAD NOTE: CAD NOTE: DESIGN NOTE: 
CAD NOTE: 
DO NOT SCALE DRAWING SHEET 
B
AA
B
B
SIZE 
SCALE: 
234
1234
DEPARTMENT CODE 
1
DOCUMENT NUMBER REV 
P1V05_PCH_STBY 
P1V05_PCH_STBY 
P1V05_PCH_STBY 
P1V05_PCH_STBY 
P1V05_PCH_STBY 
P1V05_PCH_STBY 
P1V05_PCH_STBY 
P1V05_PCH_STBY 
131 OF 270 
Wed Feb 08 16:35:05 2017 
P1V05_PCH_STBY DECOUPLING CAPS PLACE CAPS BSC 
STYLE NEAR TO PIN. PLACE CAPS ON THE SECONDARY SIDE OF BGA PLACE CAPS O N THE 
EDGE OF THE PKG. 
PCH DECOUPLING 2/3 
BOM_COST=SB 
ROOM=LBG_DECOUPLING 
WIWYNN CORPORATION 



C3N10 
2
0603V 
1.0UF 
C3N19 
E15431-004 
0402V 
X6S 
4V 
20% 
22.0UF 
E15431-004 
C3N30 
X6S 
4V 
0603V 
20% 
22.0UF 
E15431-004 
C3N27 
X6S 
4V 
0603V 
20% 
22.0UF 
E15431-004 
C7C9 
2
1
X6S 
4V 
0603V 
20% 
22.0UF 
E15431-004 
C3M6 
2
1
X6S 
4V 
0603V 
20% 
22.0UF 
E15431-004 
C3L24 
2
1
X6S 
4V 
0603V 
20% 
22.0UF 
E15431-004 
C3L22 
2
1
X6S 
4V 
0603V 
20% 
22.0UF 
E15431-004 
C3L23 
2
1
X6S 
6.3V 
0402V 
10% 
1.0UF 
D97712-004 
C3N20 1
X6S 
6.3V 
0402V 
10% 
1.0UF 
D97712-004 
C3N15 
2
1
X6S 
6.3V 
0402V 
10% 
1.0UF 
D97712-004 
C3N5 
2
1
X6S 
6.3V 
0402V 
10% 
1.0UF 
C3N4 
D97712-004 
2
1
X6S 
6.3V 
0402V 
10% 
1.0UF 
D97712-004 
C3N17 
2
1
X6S 
6.3V 
0402V 
10% 
1.0UF 
D97712-004 
C3N6 
2
1
X6S 
6.3V 
0402V 
10% 
1.0UF 
D97712-004 
C3N2 
2
1
X6S 
6.3V 
0402V 
10% 
1.0UF 
D97712-004 
C3N18 
1
2 X6S 
4V 
0805 
20% 
47UF 
C95333-006 
C7A31 
2
1
X6S 
4V 
0603V 
20% 
22.0UF 
E15431-004 
C3L27 
1
2 X6S 
4V 
0805 
20% 
47UF 
C95333-006 
C7A32 
2
1
X6S 
6.3V 
0402V 
10% 
1.0UF 
D97712-004 
C3N16 
2
1
X6S 
6.3V 
0402V 
10% 
1.0UF 
D97712-004 
C3N7 C3N1 
2
1
X6S 
6.3V 
0402V 
10% 
D97712-004 
2
1
X6S 
6.3V 
0402V 
10% 
1.0UF 
D97712-004 
C3N3 
2
1
X6S 
6.3V 
0402V 
10% 
1.0UF 
D97712-004 2
1
X6S 
6.3V 
10% 
1.0UF 
D97712-004 
C2N11 
2
1
X6S 
4V 
0603V 
20% 
22.0UF 
E15431-004 
C3L26 
2
1
X6S 
6.3V 
0402V 
10% 
1.0UF 
D97712-004 
C2N12 
2
1
X6S 
6.3V 
0402V 
10% 
1.0UF 
D97712-004 
C2N4 
2
1
X6S 
6.3V 
0402V 
10% 
1.0UF 
D97712-004 
C2N3 
2
1
X6S 
6.3V 
0402V 
10% 
1.0UF 
D97712-004 
C2N9 
1
2 X6S 
4V 
0805 
20% 
47UF 
C95333-006 
C7B4 1
2 X6S 
4V 
0805 
20% 
47UF 
C95333-006 
C7A33 
X6S 
4V 
0603V 
20% 
22.0UF 
E15431-004 
C3N31 
2
1
X6S 
4V 
0603V 
20% 
22.0UF 
E15431-004 
C3M7 
X6S 
4V 
0603V 
20% 
22.0UF 
E15431-004 
C3N11 
X6S 
4V 
0603V 
20% 
22.0UF 
E15431-004 
C3N28 
X6S 
4V 
0603V 
20% 
22.0UF 
E15431-004 
C3N24 
X6S 
4V 
0603V 
20% 
22.0UF 
E15431-004 
X6S 
4V 
0603V 
20% 
22.0UF 
C3N12 
X6S 
4V 
0603V 
20% 
22.0UF 
E15431-004 
C7A36 
2
1
X6S 
4V 
0603V 
20% 
22.0UF 
E15431-004 
C3L25 
CAD NOTE: 
CAD NOTE: 
DESIGN NOTE: 
DESIGN NOTE: CAD NOTE: 
DO NOT SCALE DRAWING SHEET 
B
AA
B
B
SIZE 
SCALE: 
234
1234
DEPARTMENT CODE 
1
DOCUMENT NUMBER REV 
PVNN_PCH_STBY 
PVNN_PCH_STBY 
PVNN_PCH_STBY 
PVNN_PCH_STBY 
PVNN_PCH_STBY 
PVNN_PCH_STBY 
PVNN_PCH_STBY 
PVNN_PCH_STBY 
132 OF 270 
Wed Feb 08 16:35:05 2017 
PLACE CAPS BSC 
STYLE NEAR TO PIN. 
PVNN_PCH_STBY DECOUPLING CAPS 
PVNN_PCH_STBY DECOUPLING CAPS PLACE CAPS ON THE SECONDARY SIDE OF BGA 
EDGE OF THE PKG. 
PLACE CAPS ON THE 
PCH DECOUPLING 3/3 
ROOM=SB_DECOUPLING BOM_COST=SB WIWYNN CORPORATION 



2 R8B23 
FM_OCP_MEZZA_PRES 
G21796-016 
FM_BMC_READY_N 
G21796-072 
FM_TPM_PRES_N 
0402 
CHIP 1/16W 
R8E3 
2
G21796-072 CHIP 1% 
1
1/16W 4.75K 
0402 1% 
21
4.75K 
R7D6 
1/16W 
1.00K 
IRQ_LPC_SERIRQ_N 
1
R3P5 
1/16W 
FM_SLT_CFG1 
FM_CPU1_RC_ERROR_N 
FM_PCH_PRSNT_N 
FM_SINT_PRSNT_N 
FM_WBG_PRSNT_N 
PU_LPC_CLKRUN_N 
IRQ_PIRQA_SPI_TPM_N 
PU_LPC_PME_N 
PU_IRQ_PCH_SCI_WHEA_N 
PU_IRQ_VRALERT_N 
FM_BIOS_POST_CMPLT_N 
IRQ_BMC_PCH_SCI_LPC_N 
FM_CPU1_RC_EN 
FM_THROTTLE_N 
IRQ_BMC_PCH_SMI_LPC_N 
FM_SLT_CFG0 
FM_PCH_PLD_DATA 
IRQ_HSC_FAULT_N 
FM_XRC_PRESENT_N 
FM_XRC_READY_N 
PWRGD_SYS_PWROK 
PWRGD_PCH_PWROK 
IRQ_PCH_NIC_ALERT_N 
FM_BIOS_SMI_ACTIVE_N 
FM_CPU0_RC_EN 
FP_PWR_ID_LED_N 
PU_10GBE_LOM_PCI_DISABLE_N 
IRQ_BOARD_BMC_ALERT_N 
FM_CPU0_RC_ERROR_N 
FM_OCP_MEZZB_PRES_1V05_PCH_N 
FM_PRSNT_2_6_N 
FM_PRSNT_2_5_N 
FM_PRSNT_2_4_N 
FM_PRSNT_2_3_N 
FM_PRSNT_2_2_N 
FM_OCP_MEZZC_PRES_1V05_PCH_N 
FM_PRSNT_2_1_N 
0402 
G21796-026 2
R3P7 
1% 
1
1.00K 1/16W EMPTY 
R3N16 
G21796-026 
0402 1.00K 
1 2
1/16W EMPTY 1% 
2 G21796-026 
0402 EMPTY 1/16W 
R3N15 
1.00K 
1
1% 
R3P6 
0402 EMPTY 
2
1.00K 
G21796-026 1
1/16W 1% 
2
1% 
1
0402 1.00K 1/16W EMPTY 
G21796-026 
R3P53 
4.75K 
1/16W 
0402 
G21796-072 CHIP 1% 
0402 
CHIP 
10.0K 
1/16W 
1% 
G21796-016 R8D44 
21
CHIP 
1% 0402 
21
R2P22 G21796-016 
10.0K 
1/16W 
1
R7D44 
0402 
G21796-072 1/16W 1% CHIP 
24.75K 
1/16W 1.5K 0402 CHIP G21796-003 
2
R2N29 
1
1% 
R2M8 
1 2
0402 1/16W CHIP G21796-003 1% 1.5K 
CHIP 
1% 4.75K 
1/16W 0402 
G21796-072 
2
R2N32 
1
CHIP G21796-072 1% 1/16W 
R8C25 
14.75K 0402 2
1% 1.00K 1/16W 
1
R7D2 
CHIP 0402 G21796-026 
2
1/16W 
R7D7 
1.00K 1% G21796-026 CHIP 0402 
G21796-072 
0402 
CHIP 1% 
R8C7 
21
1/16W 
4.75K 
G21796-072 
R8C1 
4.75K 
1/16W CHIP 
0402 
1% 
21
1
0402 CHIP 1/16W 
G21796-026 R3P8 
1.00K 
2
1% 
2
R2N7 
10402 
1/16W G21796-072 CHIP 
4.75K 
1% 
G21796-072 CHIP 
0402 
R8B31 
4.75K 
1/16W 1% 
21
1/16W CHIP 
R8C2 
1
G21796-072 
24.75K 0402 
1% 
CHIP 
G21796-072 4.75K 
1% 
2
R8C6 0402 1
1/16W 
0402 
1% 
CHIP 1/16W 
G21796-072 
R8D14 
21
4.75K 
CHIP 
0402 
10.0K 
G21796-016 
R7C5 
1/16W 
1% 
2
1
R7C8 
10.0K 
G21796-016 
1/16W 
1% 
CHIP 
1
2
0402 
R7B6 
10.0K 
1% 
1/16W 
1
G21796-016 
CHIP 2
0402 
CHIP G21796-026 
2
R8C4 
0402 
1% 
1
1/16W 
1.00K 
1/16W 
G21796-026 
1% 1.00K 
2
CHIP 0402 
1
R2M4 
CHIP 1/16W 
G21796-026 2
0402 1% 
1
R8B30 
1.00K 
G21796-026 
1% 0402 1/16W CHIP 
21
1/16W 
10.0K 1% 
G21796-016 
2
0402 
CHIP 
R2N9 
1
CHIP 0402 
2
1.00K 
G21796-026 1
R2R5 
1/16W 1% 
0402 
G21796-016 
2
CHIP 
1% 
1
R2N16 
10.0K 
1/16W 
G21796-016 0402 CHIP 1/16W 1% 10.0K 
2
R7D4 
1
R7D3 
1% 
1
CHIP G21796-072 4.75K 0402 
2
1% 10.0K CHIP 0402 
R7D12 
21
PU_FM_RCIN_N 
1/16W CHIP 0402 G21796-016 1% 10.0K 
R7D10 
1 2
CHIP 
R7D8 
2
1/16W G21796-016 0402 1% 10.0K 
1
EMPTY 1/16W 
G21796-016 R2N12 1 2
0402 1% 10.0K 
G21796-001 
1
2.0K 
CHIP 
1% 0402 
2R3N3 
1/16W 
INSTALLED WRONG DIRECTION 
TP FAB3 CHANGE RES FROM 10K TO 4.75K 1004 
250 119 146 
120 146 119 182 
249 119 146 
146 119 
108 119 147 
56 120 145 
121 191 
121 191 
121 191 
119 
184 119 
119 
119 
119 
119 146 
120 146 119 
119 190 
119 170 95 146 
120 144 119 
108 119 147 
119 190 
199 119 146 
182 119 147 
182 119 147 
191 118 144 247 
191 118 144 
120 119 145 
120 145 
120 190 
120 146 175 
120 
120 145 182 
22 118 120 
145 
250 121 
109 121 
121 
121 
121 
121 
250 121 
121 119 
DESIGN NOTE: 
TP FAB1 NOPOP RES 0307 
LBG 
WBG 
RSVD 
TP FAB1 NOPOP RES 0309 
GPIO L FAMILY IS ON P1V05_PCH_STBY 
DO NOT SCALE DRAWING SHEET 
B
AA
B
B
SIZE 
SCALE: 
234
1234
DEPARTMENT CODE 
1
DOCUMENT NUMBER REV 
OUT 
OUT 
OUT 
OUT 
OUT 
P3V3_STBY 
OUT 
OUT 
P3V3_STBY 
OUT 
P1V05_PCH_STBY 
P3V3_STBY 
OUT 
OUT 
OUT 
OUT 
OUT 
OUT 
OUT 
OUT 
OUT 
P3V3_STBY 
P3V3_STBY 
OUT 
P3V3_STBY 
OUT 
OUT 
OUT 
OUT 
OUT 
OUT 
OUT 
OUT 
OUT 
P3V3_STBY 
OUT 
P3V3_STBY 
OUT 
OUT 
P3V3_STBY 
OUT 
P3V3_STBY 
OUT 
OUT 
OUT 
OUT 
OUT 
OUT 
OUT 
OUT 
OUT 
OUT 
OUT 
133 OF 270 
Wed Feb 08 16:35:05 2017 
PIN C18 
TP FAB1 RENAME 1218 
CGC_DUT_DETECT# 
GPP_I 
GPP_G 
GPP_L 
GPP_D 
GPP_F 
COMMENT 
GPP_A 
GPP_B 
1
X
10
1
1
X
0
0
0
1
GPP_E 
GPP_H 
ROOM=SB_PU_PD 
GPP_C 
SINT_PRSNT 
PIN D8 
WBG_PRSNT 
0
LBG PULLUPS/PULLDOWNS 
PCH DETECTION 
WIWYNN CORPORATION 



FM_PCH_BMC_THERMTRIP_N 
G21796-016 
FM_PCH_LVC1_THERMTRIP_N 
C79254-001 
FM_PCH_BMC_THERMTRIP_EXI_STRAP_N 
RST_PLTRST_BUF_N FM_THERMTRIP_DLY_R 
R7C21 
10.0K 
1% 
0402 
CHIP 
1/16W 
2
1
R2P17 
G21796-072 
4.75K 
1% 
0402 
CHIP 
1/16W 
2
1
2N7002 
Q8D2 
FET 
C79254-001 
FET 
2N7002 
Q7D1 
FM_THERMTRIP_DLY 
1/16W 
R7D18 
G21796-026 
1.00K 1% 
0402 CHIP 
21
120 144 118 
119 126 
146 191 145 184 191 
S
D
G
S
D
G
DO NOT SCALE DRAWING SHEET 
B
AA
B
B
SIZE 
SCALE: 
234
1234
DEPARTMENT CODE 
1
DOCUMENT NUMBER REV 
P1V05_PCH_STBY 
OUT 
IN 
IN 
P3V3_STBY 
IN 
OUT 
134 OF 270 
Wed Feb 08 16:35:06 2017 
THERMTRIP AND FIVRBREAK 
WIWYNN CORPORATION 



ENABLE SATA <DEFAULT> HIGH 
DISABLE SATA LOW 
ENABLE PCIE_UP[7:0] 
G21796-112 
R9A13 
1
PU_KEY_CONN_PIN2_R 
FM_PCH_SATA_RAID_KEY_R 
R2P19 
10.0K 
R8D21 
FM_PCH_SATA_RAID_KEY 
1/16W 
TP_JUMPER_BLOCK_1_8 
TP_JUMPER_BLOCK_1_2 
FM_DIS_ADR_DLY 
FM_IE_DISABLE_N 
TP_JUMPER_BLOCK_1_1 
RST_BMC_SRST_N 
TP_JUMPER_BLOCK_ 1_7 
FM_CPLD_UART_CH_LOCK_N 
3
4
2
1
CONN 
D42317-002 
J9A1 
G21796-112 
1
2
CHIP 
0402 
1% 
R9A16 
2.21K 
1
J8G2 
9
11 
7
3
5
8
10 
12 
6
CONN 
4
2
C73564-003 
2
1
1/16W 
CHIP 
1% 
G21796-072 
R7D30 
4.75K 
0402 
2
1
CHIP 
1% 
1.00K 
G21796-026 
0402 
1/16W 
2
CHIP 0402 
1% 
G21796-074 
1/16W 
33.2 
2
0402 
1% 
2.21K 
R9A12 
1 1/16W 
CHIP 
2
1
1/16W 
0402 
1% 
1.00K 
R2N24 
EMPTY 
G21796-026 
1
2
1/16W 
CHIP 
0402 
1% 
10.0K 
G21796-016 
R2N23 
FM_QAT_EN_N 
2
1
1/16W 
CHIP 
1% 
0402 
G21796-016 
TP FAB4 UPDATE THE JUMPER NOTE 20170111 
TP FAB4 NOPOP J9A1 20170206 
119 
190 
120 190 118 157 145 
190 
119 
CONN12_C73564003 
DESIGN NOTE: 
DESIGN NOTE: 
DESIGN NOTE: 
CAD NOTE: 
DESIGN NOTE: 
DESIGN NOTE: 
DESIGN NOTE: 
SET TO HIGH IMPEDANCE 
IS PULLED LOW AND ALL PINS ON BMC ARE 
WHEN JUMPER IS INSTALLED ON PINS 3 AND 5, SRST# ON BMC 
BMC DISABLED WHEN JUMPER IS INSTALLED ON PINS 3 AND 5 
ADR DELAY IS DISABLED WHEN JUMPER IS INSTALLED ON PINS 10 AND 12 WILL STAY SELECTED AFTER A POWER CYCLE 
UART CHANNEL SELECTED ON THE OUTPUT OF UART MUX 
WHEN JUMPER IS INSTALLED ON PINS 7 AND 11, THE CURRENT 
UART CHANNEL LOCKED WHEN JUMPER IS INSTALLED ON PINS 7 AND 11 
DO NOT SCALE DRAWING SHEET 
B
AA
B
B
SIZE 
SCALE: 
234
1234
DEPARTMENT CODE 
1
DOCUMENT NUMBER REV 
P3V3_STBY 
OUT 
OUT 
P3V3_STBY P3V3_STBY 
P3V3_STBY 
BI 
P3V3_STBY 
OUT 
OUT 
OUT 
P3V3_STBY 
ROOM=SB 
135 OF 270 
Wed Feb 08 16:35:06 2017 
IO2 
IO1 
IO4 
IO3 
IO6 
IO4 
IO2 
IO8 
IO12 
IO10 
IO11 
IO1 
IO3 
IO5 
IO7 
IO9 
NORMAL FUNCTIONALITY 8-10 
FOURCE POWER ON 
SYSTEM BEHAVIOR JUMPER LOCATION 
1-3 
3-5 
9-11 UART CHANNEL LOCKED 
4-6 BMC PINS SET TO HIGH IMPEDANCE 
2-4 
JUMPER LOCATION SYSTEM BEHAVIOR 
NORMAL FUNCTIONALITY 
ADR DELAY DISABLED 10-12 
NORMAL FUNCTIONALITY 7-9 
SATA RAID KEY 
PLACE TO THE LEFT OF J7G2 
QAT ENABLE 
NOPOP 
TP JUMPER IS INSTALLED ON PINS 4 AND 6 FOR DISABLE IE 
LBG HEADERS (1/3) 
NORMAL (DEFAULT) 
WIWYNN CORPORATION 



NORMAL<DEFAULT> 
PASSWORD CLEAR 
BIOS USB FLASH RECOVERY MODE 
NORMAL OPERATION <DEFAULT> 
8-10 
10-12 
NORMAL<DEFAULT> 
RECOVER BIOS 
4-6 
2-4 
9-11 
3-5 
1-3 
7-9 
ROOM=SB 
ME FORCE UPDATE 
NORMAL <DEFAULT> 
33.2 
0402 
R8E14 
G21796-026 
FM_PASSWORD_CLEAR_N 
FM_BIOS_TOP_SWAP 
RST_PLTRST_TOP_SWAP 
FM_BIOS_TOP_SWAP_SPKR FM_BIOS_TOP_SWAP_SPKR_R 
FM_ME_RECOVER_N 
PD_PASSWORD_CLEAR 
PD_ME_RCVR_N 
TP_PASSWORD_CLEAR 
TP_ME_RCVR_BOOT 
PU_BIOS_RECOVER_BOOT 
PU_BIOS_USB_RECOVERY 
RST_PLTRST_N 
1
9
11 
7
3
5
8
10 
12 
6
4
2
CONN 
C73564-003 
J7G3 
CHIP 
1/16W 
2
0402 
G21796-016 
1
1% 
10.0K 
R3T14 
R7G27 
1.00K 
1% 
CHIP 
G21796-026 
0402 
1
1/16W 
2
R7G29 
1.00K 
1% 2
1/16W 
0402 
1
CHIP 
1% 
1/16W 
R2N28 
G21796-016 
10.0K 
CHIP 2
1
R8E16 
1/16W 
2 CHIP 
0402 
G21796-040 
1
1% 
20.0K 
G21796-026 
CHIP 2
1
1/16W 
0402 
1% 
1.00K 
R7G31 
2
1
3
FET 
2N7002 
C79254-001 
Q8E1 
2
1
CHIP 
0402 
1% 
4.75K 
G21796-072 
1/16W 
2 4
IC 
74HC1G126 
U8E3 
1 VCC=P3V3_STBY;GND=GND; 
A79322-001 
2
1
X7R 
16V 
0402V 
10% 
0.1UF 
A36096-030 
C8E8 
1 2
1/16W 
CHIP 0402 
R8E20 
1% 
G21796-074 
0402 
1% 
1
R7G28 
1.00K 
2
1/16W 
CHIP 
G21796-026 
1
2
1/16W 
CHIP 
0402 
1% 
10.0K 
G21796-016 
R7G26 
119 
120 136 145 157 119 175 
119 120 
120 145 157 136 
119 139 191 247 
TP_BIOS_USB_RECOVERY 
TP_BIOS_RECOVER_BOOT 
FM_BIOS_USB_RECOVERY 
FM_BIOS_TOP_SWAP 
CONN12_C73564003 
S
D
G
DESIGN NOTE: 
DESIGN NOTE: 
CAD NOTE: 
DESIGN NOTE: 
BOM NOTE: 
CAD NOTE: DESIGN NOTE: 
DESIGN NOTE: 
4 JUMPER HEADERS (IPN 634479-007) ADDED IN MOD FILE
DO NOT SCALE DRAWING SHEET 
B
AA
B
B
SIZE 
SCALE: 
234
1234
DEPARTMENT CODE 
1
DOCUMENT NUMBER REV 
OUT 
OUT OUT 
OUT 
P3V3_STBY 
IN 
IN 
P3V3_STBY 
P3V3_STBY 
OUT 
P3V3_STBY 
136 OF 270 
Wed Feb 08 16:35:06 2017 
IO6 IO4 IO2 
IO8 
IO12 IO10 IO11 
IO1 
IO3 
IO5 
IO7 
IO9 
TOP SWAP CIRCUITRY 
ME FORCE UPDATE 
NORMAL FUNCTIONALITY 
NORMAL FUNCTIONALITY 
PASSWORD CLEAR 
RECOVER BIOS 
NORMAL FUNCTIONALITY 
BIOS USB FLASH RECVRY MODE 
NORMAL FUNCTIONALITY 
SYSTEM BEHAVIOR 
1-3 
3-5 
2-4 
9-11 
7-9 
JUMPER LOCATION 
8-10 
10-12 
4-6 
PLACE CAP CLOSE TO VCC ON U8E3 
PLACE TO THE RIGHT OF BT8G1 
BIOS USB RECOVERY 
BIOS RECOVERY MODE JUMPER 
ME FW UPDATE 
PASSWORD CLEAR 
TOP SWAP OVERRIDE STRAP 
LBG HEADERS (2/3) 
WIWYNN CORPORATION 



3-5 
TRIP=11.5V(DEFAULT) 
2-4 
CLEAR RTC REGISTERS 
8-10 
10-12 
NORMAL RTC RESET (DEFAULT) 
4-6 
7-9 
1-3 
TRIP=11V 
9-11 
NORMAL<DEFAULT> 
SMBUS UART NOT PRESENT 
BMC DISABLE 
BMC ENABLE (DEFAULT) 
G21796-072 
0402 
1/16W 
G21796-016 
0402 
C73564-003 
1/16W 
4.75K 
1/16W 
CHIP 
R6W1 
1
1% 
FM_UART_PRES_N 
UV_HIGH_SET 
PD_IE_DEBUG_MODE 
R1U64 
1.00K 
G21796-016 
J9G1 
CONN 
1/16W 
10.0K 
1% 
G21796-026 
20.0K 
0402 
G21796-040 
12 
0402 
4.75K 
1% 
G21796-072 
CHIP 
11 
1
0402 
PU_SPI_BMC_BT_CS0_N 
PD_SPI_BMC_BT_CS0_N 
R25W94 
4.75K 
RST_RTCRST_N 
TP_IE_DEBUG_MODE 
TPM_SPI_BMC_WP_N 
RST_SRTCRST_N 
CHIP 
0402 
1/16W 
2
1
R7C13 
2
C3N32 
D97712-004 
1.0UF 
10% 
0402V 
6.3V 
X6S 
1
2
G21796-040 
0402 
1/16W 
R3N4 
1% 
CHIP 
1
2
0402 
2
1
CHIP 
R1U63 
1.00K 
1% 
1/16W 
G21796-026 
10.0K 
R6W2 
CHIP 
1% 
G21796-072 
0402 
1% 
CHIP 
1
2
RN8F1 
CHIP 
1/16W 
1% 
C7C19 
D97712-004 
0402V 
2 X6S 
10% 
1.0UF 
6.3V 
1
R25W154 5% 
21
G21497-005 CHIP 
0.0 
R7C10 
1/16W 
20.0K 
1% 
1
2 CHIP 
5
3
7
2
9
6
8
10 
4
1/16W 
G21796-021 
0402 
R7C11 
1.0M 
1% 
EMPTY 
119 
146 
200 
146 246 
121 
246 145 
121 
PU_UV_HIGH_SET 
PD_UV_HIGH_SET PD_RST_RTCRST_N 
SPI_BMC_BT_CS0_N 
TP_RST_RTCRST_N 
SPI_BMC_BT_WP0_N 
0402 
1/16W 
CONN12_C73564003 
2 1
CAD NOTE: 
DESIGN NOTE: 
BOM NOTE: 
DESIGN NOTE: 
DESIGN NOTE: 
DESIGN NOTE: 
4 JUMPER HEADERS ADDED (IPN 634479-007) IN MOD FILE
1
2
1
2
DO NOT SCALE DRAWING SHEET 
B
AA
B
B
SIZE 
SCALE: 
234
1234
DEPARTMENT CODE 
1
DOCUMENT NUMBER REV 
P3V3_RTC_STBY 
P3V3_RTC_STBY 
P3V3_STBY 
OUT 
OUT 
P3V3_STBY 
P3V3_STBY 
OUT 
IN OUT 
OUT 
OUT 
137 OF 270 
Wed Feb 08 16:35:07 2017 
IO6 IO4 
IO2 
IO8 
IO12 IO10 IO11 
IO1 
IO3 
IO5 
IO7 
IO9 
TP FAB3 CHANGE R6W1 0803 
TP FAB1 MOVE RES HERE 0308 
TP FAB1 MOVE RES HERE AND POP RES 0308 
TP FAB1 NOPOP RES 0227 
TP FAB1 POP RES 0301 
TP FAB1 MOVE RES HERE 0308 
CLEAR RTC REGISTERS 
NORMAL FUNCTIONALITY 2-4 
8-10 
JUMPER LOCATION 
9-11 
3-5 
7-9 
1-3 
10-12 
4-6 
TP FAB1 NOPOP RES 0301 
TP FAB1 J9G1 PIN 3&5 RESERVE TSET POINT 1203 
TP FAB1 RECONNECT PIN 1, 3, 5 0308 
SMBUS UART NOT PRESENT 
NORMAL FUNCTIONALITY 
TP FAB1 ADD RES 0308 
SYSTEM BEHAVIOR JUMPER LOCATION SYSTEM BEHAVIOR 
TRIP=11V 
BMC ENABLE (DEFAULT) 
BMC DISABLE 
TRIP=11.5V (DEAULT) 
TP FAB1 CHANGE JUMPER 8, 10, 12 FUNCTION 0308 
PLACE TO THE RIGHT OF OTHER 2X6 HEADER 
IE DEBUG 
UVP INBN 
BMC ENABLE 
CMOS CLEAR JUMPER 
ROOM=SB 
LBG HEADERS (3/3) 
WIWYNN CORPORATION 



G21796-173 
SMB_SMLINK0_STBY_LVC3_SDA 
R8C12 
SMB_HOST_STBY_LVC3_SCL 
SMB_HOST_STBY_LVC3_SDA 
SMB_BMC_PMBUS_STBY_LVC3_SDA 
SMB_SMLINK0_STBY_LVC3_SDA_R1 
SMB_SMLINK0_STBY_LVC3_SCL_R1 
SMB_LAN_STBY_LVC3_SDA_R2 
SMB_LAN_STBY_LVC3_SDA_R1 
SMB_HOST_STBY_LVC3_SCL 
SMB_BMC_PMBUS_STBY_LVC3_SCL 
SMB_LAN_STBY_LVC3_SCL 
SMB_LAN_STBY_LVC3_SDA 
SMB_OCP_FRU_STBY_LVC3_SDA 
SMB_OCP_FRU_STBY_LVC3_SCL 
SMB_VR_STBY_LVC3_SDA 
SMB_VR_STBY_LVC3_SCL 
SMB_HOST_STBY_LVC3_SDA 
SMB_HOST_STBY_LVC3_SCL_R1 
SMB_SMLINK0_STBY_LVC3_SCL 
R2U3 
665 
1.0% 
1/16W 
2 CHIP 
G21796-235 
1
0402 
665 
R2U11 
G21796-235 
1
1.0% 
1/16W 
CHIP 2
0402 
G21796-235 
665 
1.0% 
1
1/16W 
R2N5 
CHIP 
0402 
2
1.0% 
665 
G21796-235 
0402 
1/16W 
CHIP 
R2N8 
1
2
R8D15 
1.37K 
1% 
1/16W 
0402 
CHIP 
G21796-095 
1/16W 
R8D17 
1.37K 
1% 
CHIP 
0402 
G21796-095 
R2T54 
1/16W 
G21796-235 
1
1.0% 
665 
2 CHIP 
0402 
1.0% 
CHIP 
665 
1
2
1/16W 
0402 
G21796-235 
R2T53 
1/16W 
CHIP 
G21796-095 
0402 
R8W6 
1% 
1.37K 
G21796-095 
1/16W 
0402 
CHIP 
R8W7 
1.37K 
1% 
G21796-173 
1/16W 1% 0402 
2 CHIP 
R8W4 
20.0 1
20.0 
R8W5 1% 1/16W 
G21796-173 2 CHIP 
0402 
1
R2N21 0402 1/16W 1 25% CHIP 0.0 G21497-005 
G21497-005 1/16W R2N20 0402 CHIP 215% 0.0 
1/16W G21796-173 0402 CHIP 1% 2120.0 
0402 G21796-173 1% R8C11 1/16W 2120.0 CHIP 
R8C14 1% 1 0402 2 CHIP G21796-173 20.0 1/16W 
G21796-173 1% 1 0402 1/16W 2 CHIP 20.0 R8C20 
1/16W CHIP 2
R2U6 
11% 20.0 0402 
0402 G21796-173 20.0 1/16W R2U9 
1 21% CHIP 
20.0 G21796-173 2
R8D4 
11% 0402 1/16W CHIP 
2
R8D7 20.0 G21796-173 CHIP 1% 1 1/16W 0402 
EMPTY G21796-173 
1/16W 
20.0 
0402 R2U12 2
1% 
1
1/16W 20.0 1% EMPTY 
0402 R2U8 21
G21796-173 
SMB_LAN_STBY_LVC3_SCL_R2 
SMB_LAN_STBY_LVC3_SCL_R1 
SMB_VR_STBY_LVC3_SDA_R1 
SMB_VR_STBY_LVC3_SCL_R1 
SMB_HOST_STBY_LVC3_SDA_R1 
156 159 
159 101 102 111 138 156 247 
101 102 111 138 156 159 247 
159 181 199 247 
119 
119 
120 
120 
138 
159 
101 
102 
111 
156 
247 
159 181 247 199 
160 156 182 
156 160 182 
91 159 186 188 
159 91 186 188 
108 
108 
119 108 
108 119 
159 193 194 201 206 211 213 
215 218 223 226 235 
159 211 213 235 193 194 201 
206 215 218 223 226 
101 
102 
111 
138 
156 
159 
247 
119 
159 156 
120 
120 
120 
120 
119 
SMB_HOST_STBY_LVC3_SCL_R5 
SMB_HOST_STBY_LVC3_SDA_R5 
SMB_SLOTX24_PCH_STBY_LVC3_SCL 
SMB_SLOTX24_PCH_STBY_LVC3_SDA 
G21497-013 
0402 
CHIP 
3.3K 
1/16W 
5% 
R24W2 
1/16W 
CHIP 
G21497-013 
5% 
R24W1 
0402 
3.3K 
3.3K 
R8B26 
5% 
1/16W 
CHIP 
G21497-013 
0402 
R8B24 
1/16W 
3.3K 
0402 
CHIP 
G21497-013 
5% 
CAD NOTE: 
DESIGN NOTE: 
CAD NOTE: 
DESIGN NOTE: 
CAD NOTE: CAD NOTE: 
AFTER LAYOUT IS DONE 
IF CONCLUSION IS IT'S NEEDED 
WILL ADD OTHER STEERING RESISTORS 
RESISTORS ON THE SMB_OCP_FRU_STBY_LVC3_SDA/SCL SIDE
RUN TRACES THROUGH PADS ON THESE 
1
2
1
22
1
2
1
1
22
1
1
2
1
2
DO NOT SCALE DRAWING SHEET 
B
AA
B
B
SIZE 
SCALE: 
234
1234
DEPARTMENT CODE 
1
DOCUMENT NUMBER REV 
OUT 
BI 
OUT 
BI 
OUT 
BI 
OUT 
BI 
OUT 
BI 
P3V3_STBY 
P3V3_STBY 
P3V3_STBY P3V3_STBY 
OUT 
BI 
IN 
BI 
OUT 
BI 
P3V3_STBY 
P3V3_STBY 
OUT 
BI 
BI 
IN 
P3V3_STBY 
P3V3_STBY 
P3V3_STBY 
P3V3_STBY 
P3V3_STBY 
P3V3_STBY 
P3V3_STBY 
P3V3_STBY 
BI 
IN 
BI 
IN 
IN 
BI 
IN 
BI 
138 OF 270 
Wed Feb 08 16:35:07 2017 
TP FAB1 DELETE RES (NO USE IE) 0118 
BOM_COST=SM_CONTROLLER ROOM=SMBUS 
OPTION 1120 
TP FAB1 DEL RES 0309 
TP FAB1 ADD RES 0310 
TP FAB1 PUT RES BACK 0228 TP FAB1 DELETE RES (NO USE IE) 0118 
TP FAB1 CHANGE NET NAME 0310 
TP FAB1  MOVE TO PAGE 159 0314 
TP FAB1 ADD RES 0314 
PLACE RESISTORS CLOSE TO PCH 
PLACE RESISTORS CLOSE TO PCH 
ON SEPARATE PAGE 
PULL UPS FOR SENSOR BUS 
PLACE SMB RESISTORS NEAR PCH 
LBG SMBUS RESISTORS 
WIWYNN CORPORATION 



1/16W 
10.0K 
G21796-074 
0.1UF 
G21796-074 
RMII_SPRNGVLLE_BMC_PCH_RXD0 
RMII_SPRNGVLLE_BMC_PCH_RXD1 
1
R9E5 
16V 
1
PE_PCH_SPRV_RX_C_DP 
RMII_BMC_PCH_SPRNGVLLE_CRSDV 
PU_SPRV_LAN_PWR_GOOD 
XTAL_25MHZ_IN_R 
1
5.0% 0
G22178-002 
E15431-002 
0603 
6.3V R1T32 1/10W 
10.1UF 
16V 
10% 
X7R 
A36096-030 
0402V 
C1T3 
0.1UF 
6.3V 
20% 
X6S 
16V 
X7R 
E15431-002 
C1R20 C1R13 C22W34 
COG 
0402LF 
SMB_SPRINGVILLE_STBY_LVC3_SDA 
31 
LED_LAN_1_N 
25V 
PE_PCH_SPRV_TX_C_DP 
A36096-030 
FM_PE_SPRV_WAKE_N 
0.0 
0.0 
10% 
CLK_100M_SPRV_DN 
CHIP 
0402 
CHIP 
G21796-016 
R9E23 
4.99K 1
G21796-016 
G21796-074 
1% 
10.0K 
R9E13 
1% 
1.0% 
G21796-027 
2
R9F5 
3.32K 
G21796-027 
PU_SPRV_LAN_PWR_GOOD 
PD_SPRV_RSET 
33.2 
2
CHIP 
0402 
TP_SPRV_SDP2 
TP_SPRV_SDP3 
X7R 
IRQ_LOM_ALERT_N 
PU_JTAG_SPRV_TDO 
1% 
RMII_SPRNGVLLE_BMC_PCH_RXD0_R 
G21796-074 2
CHIP 
R9E19 
RMII_SPRNGVLLE_BMC_PCH_RXD1_R 
1% 
C1T4 
10UF 
6.3V 
20% 
E15431-002 
0603 
0
1
59 
P0V9_LAN_I210 
0603 
P1V5_LAN_I210 
1/10W 
G22178-002 
X6S 
0603 
10 
1/10W 
20% 
PE_PCH_SPRV_RX_DP 
SPI_NIC_CS_N 
SPI_NIC_MOSI 
SPI_NIC_CS_R_N 
1/16W 
CHIP 2
G21796-016 
0402 
0402 
1/16W 
CHIP 
G21796-016 
IRQ_LOM_ALERT_N 
SPI_NIC_SCLK 
2
20% 
C1R22 
2
1
20% 
X6S 
CLK_50M_CKMNG_SPRVLLE 
0
1
46 
16 
2
C2M23 
C1R19 
0.1UF 
16V 16V 
0.1UF 
X7R 
4V 
22.0UF 
10% 
2 A36096-030 
0402V 0402V 
A36096-030 2A36096-030 
0603 A36096-030 
0402V 0402V 
C9E5 
1
2 X7R 2 E15431-002 2 X7R 
A36096-030 
0402V 0402V 0603V 
E15431-004 
0603 
E15431-002 
0402V 
A36096-030 
0402V 
A36096-030 
X7R 2
C1R15 
0.1UF 
20% 
C1R16 
22.0UF 10UF 
C1R29 
6.3V 
C1R21 
0.1UF 
1
1
CHIP 
R1T34 
2
0.1UF 
A36096-030 
RMII_BMC_PCH_SPRNGVLLE_TXEN 
C1R17 
16V 
X7R 
0402V 
CLK_50M_CKMNG_SPRVLLE 
R1R12 
C1R26 
EMPTY 
1
R9E4 
IC 
5% 
1
Y9E1 
G21796-016 
1/16W 
PE_PCH_SPRV_RX_C_DN 
R1T1 
G21796-016 
0402 
CHIP 
1 1 C9E12 
1/16W 
10% 
1/16W 
1% 
R9E7 
CHIP 
3.32K 
0402 
1
10UF 
0603 
1
10% 
1
2
0.1UF 
16V 
2
1
X7R 
10% 
2 X7R 
10% 10% 
1
PE_PCH_SPRV_TX_DP 
RST_PLTRST_N 
PE_PCH_SPRV_TX_DN 
XTAL_25MHZ_OUT 
XTAL_25MHZ_IN_R 
2
0.1UF 
1
0402V 
X7R 
16V 
A36096-030 
C2M24 
10% 
1
0.1UF 10% C9E4 
0402V 
0402V 
X7R 
1
C9E7 
2
10% 
0402LF 
1
CHIP 
1
R1R15 0
5.0% 
CHIP 2
2
1
1% 
2
10.0K 
1% 
CHIP 2
1% 
221
CHIP 
0.0 R1R1 5% 
1
1/16W 
1% 
2
CHIP 
1/16W 
1% 
1
2
20% 
4V 
2 2
10% 
16V 
X7R 2 2
16V 
10% 
16V 
0402V 
X7R 
C1R18 
10% 
0.1UF 1
22
16V 
0.1UF 1
16V 
X7R 
1
X6S 
0603 
2
1 1% 
CHIP 
R9E9 
1
2
CHIP 
R9E20 5% 
3
0.1UF 
X6S 
1
X7R 
0402 
1
X7R 
1/16W 
CHIP 
1
R9E8 33.2 
A36096-030 
1% 
22.1 
16V 
1 2
2
22.1 
2
2
10% 
C9E6 1
A36096-030 
0402V 
0.1UF 
C1R24 
A36096-030 
10% 
16V 
0.1UF 
C1T5 
X6S 2
10% 
A36096-030 
16V 
A36096-030 
0402V 
C22W35 
10UF 1 C1R31 C1R14 
2
1
R9E18 
1
5% 
COG 
2
C9E8 
50V 
2
2
1
1% 
0402 
1/16W 
CHIP 
G21796-016 
10.0K 
RST_PLTRST_SPRV_R_N 
5% 
1
1XTAL_25MHZ_IN 
A36095-047 
50V 
15.0PF 
C9E9 
D71700-057 
5.0% 
EMPTY 
1 2
1/10W 
0603 
43 
33 
9
50 
53 
49 
52 
55 
57 
54 
58 
40 
30 
37 
63 
61 
62 
60 
4
35 
34 
36 
44 
3
5
6
15 
13 
20 
21 
32 
41 
51 
39 
47 
56 
38 
17 
24 
23 
8
2
1
18 
29 
28 
26 
IC 
EU9E1 
22 
25 
12 
7
65 
14 
64 
27 
G47144-004 
NIC_MDI_SPRV_RJ45_0_DP 
NIC_MDI_SPRV_RJ45_0_DN 
NIC_MDI_SPRV_RJ45_1_DN 
NIC_MDI_SPRV_RJ45_1_DP 
NIC_SET_N_MDI_2_DN 
NIC_SET_P_MDI_2_DP 
NIC_SER_N_MDI_3_DN 
NIC_SER_P_MDI_3_DP 
A_CBOT 
LED_LAN_0_N 
LED_LAN_2_N 
RMII_PCH_SPRNGVLLE_ARB_OUT 
RMII_BMC_PCH_SPRNGVLLE_TXEN 
SPI_NIC_MOSI_R 
SPI_NIC_SCLK_R 
CLK_100M_SPRV_DP 
PE_PCH_SPRV_TX_C_DN PE_PCH_SPRV_RX_DN 
48 PD_SPRV_RSET 
19 
0402 
TP_SPRV_SDP0 
CHIP 22 CHIP 
1/16W 
PU_JTAG_SPRV_TCK 
1% 
1
1% 
10.0K 
R9E1 
SPI_NIC_MISO 
RST_PLTRST_SPRV_R_N 
2
1
1
PU_JTAG_SPRV_TDI 
PU_JTAG_SPRV_TMS 
XTAL_25MHZ_OUT 
0402 CHIP 
RMII_BMC_PCH_SPRNGVLLE_TXD0 
RMII_BMC_PCH_SPRNGVLLE_TXD1 
10UF 
6.3V 
1 0.039UF 
0402 
G21796-016 
1
0603 
1% 
G21796-016 
0402 
C9F2 
G22178-002 
10UF 
C1R30 
45 
G22178-002 
2
5.0% 
P3V3_STBY_P1V5_LAN_I210 
11 
42 
CHIP 
1 2
R9E16 
CHIP 
1/16W 
CHIP 1/16W 
33.2 
G21796-250 
33.2 
R9F1 
1.0% 22.1 
1/16W 
RMII_PCH_SPRNGVLLE_ARB_IN_R 
RMII_BMC_PCH_SPRNGVLLE_CRSDV_R RMII_BMC_PCH_SPRNGVLLE_CRSDV 
2
0402 
RMII_PCH_SPRNGVLLE_ARB_IN 
0402 
0402 
R9E17 
1.0% 
1/16W 
2
10.0K 
1/16W 
10.0K 
R9E3 
E15431-002 
R9E2 
10.0K 
10.0K 
R9W36 
CHIP 
R9E22 
0402 
G21796-013 
1/16W 
R1T33 
25.000MHZ 
XTAL_25MHZ_OUT_R 
15.0PF 
A36095-047 
0402LF 
0603V 
E15431-004 
EMPTY 
20% 
6.3V 
SMB_SPRINGVILLE_STBY_LVC3_SCL 
FM_1GB_LOM_DISABLE_N 
A36096-063 
A_CTOP 
C9E1 1
TP FAB3-DVT CHANGE CONNECTION 20161108 
TP FAB3-DVT ADD RES R9W36 20161114 
TP FAB3-DVT CHANGE CONNECTION 20161108 
TP FAB3 CHANGE CAP 0902 
121 147 
116 
121 
139 
147 
139 
159 
141 
142 
114 
139 
139 
139 119 146 
140 
140 
139 119 
146 
140 
101 139 
147 150 121 139 
101 139 
116 
116 
119 
136 
191 
247 
116 
139 
139 
139 
141 
141 
141 
141 
141 
141 
141 
141 
141 
141 
121 125 
139 147 150 121 
114 
139 
140 
139 
139 
147 121 
147 121 
121 139 147 
121 
159 
118 
WHERE CLOAD IS THE LOAD CAPACITANCE OF THE CRYSTAL (18PF FOR D71700-031) 
GROUP=NI_I210&RJ45 
FOR -IS SKU: 
AND CSTRAY IS THE CAPACITANCE OF SOLDER PADS, TRACES AND I210 PACKAGE 
DE-POP R1T32 
WILL NEED TO RE CALCULATE THIS VALUE WHEN LAYOUT HAS BEEN DONE 
STUFF R1T33 
GROUP=NI_I210&RJ45 
GROUP=NI_I210&RJ45 
GROUP=NI_I210&RJ45 
0402 
G21796-250 
GROUP=NI_I210&RJ45 
GROUP=NI_I210&RJ45 
GROUP=NI_I210&RJ45 
GROUP=NI_I210&RJ45 G21796-250 
1/16W 
GROUP=NI_I210&RJ45 
PU_DEV_OFF_N 
GROUP=NI_I210&RJ45 
GROUP=NI_I210&RJ45 GROUP=NI_I210&RJ45 
GROUP=NI_I210&RJ45 
GROUP=NI_I210&RJ45 GROUP=NI_I210&RJ45 
GROUP=NI_I210&RJ45 
GROUP=NI_I210&RJ45 
GROUP=NI_I210&RJ45 
GROUP=NI_I210&RJ45 GROUP=NI_I210&RJ45 
GROUP=NI_I210&RJ45 
GROUP=NI_I210&RJ45 
GROUP=NI_I210&RJ45 GROUP=NI_I210&RJ45 
GROUP=NI_I210&RJ45 
0805 
NOPOP 
GROUP=NI_I210&RJ45 
22UF 
16V 
X6S 
GROUP=NI_I210&RJ45 GROUP=NI_I210&RJ45 
GROUP=NI_I210&RJ45 
G21497-005 
G21497-005 
GROUP=NI_I210&RJ45 
GROUP=NI_I210&RJ45 
GROUP=NI_I210&RJ45 
GROUP=NI_I210&RJ45 
GROUP=NI_I210&RJ45 
GROUP=NI_I210&RJ45 
GROUP=NI_I210&RJ45 
GROUP=NI_I210&RJ45 
GROUP=NI_I210&RJ45 
22UF 
GROUP=NI_I210&RJ45 
GROUP=NI_I210&RJ45 
16V 
NOPOP 
GROUP=NI_I210&RJ45 
DE-POP R1T34 
NOPOP 
20% 
X6S X6S 
22UF 
20% 
16V 
0402 
X6S 
1/16W 
0805 
20% 
DEFAULT CONFIG IS FOR -AT SKU 
C1 = C2 = 2 * [CLOAD-CSTRAY] 
TYPICAL CSTRAY IS 3PF TO 7PF 
0402 G21497-005 
1/16W 
0402 
0402 
16V 
NOPOP 
22UF 
1/16W 
0402 
0805 
20% 
0805 
GROUP=NI_I210&RJ45 
1/16W 
GROUP=NI_I210&RJ45 
GROUP=NI_I210&RJ45 
GROUP=NI_I210&RJ45 
GROUP=NI_I210&RJ45 
GROUP=NI_I210&RJ45 
GROUP=NI_I210&RJ45 
GROUP=NI_I210&RJ45 
GROUP=NI_I210&RJ45 GROUP=NI_I210&RJ45
SHUNT CAPACITORS CAN BE CALCULATED USING THE FOLLOWING EQUATION 
GROUP=NI_I210&RJ45 
GROUP=NI_I210&RJ45 
GROUP=NI_I210&RJ45 
SC22U16V5MX-4-GP 
SC22U16V5MX-4-GP 
SC22U16V5MX-4-GP 
SC22U16V5MX-4-GP 
CAD NOTE: 
DESIGN NOTE: 
DESIGN NOTE: 
CAD NOTE: 
CAD NOTE: 
CAD NOTE: 
PUT TOGETHER PUT TOGETHER 
PLACE CAPS ON PE_PCH_SPRV_RX_DP/DN 
PLACE THESE CAPS NEAR PCH 
RMII_SPNGVLLE_BMC-PCH_RXD1_R 
RMII_PCH_SPRNGVLLE_ARB_IN_R 
NETS WITHIN TWO INCHES OF SPRINGVILLE: 
PLACE SERIES RESISTORS ON THE FOLLOWING 
SPI_NIC_CS_R_N 
SPI_NIC_MOSI_R 
RMII_BMC_PCH_SPRNGVLLE_CRSDV_R 
RMII_SPRNGVLLE_BMC_PCH_RXD0_R 
SPI_NIC_SCLK_R 
NEAR THE BMC 
NEAR PCH 
PLACE THIS RESISTOR 
DO NOT SCALE DRAWING SHEET 
B
AA
B
B
SIZE 
SCALE: 
234
1234
DEPARTMENT CODE 
1
DOCUMENT NUMBER REV 
IN 
IN 
BI 
BI BI 
BI 
IN 
P1V5_LAN 
P0V9_LAN 
IN 
OUT 
IN 
OUT 
OUT 
IN 
OUT 
IN 
IN 
OUT 
IN 
IN 
OUT OUT 
OUT 
IN 
P3V3_STBY 
IN OUT 
P3V3_STBY 
OUT 
OUT 
P3V3_STBY 
P3V3_STBY 
P3V3_STBY 
OUT 
OUT 
OUT 
P3V3_STBY 
P3V3_STBY 
OUT 
OUT 
IN 
IN 
P0V9_LAN 
P1V5_LAN 
OUT 
OUT 
OUT IN 
OUT 
IN 
IN 
OUT 
BI 
BI 
BI 
BI 
OUT 
OUT 
IN 
IN 
2
2
2 1
1 2
1
1
Wed Feb 08 16:35:07 2017 
139 OF 270 
XTAL1 
SDP1_PCIE_DIS_SDP1 
SMB_CLK 
CBOT 
MDI_MINUS0_SFP_I2C_DATA 
MDI_MINUS1_SRDS_SIG_DET 
VDD0P9<1> VDD0P9<2> VDD0P9<3> MDI_PLUS3_SERP MDI_MINUS3_SERN MDI_PLUS2_SETP MDI_MINUS2_SETN MDI_PLUS1_SFP_I2C_CLK 
MDI_PLUS0_NC 
VDD1P5_OUT 
VDD3P3<4> 
VDD3P3<3> 
VDD3P3<2> 
VDD3P3<1> 
XTAL2 
VDD3P3<0> 
VDD1P5<0> VDD1P5<1> 
VDD0P9_OUT 
VDD0P9<0> 
SMB_DATA SMB_ALRT_N 
SDP3 
SDP2 
SDP0 
RSET 
PE_WAKE_N 
PE_TP PE_TN 
PE_RST_N 
PE_RP 
PE_RN 
PECLKP 
PECLKN 
NVM_SO 
NVM_SK 
NVM_SI NVM_CS_N 
NC_SI_TX_EN 
NC_SI_TXD1 
NC_SI_TXD0 NC_SI_RXD1 NC_SI_RXD0 
NC_SI_CRS_DV NC_SI_CLK_IN NC_SI_ARB_OUT 
NC_SI_ARB_IN 
NC 
LED2 LED1 LED0 
LAN_PWR_GOOD 
JTAG_TMS JTAG_TDO JTAG_TDI 
JTAG_CLK 
GND 
DEV_OFF_N 
CTOP 
TP FAB1 DEL NET 0309 
TP FAB1 CHANGE ONE 100UF CPA TO FOUR 22UF CAPS 0108TP FAB1 CHANGE ONE 100UF CPA TO FOUR 22UF CAPS 0108
ROOM NT_FABRIC 
LAN SPRINGVILLE I210 (1/3) 
SPRINGVILLE 
WIWYNN CORPORATION 



1/16W 
CHIP 
U9E1 
G21796-040 
0402 
SPI_NIC_MOSI 1
1/16W 
A36096-030 
1/16W 
EMPTY 2
C1R25 
2
0402V 
IC 
R9E6 
SPI_NIC_MISO_R SPI_NIC_MISO 
SPI_NIC_SCLK 
SPI_NIC_CS_N 
PU_NV_WP_N 
0.1UF 
16V 
1
1% 
R1R7 
20.0K 1
1% 
2
0402 
G21796-027 
CHIP 
1/16W 
R1R3 
3.32K 1
1% 
2
R1R9 
1
1% 
2
5 2
4
8
7
6
1
3
G21796-027 
PU_NV_HOLD_N 
1% 
2
33.2 
0402 
1 3.32K 
R1R6 
0402 
G21796-027 
CHIP 
1/16W 
3.32K 
H77797-001 
X7R 
10% 
0402 G21796-074 CHIP 
139 139 
139 
GROUP=NI_I210&RJ45 
GROUP=NI_I210&RJ45 
GROUP=NI_I210&RJ45 
GROUP=NI_I210&RJ45 
GROUP=NI_I210&RJ45 
GROUP=NI_I210&RJ45 
GROUP=NI_I210&RJ45 
DO NOT SCALE DRAWING SHEET 
B
AA
B
B
SIZE 
SCALE: 
234
1234
DEPARTMENT CODE 
1
DOCUMENT NUMBER REV 
OUT 
IN 
IN 
IN 
P3V3_STBY 
Wed Feb 08 16:35:07 2017 
140 OF 270 
M25PE16 
DQ1 
VSS W_N S_N RESET_N 
C
DQ0 
VCC 
LAN SPRINGVILLE I210 (2/3) 
WIWYNN CORPORATION 



GREEN 
GREEN 
YELLOW 
0402 
1/16W 
G21796-267 
1.0% 
C9G3 
470PF 
50V 
10% 
0402LF 
A36096-049 
X7R 
10% 
470PF 
150.0 
LED_LAN_1_R_N 
EMPTY 
10% 
EMPTY 
10% 
A36096-049 
NIC_MDI_SPRV_RJ45_2_R_DP 
NIC_MDI_SPRV_RJ45_0_R_DP 
NIC_MDI_SPRV_RJ45_0_R_DN 
NIC_MDI_SPRV_RJ45_1_R_DP 
G21497-005 
NIC_LED_ACT_ANODE_R 
GND_LAN_TRCT1234_C 
LED_LAN_1_N 
C9F22 
R9G1 
GND_LAN_TRCT1234_C 
NIC_MDI_SPRV_RJ45_3_R_DN 
NIC_MDI_SPRV_RJ45_3_R_DP 
NIC_MDI_SPRV_RJ45_2_R_DN 
CHIP 
0.1UF 
C9G4 
16V 
10% 10% 
16V 
1
SKT-RJ45-LED-XFOR-1-GP 
X7R 
0402LF 
NIC_MDI_SPRV_RJ45_0_DP 
NIC_MDI_SPRV_RJ45_0_DN 
NIC_MDI_SPRV_RJ45_1_DP 
NIC_MDI_SPRV_RJ45_1_DN 
GND_LAN_TRCT1234_C 
NIC_MDI_MNG_RX_DP 
NIC_SET_N_MDI_2_DN 
NIC_MDI_MNG_RX_DN 
LED_LAN_2_N 
LED_LAN_0_N 
NIC_SET_P_MDI_2_DP 
A36096-066 C9G9 
5% G21497-005 
5% R9G24 
5% R9G20 0.0 
5% 
5% R9G17 0.0 
5% 
5% 
5% G21497-005 
C9G5 1
X7S 
16V 
0402 
2 G71842-007 
1.0UF 
C9G6 
0.1UF 
A36096-030 
0402V 
1
2 X7R 
A36096-030 
0402V 
2
10% 
X7R 
2
1
1
2
0.0 5% 
CHIP 
1
1
2 X7R 
50V 
10% 
A36096-049 
0402LF 
470PF 
C9G2 
50V 
X7R 
C9G1 1
2
470PF 1
2
0402LF 
2
75 
R9G3 
1
1
75 
R9G2 
1/16W 
C9G13 10% 
C9G16 
A36096-066 4700PF C9G12 50V 
NIC_SER_P_MDI_3_DP 
NIC_SER_N_MDI_3_DN 
R9G19 
R9G22 
R9G4 
50V 
JA9G1 
A36096-049 
1.0% 
10% 
1/16W 
0402 
CHIP 
G21796-267 
CHIP 
1/16W 
1/16W 
0402 
0402 
0402 
0402 
CHIP 
CHIP 
0402 
2
2
0.0 
0.0 
0.0 
EMPTY 
R9G9 
R9G11 
R9G18 
G21497-005 
LED_LAN_2_R_N 
LED_LAN_0_R_N 
0402 
1/16W 
0402 CHIP 
1/16W 
1/16W 
0.0 
50V 
50V 10% 
A36096-066 
A36096-066 
4700PF 
50V 
0402LF 
0402LF 
EMPTY 
NIC_MDI_SPRV_RJ45_3_R_DN 
NIC_MDI_SPRV_RJ45_0_R_DP 
NIC_MDI_SPRV_RJ45_0_R_DN 
NIC_MDI_SPRV_RJ45_1_R_DN 
NIC_MDI_SPRV_RJ45_1_R_DP 
NIC_MDI_SPRV_RJ45_2_R_DN 
NIC_MDI_SPRV_RJ45_2_R_DP 
NIC_MDI_SPRV_RJ45_3_R_DP 
G21796-009 
1/16W 1% 
1/16W 
CHIP 
0402 
0402 
0.0 
G21497-005 0.0 0402 1/16W 
G21497-005 
1/16W CHIP 
CHIP 
CHIP 
CHIP 
0402LF NIC_MDI_MNG_TX_DN 
NIC_MDI_MNG_TX_DP 
0402LF 4700PF 
4700PF 
G21497-005 
G21497-005 
G21497-005 
NIC_MDI_SPRV_RJ45_1_R_DN 
141 
141 
141 
141 
141 
139 
141 
141 
141 
141 
139 
139 
139 
139 
141 
181 
139 
181 
139 
139 
139 
139 
139 
141 
141 
141 
141 
141 
141 
141 
141 
181 
181 
141 
GROUP=NI_I210&RJ45 
GROUP=NI_I210&RJ45 GROUP=NI_I210&RJ45 
GROUP=NI_I210&RJ45 
GROUP=NI_I210&RJ45 
GROUP=NI_I210&RJ45 
GROUP=NI_I210&RJ45 
GROUP=NI_I210&RJ45 
GROUP=NI_I210&RJ45 
GROUP=NI_I210&RJ45 
GROUP=NI_I210&RJ45 
GROUP=NI_I210&RJ45 
GROUP=NI_I210&RJ45 
GROUP=NI_I210&RJ45 
GROUP=NI_I210&RJ45 
GROUP=NI_I210&RJ45 
GROUP=NI_I210&RJ45 
GROUP=NI_I210&RJ45 
GROUP=NI_I210&RJ45 
GROUP=NI_I210&RJ45 
GROUP=NI_I210&RJ45 
GROUP=NI_I210&RJ45 
GROUP=NI_I210&RJ45 
STUFF ON AT 
STUFF ON AS 
2
R1 
R9 
R10 
R11 
2
1
1 2
1 2
1
1
1
1
1
R5 
R6 
R2 
R7 
R4 
R3 
L1 
1
2
R8 
L3 
L4 
L2 
1
1
2
2
2
2
2
2
1
2
DO NOT SCALE DRAWING SHEET 
B
AA
B
B
SIZE 
SCALE: 
234
1234
DEPARTMENT CODE 
1
DOCUMENT NUMBER REV 
BI 
BI 
BI 
BI 
BI 
BI 
BI 
BI BI 
BI 
BI 
BI 
BI 
BI 
BI 
BI 
OUT 
IN 
IN 
P3V3_STBY 
IN 
BI 
BI 
BI 
BI 
BI 
BI 
BI 
BI 
IN 
IN 
OUT 
IN 
OUT 
IN 
141 OF 270 
TP FAB1 CONNECT TO GND 0307 
TP DELETE RES 0307 
ROOM NT_FABRIC 
Wed Feb 08 16:35:08 2017 LAN SPRINGVILLE I210 (3/3) 
WIWYNN CORPORATION 



G21796-074 
CHIP 
FM_PE_BMC_WAKE_N FM_ALL_WAKE_N 
1/16W G21497-005 
5% 
0.0 
R8E29 
21
0402 
G21497-005 
2
1/16W 
5% 
1/16W 
FM_PE_OCP_WAKE_N 
CHIP 
G21497-005 
0402 
1/16W 
5% 
0.0 
R8E26 
21
1
0.0 
R8E27 
0.0 
FM_PE_SPRV_WAKE_N 
FM_PE_M2_WAKE_N 
FM_PE_SLOTX24_WAKE_N 
G21497-005 
2
0402 CHIP 5% 
1
CHIP 
G21497-005 
0402 
0.0 
R8E28 
VCC=P3V3_STBY;GND=GND; 
IRQ_LVC3_WAKE_N IRQ_LVC3_WAKE_R_N 
PU_TRI_STATE_EN 
1
33.2 
CHIP 
1% 
R8E17 
2
0402 1/16W 
A79322-001 
2
U8E4 
IC 
1
4
74HC1G126 
2K15R2F-1-GP 2K15R2F-1-GP 
R8E36 R8E30 
10% 
X7R 2 A36096-030 
0402V 
1 C8E5 
16V 
0.1UF 
2
1% 
G21796-072 
1
R8E23 
0402 CHIP 1/16W 
4.75K 
2
R8E21 5% 
1/16W 
1
EMPTY 0402 
146 
186 
139 
185 
108 
118 
1/16W 
2.15K OHM 
0402 
1% 
1/16W 
0402 
1% 
2.15K OHM 
DESIGN NOTE: 
CAD NOTE: 
TP FAB3 CHANGE RES 0803 
DO NOT SCALE DRAWING SHEET 
B
AA
B
B
SIZE 
SCALE: 
234
1234
DEPARTMENT CODE 
1
DOCUMENT NUMBER REV 
OUT 
P3V3_STBY 
P3V3_STBY 
P3V3_STBY 
IN 
IN 
IN 
IN 
IN 
1
1 2
2
142 OF 270 
Wed Feb 08 16:35:08 2017 
PLACE CAP CLOSE TO TRI STATE BUFFER 
ADD PULLUP NEAR X24 CONN 
PCIE WAKE TRI-STATE BUFFER 
WIWYNN CORPORATION 



1/7 
1 OF 7 
MA15 
MCS# 
MCKP 
MDQ8 
MDQ7 
MRAS# 
MWE# 
MDQ10 
MDQ11 
MA14_MACT# 
MA13 
MDM0 
MDQ12 
MDQ13 
MDQ5 
MDQ6 
MDQS0N 
MDQS0P 
MDQS1N 
MDQS1P 
MA0 
MA1 
MA12 
MA2 
MA3 
MA4 
MA5 
MA6 
MA7 
MA8 
MA9 
MBA0 
MBA1 
MBA2_MBG0 
MCKN 
MCKE 
MODT 
MDQ9 
MVREF 
MA11 
MA10 
MCAS# 
MIOZ 
MDM1 
MDQ14 
MDQ15 MA15 
MDQ0 
MDQ1 
MDQ2 
MDQ3 
MDQ4 
10% 
16V 
0.1UF 
C25W22 
X7R 
0402V 
1
2 A36096-030 
U25W4 
AST2520A1-GP-GP 
0402 
G21796-294 
1/16W 
CHIP 
1.0% 240 R1T27 
MDQ15 
151 
151 
151 
151 
151 
151 
151 
151 
151 
151 
151 
151 
151 
151 
151 
151 
151 
151 
151 
151 
151 
151 
151 
151 
151 
151 
151 
151 
151 
151 
151 
151 
151 
151 
151 
151 
151 
151 
151 
151 
151 
151 
151 
151 
151 
151 
151 
151 
151 
BMC_M_WE_N 
BMC_M_A11 
BMC_M_A10 
BMC_M_CAS_N 
BMC_M_RAS_N 
BMC_M_CLK_DP 
BMC_M_CS_N 
BMC_M_CLK_DN 
BMC_M_CKE 
BMC_M_ODT 
BMC_M_BA1 
BMC_M_BA0 
BMC_MIOZ 
BMC_M_BG0 
BMC_M_DQ15 
BMC_M_DQ14 
BMC_M_DQ13 
BMC_M_DQ12 
BMC_M_DQ11 
BMC_M_DQ10 
BMC_M_DQ9 
BMC_M_DQ8 
BMC_M_DQ1 
BMC_M_DQ0 
BMC_M_DQS0_DP 
BMC_M_DQS0_DN 
BMC_M_DQ7 
BMC_M_DQ6 
BMC_M_DQ5 
BMC_M_DQ4 
BMC_M_DQ3 
BMC_M_DQ2 
BMC_M_DQS1_DP 
BMC_M_DQS1_DN 
BMC_M_DM0 
BMC_M_DM1 
BMC_M_A12 
BMC_M_A13 
BMC_M_MACT_N 
TP_BMC_M_A15 
BMC_M_A4 
BMC_M_A5 
BMC_M_A6 
BMC_M_A7 
BMC_M_A8 
BMC_M_A9 
BMC_M_A3 
BMC_M_A0 
BMC_M_A1 
BMC_M_A2 
BMC_M_VREFCA 
AA12 
AB11 
AA8 
V9 
W12 
Y12 
Y7 
W8 
Y15 
AB15 
U8 
AA6 
W7 
Y9 
W9 
AB10 
AB9 
AB6 
AB7 
V13 
AB14 
Y14 
W14 
U14 
W15 
V15 
AB16 
AA16 
W16 
Y16 
U12 
Y13 
W13 
AB12 
Y11 
V11 
Y8 
T9 
AA14 
U13 
AB13 
W11 
AB8 
V7 
U7 U15 
U10 
W10 
Y10 
AA10 
U9 
12
DO NOT SCALE DRAWING SHEET 
B
AA
B
B
SIZE 
SCALE: 
234
1234
DEPARTMENT CODE 
1
DOCUMENT NUMBER REV 
OUT 
OUT 
OUT 
IN 
OUT 
OUT 
OUT 
OUT 
OUT 
OUT 
OUT 
OUT 
OUT 
OUT 
OUT 
OUT 
OUT 
OUT 
OUT 
OUT 
OUT 
OUT 
OUT 
OUT 
OUT 
OUT 
OUT 
OUT 
OUT 
OUT 
OUT 
OUT 
OUT 
OUT 
OUT 
OUT 
OUT 
OUT 
OUT 
OUT 
OUT 
OUT 
OUT 
OUT 
OUT 
OUT 
OUT 
OUT 
OUT 
143 OF 270 
Wed Feb 08 16:35:09 2017 BMC (1 OF 7) 
ROOM=BMC 
BOM_COST=SM_CONTROLLER 
WIWYNN CORPORATION 



2/7 
2 OF 7 
GPIOG3_SGPS1I1 
GPIOJ1_SGPMLD 
GPIOB0 
GPIOI1_SYSCK 
GPIOA5_TIMER6_SDA9 
GPIOQ5_SDA14 
GPIOQ4_SCL14 
GPIOB5_LPCPD#_LPCSMI# 
GPIOK4_SCL7 
GPIOK5_SDA7 
GPIOK6_SCL8 
GPIOK7_SDA8 
GPIOA4_TIMER5_SCL9 
GPIOA5_TIMER6_SDA9 
GPIOI3_SYSMISO 
GPIOI2_SYSMOSI 
GPIOJ3_SGPMI 
GPIOG0_SGPS1CK 
GPIOG1_SGPS1LD 
GPIOK3_SDA6 
GPIOK2_SCL6 
GPIOK1_SDA5 
GPIOK0_SCL5 
GPIOQ3_SDA4 
GPIOQ2_SCL4 
GPIOQ1_SDA3 
GPIOQ0_SCL3 
GPIOY7_SDA2 
GPIOY6_SCL2 
GPIOB7 
GPIOB3 
GPIOB2 
GPIOB1 
GPIOB0 
TDO 
GPIOY5_SDA1 
DACB 
GPIOG2_SGPS1I0 
GPIOG3_SGPS1I1 
GPIOJ2_SGPMO 
GPIOJ0_SGPMCK 
GPIOJ1_SGPMLD 
GPIOI6_SPI1MOSI_VBMOSI 
GPIOI4_SPI1CS0#_VBCS# 
GPIOI5_SPI1CK_VBCK 
GPIOI0_SYSCS# 
GPIOI1_SYSCK 
NTRST 
RTCK 
TCK 
TDI 
TMS 
DACG 
DACR 
DACRSET 
GPIOI7_SPI1MISO_VBMISO 
GPIOY4_SCL1 
GPIOB4_USBCKI 
GPIOB6_LPCPME# 
1/16W 
G21497-005 
CHIP 
G21497-005 
0.0 
1/16W 
5% 
0402 
AST2520A1-GP-GP 
R25W140 
0.0 
R25W58 
18KR2F-GP 
1 21% G21796-074 1/16W 33.2 R25W70 0402 
CHIP 
0402 2133.2 R25W75 G21796-074 1/16W 1% 
CHIP 
1/16W 
1% 
150.0 
R25W123 
CHIP 
1
0402 
2
1/16W 
0402 
1% 
R25W124 
CHIP 
150.0 
G21796-009 
0402 
1% 
CHIP 
R25W125 
150.0 
G21796-009 
1/16W EMPTY 
5% 
0402 
0402 CHIP 1/16W 51 5.0% R1U14 
1/16W 51 R1U13 5.0% 
0402 1/16W 51 5.0% R1U12 
U25W4 
FM_CPU0_FIVR_FAULT_LVT3_R_N 
FM_CPU1_FIVR_FAULT_LVT3_R_N 
FM_CPU0_FIVR_FAULT_LVT3_N 
FM_CPU1_FIVR_FAULT_LVT3_N 
G21796-009 
G21497-048 
G21497-048 
G21497-048 CHIP 0402 
CHIP 
R25W182 
TP FAB3 NOPOP R25W182 0922 
TP FAB3 ADD R25W182 0921 
160 
159 
133 191 118 
255 
157 181 120 190 
160 
160 
160 
157 119 
120 133 119 
133 191 118 247 
223 94 119 
111 190 
92 190 247 
114 
150 
144 252 
144 252 
144 252 
190 
159 
159 
154 
154 
154 
191 
159 
159 
159 
167 
167 
159 
159 
159 
159 
159 
159 
190 120 158 
190 120 158 
189 255 
189 255 
189 255 
189 254 
189 245 254 
134 120 
92 120 
21 118 190 
190 
154 
191 
190 
190 
119 125 191 
120 191 
GROUP=AST2500 
GROUP=AST2500 
GROUP=AST2500 
BMC_DEBUG_EN_N 
XDP_SYSPWROK 
NOPOP 
18KOHM 
1% 
1/16W 
1
2
1
2
1 2
21
0402 
21
144 252 
144 252 
144 252 
BMC_VGA_RED 
BMC_VGA_GREEN 
BMC_VGA_BLUE 
SMB_SLOTX24_STBY_LVC3_SDA_R 
SMB_OCP_LAN_STBY_LVC3_SCL_R 
PWRGD_PCH_PWROK 
FM_MP_PS_FAIL_N 
SMB_SLOTX24_STBY_LVC3_SCL_R 
SMB_LAN_STBY_LVC3_SDA_R 
SMB_LAN_STBY_LVC3_SCL_R 
H_CPU0_FAST_WAKE_LVT3_N 
IRQ_BMC_PCH_SMI_LPC_N 
PWRGD_SYS_PWROK 
IRQ_PVDDQ_GHJ_VRHOT_LVT3_N 
SGPIO_BMC_CLK_R 
SGPIO_BMC_DOUT_R 
FM_CPU_CATERR_LVT3_N 
CLK_48M_USB_BMC 
PU_JTAG_BMC_RTCK 
BMC_VGA_RED 
BMC_VGA_GREEN 
BMC_VGA_BLUE 
A_DACRSET 
SMB_OCP_FRU_STBY_LVC3_SDA_R 
SMB_HOST_STBY_LVC3_SDA_R 
SPI_BMC_DO 
SPI_BMC_CLK 
SPI_BMC_CS0_N 
SMB_BMC_PMBUS_STBY_LVC3_SCL_R 
SMB_BMC_PMBUS_STBY_LVC3_SDA_R 
SMB_OCP_FRU_STBY_LVC3_SCL_R 
SMB_SENSOR_BMC_STBY_LVC3_SDA 
SMB_SENSOR_BMC_STBY_LVC3_SCL 
SMB_VR_STBY_LVC3_SDA_R 
SMB_VR_STBY_LVC3_SCL_R 
SMB_SMLINK0_STBY_LVC3_SDA_R 
SMB_SMLINK0_STBY_LVC3_SCL_R 
SMB_HOST_STBY_LVC3_SCL_R 
SMB_OCP_LAN_STBY_LVC3_SDA_R 
FM_UARTSW_LSB_N 
FM_UARTSW_MSB_N 
JTAG_BMC_TDO 
JTAG_BMC_TDI 
JTAG_BMC_TMS 
JTAG_BMC_TCK 
JTAG_BMC_TRST_N 
FM_PCH_BMC_THERMTRIP_N 
FM_CPU_ERR2_LVT3_N 
FM_CPU0_SKTOCC_LVT3_N 
SGPIO_BMC_DOUT 
SPI_BMC_DI 
SGPIO_BMC_DIN 
SGPIO_BMC_CLK 
SGPIO_BMC_LD_R_N SGPIO_BMC_LD_N 
FM_UV_ADR_TRIGGER_EN 
FM_FORCE_ADR_N 
CLK_48M_USB_BMC_R 
N22 
N21 
H21 
N1 
P1 
P2 
R1 
C14 
A13 
C16 
B16 
N4 
A19 
E19 
N2 
L1 
L4 
L3 
B9 
A9 
A10 
A11 
P20 
M20 
H20 
K18 
L18 
L19 
K19 
D11 
M19 
J2 
C19 
E16 
N3 
R2 
L2 
A14 
B15 
C15 
C18 
E15 
E11 
C9 
C10 
D12 
C8 
J3 
J4 
K4 
A15 
M18 
J20 
H22 
21
21
DO NOT SCALE DRAWING SHEET 
B
AA
B
B
SIZE 
SCALE: 
234
1234
DEPARTMENT CODE 
1
DOCUMENT NUMBER REV 
OUT 
BI 
IN 
IN 
IN 
OUT 
IN 
OUT 
OUT 
OUT 
IN 
IN 
IN 
IN 
IN 
OUT 
IN 
BI 
OUT 
BI 
OUT 
OUT 
IN 
IN 
IN 
IN 
OUT 
OUT 
OUT 
OUT 
OUT 
OUT 
IN 
OUT 
OUT 
IN 
OUT 
OUT 
OUT 
IN 
IN 
IN 
OUT 
BI 
BI 
OUT 
OUT 
BI 
BI 
OUT 
BI 
BI 
OUT 
OUT 
2 1
144 OF 270 
Wed Feb 08 16:35:09 2017 
TP FAB3 RECONNECT 0922 
TP FAB1 ADD RES 1230 
TP FAB1 ADD CONFIG/AST2500 ON RES 0118 
USB CLOCK IS FROM BMC INTERNAL 
BMC (2 OF 7) 
BOM_COST=SM_CONTROLLER 
ROOM=BMC 
WIWYNN CORPORATION 



3/7 
3 OF 7 
GPIOC1_SD1CMD_SDA10 
GPIOD7_SD2WP_N 
GPIOE7_RXD3 
GPIOL7_RXD1 
GPIOD5_SD2DAT3 
GPIOD6_SD2CD# 
GPIOL6_TXD1 
GPIOF6_TXD4_LHSIRQ# 
GPIOF4_NDTR4_LHCLK 
GPIOF3_NRI4_LHAD3 
GPIOL0_NCTS1 
GPIOC5_SD1DAT3_SDA12 
GPIOC7_SD1WP#_SDA13 
GPIOD7_SD2WP# 
GPIOD2_SD2DAT0 
GPIOD0_SD2CLK 
GPIOE0_NCTS3 
GPIOE1_NDCD3 
GPIOE5_NRTS3 
PETXP 
PETXN 
PEREXT 
TXD5 
GPIOE7_RXD3 
GPIOE6_TXD3 
GPIOE4_NDTR3 
GPIOE3_NRI3 
GPIOE2_NDSR3 
GPIOF2_NDSR4_LHAD2 
GPIOF1_NDCD4_LHAD1 
GPIOF0_NCTS4_LHAD0 
GPIOL7_RXD1 
GPIOL5_NRTS1_VPICLK 
GPIOL1_NDCD1_VPIDE 
GPIOM7_RXD2_VPIB9 
GPIOM6_TXD2_VPIB8 
GPIOM5_NRTS2_VPIB7 
GPIOM4_NDTR2_VPIB6 
GPIOM3_NRI2_VPIB5 
GPIOM2_NDSR2_VPIB4 
GPIOM1_NDCD2_VPIB3 
GPIOM0_NCTS2_VPIB2 
PERXP 
PERXN 
PERST# 
GPIOA3_TIMER4 
SRST# 
CLKIN 
GPIOD1_SD2CMD 
GPIOD4_SD2DAT2 
GPIOD3_SD2DAT1 
PECI 
RXD5 
PEREFCLKP 
PEREFCLKN 
GPIOL4_NDTR1_VPIVS 
GPIOL3_NRI1_VPIHS 
GPIOL2_NDSR1 
GPIOF7_RXD4_LHRST# 
GPIOF5_NRTS4_LHFRAME# 
GPIOG4_SGPS2CK_SALT1 
GPIOG5_SGPS2LD_SALT2 
GPIOA2_TIMER3_SPI1CS1# 
GPIOG7_SGPS2I1_SALT4 
GPIOC4_SD1DAT2_SCL12 
GPIOC6_SD1CD#_SCL13 
GPIOG6_SGPS2I0_SALT3 
GPIOY3_SIOONCTRL# 
GPIOA1_MAC2LINK 
GPIOA0_MAC1LINK 
GPIOC0_SD1CLK_SCL10 
GPIOC1_SD1CMD_SDA10 
GPIOC3_SD1DAT1_SDA11 
GPIOC2_SD1DAT0_SCL11 
TP FAB4 RECONNECT 20170111 
1/16W 
G21497-005 1/16W 
G21497-005 1/16W 
ROOM=SM_CONTROLLER 
A36096-030 
G21796-250 
PECI_BMC 
C25W21 X7R 
0402V 
2
2 RST_PLTRST_BUF_N_R 
CLK_24M_25M_BMC_CLKIN 
G21497-005 
0402 5% 0.0 
G21497-005 
G21497-005 
21
R2W5 
UART_BMC_RXD5 
R25W65 
100.0K 
1% 
1/16W 
CHIP 
G21796-010 
0402 0402 
G21796-010 G21796-010 
AST2520A1-GP-GP 
1 100.0K 
R25W61 
100.0K 
1% 
CHIP 
1% 
R25W144 
2
2
CLK_25M_BMC 
CLK_24M_BMC_CLKIN_R 
CLK_100M_BMC_PE_R_DP 
SMB_PEHPCPU1_STBY_LVC3_SCL 
SMB_PEHPCPU1_STBY_LVC3_SDA 
PU_24M_OSC_OE 
SMB_PEHPCPU0_STBY_LVC3_R_SDA SMB_PEHPCPU0_STBY_LVC3_R2_SDA 
SMB_PEHPCPU0_STBY_LVC3_R2_SCL SMB_PEHPCPU0_STBY_LVC3_R_SCL 
SMB_PEHPCPU0_STBY_LVC3_SDA 
RST_PLTRST_BUF_N 
FM_BMC_ONCTL_R_N 
SMB_PEHPCPU0_STBY_LVC3_SCL 
D34520-021 
3
2
1
4
24MHZ 
OSC 
Y9F2 
2
1
CHIP 2
1% 
CHIP 2
1
1/16W 
CHIP 2
R25W62 
100.0K 
1% G21796-010 
0402 
11
G21796-340 
1/16W 
1% 
348 
R9F20 
EMPTY 
0402 
2
1
1
0.0 5% 
CHIP 5% 
1
R25W145 0.0 
5% 0.0 
1
CHIP 
G21796-173 1/16W 1% 20.0 
R25W122 0402 CHIP 
0402 CHIP 
1/16W 
R25W121 
1% 20.0 G21796-173 
5% 0.0 
1
0402 
C9F23 
0.1UF 
10% 
16V 
1
0402V 
X7R 2
G21796-016 
1/16W 
R9F61 
10.0K 1
2
1% 
CHIP 
0402 
1R2T41 
CHIP 
0.0 
R6W17 0402 
0402 CHIP 
0.0 
R6W18 
5% 
U25W4 
CHIP 1/16W 
0.0 
2
R9F62 
G21497-005 
0402 
5% 
1
G21497-005 
0402 
1/16W 
0.0 
EMPTY 
5% 
R1T23 
G21497-005 
EMPTY 
R1T15 
0.0 
5% 
1/16W 
0402 
5% 
EMPTY 
0.0 
1/16W 
1
R9F60 
2 G21497-005 
0402 
1/16W 
P2E_SSB_BMC_TX_C_DN 
R25W64 
1/16W 
2
0402 
R25W67 
1
16V 
10% 
0.1UF 
21
0.1UF 
10% 
16V 
C25W20 
A36096-030 
A36096-030 
22.1 
5% 
P2E_SSB_BMC_TX_C_DP 
CLK_100M_BMC_PE_R_DN 
R25W141 
G21497-005 
200R2F-L1-GP 
X7R 
0402V 
0402 
G21796-010 
1/16W 
100.0K 
R25W60 
0402 CHIP 
1/16W 
PECI_BMC_R CHIP 2
1.0% 
G21497-005 
R9F33 
2
TP FAB1 ADD TEST POINT 0314 
TP FAB1 POP WHEN AST2500 0106 
TP FAB1 POP WHEN AST2500 0106 
TP FAB1 ADD TEST POINT 0314 
201 95 
166 
145 
119 120 170 
175 119 
190 
175 119 
116 
145 
120 133 
191 120 
191 119 
120 126 200 
120 133 182 
56 133 120 
22 133 118 120 
120 136 157 
200 120 170 
200 120 
200 120 170 
118 169 
250 
226 94 119 
206 95 
137 
158 
190 
190
158119 
170 
191 
120 
158 
158 
156 
157 119 
158 190 
116 
101 
191 
176 247 
164 119 
93 
168 120 190 
164 119 
93 
114 
163 182 
163 182 
120 
248 
248 
176 247 
248 
146 191 134 184 
145 
156 
150 190 
158 
108 157 119 
157 185 186 119 
248 
120 133 119 
116 
145 
116 
114 
120 156 
215 94 119 
93 
93 
245 
119 157 190 
118 135 157 
CLK_24M_25M_BMC_CLKIN 
FM_BMC_SYS_THROTTLE_R_N 
TP_BMC_GPIOA2 
IRQ_FORCE_NM_THROTTLE_N 
GROUP=AST2500 
0402 
0402 
GROUP=AST2500 
GROUP=AST2500 
IRQ_DIMM_SAVE_LVT3_N 
FM_BIOS_SMI_ACTIVE_N 
SMB_DEBUG_STBY_LVC3_SCL 
FM_BOARD_REV_ID0 
FM_CPU_ERR1_LVT3_BMC_N 
FM_SOL_UART_CH_SEL 
FM_BOARD_REV_ID1 
FM_CPU_ERR0_LVT3_BMC_N 
FM_BOARD_REV_ID2 
FM_BIOS_MRC_DEBUG_MSG_DIS_N 
SMB_DEBUG_STBY_LVC3_SDA 
IRQ_OOB_MGMT_RISER_ALERT_N 
IRQ_MEZZ_LAN_ALERT_N 
SMB_DEBUG_STBY_LVC3_SCL_R 
SMB_DEBUG_STBY_LVC3_SDA_R 
IRQ_PCH_NIC_ALERT_N 
1/16W 
1/16W 
FM_BMC_ONCTL_R_N 
0402 
1% 
200 OHM 
1/16W 
GROUP=AST2500 
GROUP=AST2520 
GROUP=AST2520 
GROUP=AST2520 
GROUP=AST2520 
GROUP=AST2520 
JTAG_RISER_N 
FM_CPLD_BMC_PWRDN_N 
1/16W 0402 
RST_BMC_SRST_N 
IRQ_PVCCIN_CPU0_VRHOT_LVC3_N 
P2E_SSB_BMC_RX_DN 
FM_PWR_BTN_N 
RST_SYSTEM_BTN_N 
P2E_SSB_BMC_RX_C_DP 
FM_PWR_BTN_R1_N 
FM_CPU1_THERMTRIP_LATCH_LVT3_N 
FM_CPU0_THERMTRIP_LATCH_LVT3_N 
FM_OC_DETECT_EN_N 
IRQ_BOARD_BMC_ALERT_N 
FM_CPU1_RC_ERROR_N 
FM_CPU0_RC_ERROR_N 
FM_PMBUS_ALERT_BUF_EN_R3_N 
FM_BIOS_TOP_SWAP 
FM_HSC_TIMER_EXP_N 
IRQ_OC_DETECT_N 
IRQ_UV_DETECT_N 
FM_OCP_MEZZC_PRES_LVT3_BMC 
FM_BATTERY_SENSE_EN_N 
FM_OCP_MEZZB_PRES_LVT3_BMC 
IRQ_PVDDQ_KLM_VRHOT_LVT3_N 
IRQ_PVCCIN_CPU1_VRHOT_LVC3_N 
SPI_BMC_BT_WP0_N 
SP1_BMC_HOST_UART_RX 
SP1_BMC_HOST_UART_TX 
FM_PMBUS_ALERT_BUF_EN_N 
FM_MEM_THERM_EVENT_PCH_N 
SP2_BMC_CM_UART_TX 
SP2_BMC_CM_UART_RX 
FM_BMC_PWRBTN_OUT_N 
FP_NMI_BTN_N 
P2E_SSB_BMC_RX_C_DN 
FM_BMC_ONCTL_N 
RST_BMC_SYSRST_BTN_OUT_N 
UART_BMC_TXD5 
PD_PEREXT 
P2E_SSB_BMC_RX_DP 
IRQ_BMC_PCH_NMI_STBY_N 
RST_SYSTEM_BTN_R_N 
IRQ_PVDDQ_ABC_VRHOT_LVT3_N 
FM_CPU1_PROCHOT_LVT3_BMC_N 
FM_CPU0_PROCHOT_LVT3_BMC_N 
CAD NOTE: 
CAD NOTE: 
1 2
21
21
1 2
2
1
21
21
D14 
W1 
AB2 
P3 
P4 
K20 
M21 
M22 
USE SHARED PADS 
K21 
U18 
W18 
D13 
K2 
E17 
D16 
A12 
J18 
J19 
B19 
D15 
A20 
A21 
L20 
G18 
H19 
U2 
H18 
Y1 
AA2 
Y2 
T5 
AA1 
L22 
U1 
P5 
R5 
T1 
F17 
E18 
L21 
D19 
G17 
V1 
B22 
T2 
B21 
C12 
D9 
K22 
E14 
E21 
D21 
E20 
F20 
D20 
C21 
B12 
D10 
E12 
C11 
B11 
F19 
P21 
E13 
K1 
B20 
C20 
F18 
B14 
AB18 
DO NOT SCALE DRAWING SHEET 
B
AA
B
B
SIZE 
SCALE: 
234
1234
DEPARTMENT CODE 
1
DOCUMENT NUMBER REV 
BI 
OUT 
OUT 
IN 
IN 
OUT 
IN 
OUT 
OUT 
IN 
IN 
IN 
IN 
IN 
OUT 
OUT 
OUT 
IN 
IN 
IN 
IN 
IN 
OUT 
IN 
IN 
IN 
IN 
IN 
IN 
IN 
OUT 
OUT 
IN 
OUT 
OUT 
OUT 
IN 
IN 
IN 
IN 
IN 
IN 
IN 
BI 
OUT 
IN 
IN 
IN 
IN 
IN 
OUT 
IN 
IN 
IN 
BI 
P3V3_STBY 
IN 
BI 
OUT IN 
IN 
IN 
OUT 
OUT 
OUT 
IN 
BI 
OUT 
OUT 
BI 
IN 
OUT BI 
Wed Feb 08 16:35:09 2017 
145 OF 270 
OSC_C 
ENABLE_CONTROL 
VDD 
GND 
OUT 
TP FAB1 ADD RES 0226 
TP FAB1 NOPOP WHEN AST2500 0106 
TP FAB1 CHANGE NET NAME 1218 
TP FAB1 REASSIGN GPIO PINS 0218 
TP FAB1 CONNECT TO LEVEL SHIFT 0121 
TP FAB1 CONNECT FROM DELAY IC 0229 
PLACE 0.1UF CAP CLOSE TO OSC 
VDD PIN 
BMC (3 OF 7) 
ROOM=BMC 
BOM_COST=SM_CONTROLLER 
WIWYNN CORPORATION 



5/7 
4/7 
5 OF 7 
GPIOAC7_ESPIRST_N_LPCRST_N 
GPIOR0_FWSPICS1_N 
GPIOR4_SPI2MOSI 
GPIOR3_SPI2CK 
GPIOAC5_ESPICS#_LFRAME# 
GPIOAC6_ESPIALT#_LSIRQ# 
FWSPICS0# 
FWSPIMISO 
GPIOAC0_ESPID0_LAD0 
GPIOAC1_ESPID1_LAD1 
GPIOAC2_ESPID2_LAD2 
GPIOAC3_ESPID3_LAD3 
GPIOAC4_ESPICK_LCLK 
GPIOAB0_VPODE_NOROE# 
GPIOAB1_VPOHS_NORWE# 
GPIOAB2_VPOVS_WDTRST1 
GPIOAB3_VPOCLK_WDTRST2 
GPIOJ5_VGAVS 
GPIOJ6_DDCCLK 
GPIOJ7_DDCDAT 
FWSPICK 
FWSPIMOSI 
GPIOJ4_VGAHS 
HBLED# 
MALERT# 
MRESET# 
GPIOR0_FWSPICS1# 
GPIOR1_FWSPICS2# 
GPIOR2_SPI2CS0# 
GPIOR5_SPI2MISO 
GPIOQ7_PEWAKE# 
GPIOQ6_OSCCLK 
EXTRST# 
ENTEST 
GPIOAC7_ESPIRST#_LPCRST# 
4 OF 7 
GPIOAA7_VPOR9_NORD7_SALT14 
GPIOZ7_VPOG9_NORA7 
GPIOAA3_VPOR5_NORD3_SALT10 
GPIOAA4_VPOR6_NORD4_SALT11 
GPIOAA5_VPOR7_NORD5_SALT12 
GPIOAA6_VPOR8_NORD6_SALT13 
GPIOAA7_VPOR9_NORD7_SALT14 
GPIOAA1_VPOR3_NORD1_SALT8 
GPIOS1_VPOB3_BMCINT 
GPIOS4_VPOB6 
GPIOS5_VPOB7 
GPIOS6_VPOB8 
USB2B_DN 
USB2B_DP 
USB2A_DN 
USB2A_DP 
GPIOAA2_VPOR4_NORD2_SALT9 
GPIOZ0_VPOG2_NORA0_SIOPBI# 
GPIOS7_VPOB9 
GPIOS3_VPOB5_SALT6 
GPIOAA0_VPOR2_NORD0_SALT7 
GPIOZ7_VPOG9_NORA7 
GPIOZ6_VPOG8_NORA6 
GPIOZ5_VPOG7_NORA5 
GPIOZ4_VPOG6_NORA4 
GPIOZ3_VPOG5_NORA3_SIOSCI# 
GPIOZ2_VPOG4_NORA2_SIOPBO# 
GPIOZ1_VPOG3_NORA1_SIOPWRGD 
GPIOS2_VPOB4_SALT5 
GPIOS0_VPOB2_SPI2CS1# 
GPIOH6_TXD6 
GPIOH7_RXD6 
GPIOH5_NRTS6 
GPIOH3_NRI6 
GPIOH4_NDTR6 
GPIOH1_NDCD6 
GPIOH2_NDSR6 
GPIOH0_NCTS6 
USB2AVRES 
USB2BVRES 
NOPOP 
G21497-005 
R1U7 
10.0K 
G21796-016 
2
1% 33.2 
CHIP 
CHIP 
1% 
33.2 R25W68 
R3N24 
R25W69 
1
1/16W 
1/16W 
100.0K 
0402 
1.0% 
CHIP 
1
1% 
G21796-345 
0402 
1/16W 
CHIP 
G21796-074 1/16W 0402 
G21796-074 
1
CHIP 
0402 
1/16W 
1% 
0402 
1% 
CHIP 
G21796-010 
G21796-074 1/16W R3N26 
1% G21796-074 
0402 1% 
1
33.2 
0402 1/16W 1% 
2
R25W72 33.2 G21796-074 
R25W82 
1
CHIP 
R25W81 CHIP 33.2 
2
0402 
CHIP 
1/16W 
1% 
8.2K 
R1T25 
G21796-345 
0402 
5% 
0402 
R25W130 
1 2
4.75K 
1/16W CHIP G21796-072 
1% 
1% 
CHIP 
2
1/16W 
1
R25W129 
0402 G21796-072 
4.75K 
AST2520A1-GP-GP 
U25W4 
AST2520A1-GP-GP 
U25W4 
1
10% 
2
X7R 
C1W21 
8.2K 
R1T26 
0.033UF 
603269-064 
0603LF 50V 
0402 
22.1 
CHIP 
0402 
G21796-074 
2
1/16W CHIP 
G21497-005 
2
CHIP 1/16W 5% 0.0 
1
0402 
1% 
21
0402 G21497-005 CHIP 
R25W184 
R25W78 
2
5% 0.0 1/16W 
1
R25W63 
1/16W 
CHIP 2
G21796-010 
100.0K 
RST_PLTRST_BUF_N 
0402 
33.2 
33.2 
33.2 R25W66 
CHIP 1/16W 
1% 
1% CHIP 
CHIP 
R25W73 
R25W74 
1% 
1
2
0.0 
R25W83 
ENTEST 
TP FAB3 RECONNECT 0922 
TP FAB3 RESERVE A RES 1004 
TP FAB1 ADD NET 0311 
TP FAB4 CHANGE CONNECTION FROM PECI_SEL TO BMC_SELF_HW_RST 20170203 
TP FAB4 CHANGE CONNECTION FROM BMC_SELF_HW_RST TO PECI_SEL 20170203 
119 151 
119 133 
150 162 246 
249 
155 
155 
155 
115 
150 162 246 
119 133 170 95 
155 
115 
115 
115 
155 
155 
155 
155 
151 
151 
111 255 
255 
254 
142 
168 120 
162 
191 134 
145 146 
184 
157 181 120 
119 126 
199 120 170 
55 112 118 190 
150 
150 
119 157 190 
249 
162 246 150 
137 246 
133 250 119 
133 199 119 
119 
119 
133 119 
146 191 134 145 184 
252 
252 
146 252 
252 
146 
120 133 119 182 
247 
150 
150 
150 
150 
133 249 119 
120 133 175 
139 119 
137 200 
166 
157 120 
218 94 119 
120 133 119 
150 
FM_BMC_HEARTBEAT_N 
FM_BIOS_POST_CMPLT_N 
1/16W 
SPI_BMC_BT_DO 
1
CLK_24M_BMC_LPC 
BMC_SELF_HW_RST 
2
LPC_LAD0_IO0_R 
LPC_LAD1_IO1_R 
LPC_LFRAME_N_CS0_R_N 
LPC_LAD3_IO3_R 
LPC_LAD2_IO2_R 
LED_POSTCODE_6 
LED_POSTCODE_5 
LED_POSTCODE_4 
A_USB2BVRES 
USB2_PCH_BMC_P5_DP 
SPI_BMC_BT_CLK 
FM_THROTTLE_N 
LED_POSTCODE_0 
USB_PCH_BMC_P4_DN 
USB_PCH_BMC_P4_DP 
USB2_PCH_BMC_P5_DN 
LED_POSTCODE_2 
LED_POSTCODE_1 
LED_POSTCODE_3 
LED_POSTCODE_7 
I2C_BMC_VGA_DDC_SDA 
I2C_BMC_VGA_DDC_SCL 
1 2
1
1 2
1 2
G21796-074 
1/16W 
A_USB2AVRES 
BMC_M_RST_N 
BMC_M_MALERT_N 
XDP_PRESENT_N 
BMC_PRDY_N 
BMC_TCK_MUX_SEL 
FM_PE_BMC_WAKE_N 
FM_POST_CARD_PRES_BMC_N 
RST_BMC_PLTRST_BUF_N 
NOPOP 
0402 
1/16W 
G21796-250 
SPI_BMC_BT_CS_N 
FM_MP_PS_REDUNDANT_LOST_N 
SPI_BMC_BT_CS_R_N 
IRQ_SML0_ALERT_N 
IRQ_SML1_PMBUS_ALERT_N 
FM_CPU1_SKTOCC_LVT3_N 
BMC_STRAP_BIT27 
BMC_STRAP_BIT20 
FM_BMC_CPLD_GPO 
PD_SP_ENTEST 
RST_BMC_EXTRST_N 
0402 
SPI_BMC_BT_DO_R 
SPI_BMC_BT_DI 
SPI_BMC_BT_CS0_N 
SPI_BMC_BT_CLK_R 
0402 G21796-074 
RST_BMC_LVC3_N 
IRQ_LPC_SERIRQ_R 
FM_OCP_MEZZA_PRES 
IRQ_HSC_FAULT_N 
LPC_LAD_IO<3:0> 
LPC_LFRAME_N_CS0_N 
IRQ_LPC_SERIRQ_N 
RST_PLTRST_BUF_N 
BMC_VGA_HSYNC 
BMC_VGA_VSYNC 
I2C_BMC_VGA_DDC_SCL 
I2C_BMC_VGA_DDC_SDA 
FM_BMC_READY_N 
HSC_SMBUS_SWITCH_EN 
BMC_STRAP_BIT3 
BMC_STRAP_BIT5 
GPIOS7 
BMC_STRAP_BIT17 
FM_BMC_NMI_N_R 
FM_TPM_PRES_N 
FP_PWR_ID_LED_N 
IRQ_LOM_ALERT_N 
UV_HIGH_SET 
PECI_SEL 
FM_BMC_NMI_N 
1/16W 
2
IRQ_PVDDQ_DEF_VRHOT_LVT3_N 
IRQ_BMC_PCH_SCI_LPC_N 
BMC_STRAP_BIT18 
146 252 
146 252 
0
2
1
3
PLACE RESISTORS CLOSE TO BMC 
CAD NOTE: 
W19 
Y19 
F21 
F22 
AB19 
T18 
G21 
G20 
D22 
E22 
C22 
N19 
T21 
T22 
R20 
R4 
R3 
T3 
AA18 
U17 
N5 
Y18 
U16 
AB17 
AA19 
T19 
T17 
V19 
N20 
B10 
V18 
K3 
G22 
AA22 
U22 
T20 
N18 
P19 
V21 
U19 
R19 
W20 
U20 
A6 
B6 
A8 
A7 
Y22 
Y20 
AA20 
P18 
Y21 
W21 
V22 
W22 
U21 
AA21 
AB21 
AB20 
R18 
V20 
A16 
D18 
B17 
C17 
A17 
B18 
D17 
A18 
B8 
B7 
21
1 2
DO NOT SCALE DRAWING SHEET 
B
AA
B
B
SIZE 
SCALE: 
234
1234
DEPARTMENT CODE 
1
DOCUMENT NUMBER REV 
IN 
BI 
IN 
BI 
BI 
IN 
OUT 
OUT 
IN 
OUT 
OUT 
OUT 
IN 
OUT 
OUT 
OUT 
OUT 
OUT 
OUT 
OUT 
OUT 
OUT 
IN 
IN 
IN 
OUT 
OUT 
OUT 
OUT 
IN 
IN 
OUT 
BI 
BI 
BI 
BI 
P3V3 
BI 
OUT 
OUT 
OUT 
OUT 
OUT 
IN 
OUT 
IN 
IN 
IN 
IN 
IN 
IN 
OUT 
OUT 
OUT 
IN 
OUT 
IN 
IN 
OUT 
IN 
IN 
OUT 
IN 
IN 
146 OF 270 
Wed Feb 08 16:35:09 2017 
TP FAB1 SWAP USB_P5 AND USB P4 0227 
TP FAB1 ADD RES 1230 
TP FAB1 NOPOP R25W66 0331 
TP FAB1 DELETE PU RES 0121 
TP FAB3 ADD CAP 0803 
TP FAB1 ADD NETS 1230 
BMC (4 & 5 OF 7) 
WIWYNN CORPORATION 



6/7 
6 OF 7 
ADC15_GPIX7 
RGMII2TXD3_GPIOU3 
GPIOP7_TACH15 
RGMII2RXCK_RMII2RCLKI_GPIOV2 
RGMII2RXD3_RMII2RXER_GPIOV7 
RGMII2RXD2_RMII2CRSDV_GPIOV6 
RGMII2RXD1_RMII2RXD1_GPIOV5 
RGMII2RXD0_RMII2RXD0_GPIOV4 
RGMII1RXCK_RMII1RCLKI_GPIOU4 
RGMII1RXCTL_GPIOU5 
RGMII1RXD3_RMII1RXER_GPIOV1 
RGMII1RXD2_RMII1CRSDV_GPIOV0 
RGMII1RXD1_RMII1RXD1_GPIOU7 
RGMII1RXD0_RMII1RXD0_GPIOU6 
GPIOR7_MDIO1 
GPIOR6_MDC1 
RGMII2RXCTL_GPIOV3 
RGMII1TXD1_RMII1TXD1_GPIOT3 
RGMII1TXD0_RMII1TXD0_GPIOT2 
RGMII1TXD3_GPIOT5 
RGMII1TXD2_GPIOT4 
RGMII1TXCTL_RMII1TXEN_GPIOT1 
RGMII1TXCK_RMII1RCLKO_GPIOT0 
RGMII2TXD0_RMII2TXD0_GPIOU0 
RGMII2TXD1_RMII2TXD1_GPIOU1 
RGMII2TXD3_GPIOU3 
RGMII2TXD2_GPIOU2 
RGMII2TXCK_RMII2RCLKO_GPIOT6 
RGMII2TXCTL_RMII2TXEN_GPIOT7 
GPIOO0_TACH0_VPIG8 
GPIOO2_TACH2 
GPIOO1_TACH1_VPIG9 
GPIOO3_TACH3 
GPIOO5_TACH5_VPIR3 
GPIOO4_TACH4_VPIR2 
GPIOP0_TACH8_VPIR6 
GPIOO7_TACH7_VPIR5 
GPIOO6_TACH6_VPIR4 
GPIOP1_TACH9_VPIR7 
GPIOP2_TACH10_VPIR8 
GPIOP5_TACH13 
GPIOP4_TACH12 
GPIOP3_TACH11_VPIR9 
GPIOP6_TACH14 
GPIOP7_TACH15 
ADC0_GPIW0 
ADC1_GPIW1 
ADC2_GPIW2 
ADC3_GPIW3 
ADC5_GPIW5 
ADC4_GPIW4 
ADC6_GPIW6 
ADC10_GPIX2 
ADC9_GPIX1 
ADC11_GPIX3 
ADC12_GPIX4 
ADC13_GPIX5 
ADC15_GPIX7 
ADC14_GPIX6 
ADCVREFN 
ADCREXT 
ADCVREFP 
GPION0_PWM0 
GPION2_PWM2_VPIG2 
GPION1_PWM1 
GPION3_PWM3_VPIG3 
GPION5_PWM5_VPIG5 
GPION4_PWM4_VPIG4 
GPION7_PWM7_VPIG7 
GPION6_PWM6_VPIG6 
RGMIICK GPIOA7_TIMER8_MDIO2 
GPIOA6_TIMER7_MDC2 
ADC7_GPIW7 
ADC8_GPIX0 
ROOM=SM_CONTROLLER 
1% 
FM_GLOBAL_RST_WARN_N 
R25W181 
1/16W 
5% 
0.0 
G21497-005 
AST2520A1-GP-GP 
U25W4 
100.0K 
R1U5 R25W142 
100.0K 
1% 
1 100.0K 
R1U2 R1U4 
1
1% 
1/16W 1/16W 
CHIP 
1% 
100.0K 
R1U1 
100.0K 
CHIP 
1/16W 
G21796-010 
CHIP 
G21796-010 
0402 
G21796-010 
1% 
G21796-010 
0402 
FM_FLASH_DESC_OVERRIDE 
1
1/16W 
CHIP 
EMPTY 
5% 
G21497-005 
0402 
CHIP 
1/16W 
1
1/16W 
1
2 CHIP 
G21796-010 
0402 
2
1
0402 
1% 
1
0402V 
A36096-030 
X7R 2
10% 
16V 
0.1UF 
C25W9 
1 2
X7R 10% A36096-030 
16V 0.1UF C25W7 
0402V 
1
X7R 10% 
16V 
0402V 
2
0.1UF C25W8 
A36096-030 
R25W90 22.1 2
CHIP 
1 1.0% 
22.1 21
CHIP 
1.0% 
1 22.1 2 1.0% 
2 22.1 
CHIP 
1.0% 
R25W87 2 22.1 1.0% 
CHIP 
1/16W 
1
2
0402 
G21796-016 
10.0K 
R25W79 
10.0K 
CHIP 
1
2
G21796-016 
1% 
1/16W 
R25W80 
0402 
22
1
22
1/16W 
0402 
1% 
R2N13 
CHIP 
1R25W88 2 1.0% 22.1 
CHIP 
R25W57 
49.9K 
1% 
0402 
G21796-048 
1/16W 
CHIP 
0.0 
R25W157 
1/16W 
1% 
100.0K R1T24 
2
0402 
0402 
G21796-010 
R25W89 
R25W85 
CHIP 
CHIP 
1
1
R25W86 
CHIP 
0402 
10.0K 
G21796-016 
0.0 
CHIP 
G21497-005 
1/16W 
5% 
0402 
FM_GLOBAL_RST_WARN_N_R 
R25W143 
TP FAB3 RECONNECT 0920 
TP FAB3 RECONNECT 0922 
TP FAB3 RECONNECTION 0831 
TP FAB3 ADD RES 0819 
TP FAB3 ADD RES 0831 
TP FAB3 DEL RES 0823 
119 190 
108 133 119 
108 133 119 
190 
192 111 
118 
169 
133 182 119 
133 182 119 
164 120 
186 
186 
186 
169 
119 
161 181 
121 139 
121 139 
119 182 
118 157 190 
251 
95 108 
120 154 
154 
92 120 190 247 
161 
161 
152 
152 
152 
152 
169 
169 
169 
169 
169 
169 
251 
150 
150 
150 
150 
150 
150 
150 
150 
119 170 
186 
119 177 
101 
121 139 
121 125 
101 
125 121 
139 150 
121 
121 139 
121 139 
150 186 
254 
164 120 
164 120 
164 120 
181 
161 181 
255 
164 120 
251 
181 
186 
186 
FM_SLT_CFG0 
FM_SLT_CFG1 
RST_RSMRST_N 
A_P3V_BAT_SCALED 
FM_XRC_PRESENT_N 
FM_XRC_READY_N 
FM_BOARD_SKU_ID0 
RMII_BMC_OCP_RXD0 
RMII_BMC_OCP_RXD1 
RMII_BMC_OCP_CRSDV 
A_P5V_STBY_SCALED 
FM_BIOS_PREFRB2_GOOD 
FAN_TACH2 
RMII_SPRNGVLLE_BMC_PCH_RXD0 
RMII_SPRNGVLLE_BMC_PCH_RXD1 
FM_BB_BMC_MP_GPIO 
FM_BMC_CPLD_MP_RST_N 
PUMP_PWM_OUT 
FM_PWRBRK_N 
FM_BACKUP_BIOS_SEL_N 
FM_BIOS_SPI_BMC_CTRL 
FM_CPU_MSMI_LVT3_N 
FAN_PWM_OUT_SYS1 
FAN_PWM_OUT_SYS0 
P3V3_STBY_BMC_ADCVREFP 
PD_ADCREXT 
P3V3_STBY_BMC_ADCVREFN 
H_CPU1_MEMGHJ_MEMHOT_LVT3_BMC_N 
H_CPU1_MEMKLM_MEMHOT_LVT3_BMC_N 
H_CPU0_MEMDEF_MEMHOT_LVT3_BMC_N 
H_CPU0_MEMABC_MEMHOT_LVT3_BMC_N 
A_PVNN_STBY_PCH_SENSOR 
A_P3V3_STBY_SCALED 
A_P1V05_STBY_PCH_SENSOR 
A_P12V_STBY_SCALED 
A_P5V_SCALED 
A_P3V3_SCALED 
PUMP_TACH1 
RMII_BMC_SPRNGVLLE_TXEN_R 
TP_RGMII2TXD2_GPIOU2 
TP_RGMII2TXD3_GPIOU3 
RMII_BMC_PCH_SPRNGVLLE_TXD1_R 
RMII_BMC_PCH_SPRNGVLLE_TXD0_R 
RMII_BMC_OCP_TXEN_R 
TP_RGMII1TXD2_GPIOT4 
TP_RGMII1TXD3_GPIOT5 
RMII_BMC_OCP_TXD0_R 
RMII_BMC_OCP_TXD1_R 
FM_FAST_PROCHOT_EN_N 
RMII_BMC_OCP_RXER 
FM_BMC_FAULT_LED_N 
CLK_50M_CKMNG_BMC_1 
RMII_BMC_PCH_SPRNGVLLE_CRSDV 
RMII_BMC_PCH_SPRNGVLLE_RXER 
CLK_50M_CKMNG_BMC_2 
1/16W G21796-250 0402 
G21796-250 0402 
0402 G21796-250 
0402 G21796-250 
0402 1/16W G21796-250 
1/16W 0402 G21796-250 
RMII_BMC_PCH_SPRNGVLLE_TXEN 
RMII_BMC_PCH_SPRNGVLLE_TXD1 
RMII_BMC_PCH_SPRNGVLLE_TXD0 
RMII_BMC_OCP_TXEN 
1/16W 
1/16W 
1/16W 
BMC_RSMRST_B_N 
BMC_PREQ_N 
FM_BOARD_SKU_ID3 
FM_BOARD_SKU_ID2 
FM_BOARD_SKU_ID1 
FAN_TACH1 
FAN_TACH0 
BMC_PWR_DEBUG_N 
FM_BOARD_SKU_ID4 
PUMP_TACH0 
FAN_TACH3 
RMII_BMC_OCP_TXD1 
RMII_BMC_OCP_TXD0 
CAD NOTE: 
21
2
1
2
1
21
W6 
G4 
F2 
C13 
B13 D3 
Y3 
T4 
W3 
AA3 
U3 
W2 
V3 
V2 
H2 
J1 
H1 
H3 
H4 
G1 
H5 
F1 
G3 
G2 
G5 
F3 
E3 
E1 
E2 
F5 
F4 
AB5 
Y6 
AA5 
W5 
AA4 
W4 
V4 
AB3 
Y4 
AB4 
U4 
V5 
U5 
B1 
B2 
D5 
D4 
B3 
A2 
B5 
E9 
E7 
D7 
F9 
A5 
C1 
D6 
C5 
C4 
A4 
B4 
C3 
D1 
D2 
E6 
C2 
PLACE THESE RESISTORS 
NEAR BMC 
D8 
E10 
V6 
A3 
Y5 
DO NOT SCALE DRAWING 
VCC_ADCAV3V3 
SHEET 
B
AA
B
B
SIZE 
SCALE: 
234
1234
DEPARTMENT CODE 
1
DOCUMENT NUMBER REV 
OUT 
IN 
IN 
OUT 
OUT 
OUT 
IN 
OUT 
IN 
IN 
IN 
IN 
IN 
IN 
IN 
IN 
IN 
IN 
IN 
P3V3_STBY 
OUT 
OUT 
OUT 
OUT 
OUT 
IN 
IN 
IN 
IN 
IN 
IN 
OUT 
OUT 
OUT 
IN 
IN 
OUT 
IN 
IN 
OUT 
IN 
IN 
IN 
OUT 
IN 
OUT 
IN 
IN 
IN 
OUT 
IN 
OUT 
IN 
IN 
IN 
IN 
IN 
IN 
IN 
OUT 
OUT 
OUT 
OUT 
OUT 
OUT 
IN 
IN 
OUT 
OUT 
Wed Feb 08 16:35:10 2017 
147 OF 270 
TP FAB1 ADD POTENTIAL DEBUG USE  0128 
TP FAB1 POP CAP 0331 
TP FAB1 RENAME RGMII2TX2, TX3 0227 
TP FAB1 NOPOP RES 0227 
TP FAB1 DEL RES 0301 
TP FAB1 NC 0314 
TP FAB1 ADD RES 0121 
BMC (6 OF 7) 
WIWYNN CORPORATION 



7/7 
7 OF 7 
PEAV33 
GPIOY2_SIOPWREQ_N 
GND0 
GND1 
GND2 
GND3 
GND6 
GND8 
GND7 
GND5 
GND4 
GND11 
GND12 
GND13 
GND10 
GND9 
GND16 
GND17 
GND18 
GND15 
GND14 
GND19 
GND21 
GND22 
GND23 
GND20 
GND24 
GND26 
GND28 
GND27 
GND25 
GND29 
GND31 
GND32 
GND33 
GND34 
GND30 
GND36 
GND37 
GND38 
GND39 
GND35 
GND42 
GND43 
GND44 
GND41 
GND40 
GND47 
GND48 
GND49 
GND46 
GND45 
GND52 
GND53 
GND54 
GND51 
GND50 
GND57 
GND58 
GND59 
GND56 
GND55 
GND62 
GND63 
GND64 
GND61 
GND60 
GND65 
GND66 
GND67 
R1VDD1 
R1VDD0 
R2VDD1 
R2VDD0 
ADCAV33 
DACDV33 
USB2AV33 
BATVDD 
PEAV33 
VPLLAV331 
VPLLAV330 
PLLAV331 
PLLAV330 
PV33D14 
PV33D13 
PV33D12 
PV33D11 
PV33D10 
PV33D9 
PV33D8 
PV33D7 
PV33D6 
PV33D5 
PV33D4 
PV33D3 
PV33D2 
PV33D1 
MVDD3 
MVDD2 
MVDD1 
MVDD0 
PECIVDD 
PLLDV11 
PEAV11 
VPLLAV111 
VPLLAV110 
IV11D24 
IV11D23 
IV11D22 
IV11D21 
IV11D20 
IV11D19 
IV11D18 
IV11D17 
IV11D16 
IV11D15 
IV11D14 
IV11D13 
IV11D12 
IV11D11 
IV11D10 
IV11D9 
IV11D8 
IV11D7 
IV11D6 
IV11D5 
IV11D4 
IV11D3 
IV11D2 
IV11D1 
IV11D0 
GPIOY0_SIOS3# 
GPIOY1_SIOS5# 
GPIOY2_SIOPWREQ# 
MVDD4 
PV33D0 
DACAV33 
GND68 
LPVDD0 
LPVDD1 
ROOM=SM_CONTROLLER 
FM_SLPS3_N R25W155 
0.0 0402 CHIP 5% 
U25W4 
AST2520A1-GP-GP 
D97712-004 
C1T21 
2
1.0UF 
10% 
6.3V 
1
X6S 
0402V 
CHIP 
R25W59 0.0 5% 0402 
FM_SLPS4_N 
GND<68> 
TP FAB3 DELETE VCC_D_PLL_3V3 AND CONNECT PV33D13 TO VCC_PA_3V3 0922 
118 190 247 
118 191 
189 254 255 
PVCCIO_CPU0_R 
G21497-005 
1/16W 
1/16W G21497-005 
BMC_JTAG_SEL_N 
VCC_VA_3V3 
VCC_A_1V1 
P1V2_AUX_BMC 
P3V3_USB2A_ALG 
VCC_DACAV3V3 
VCC_ADCAV3V3 
P1V15_AUX_BMC 
VCC_PA_3V3 
VCC_D_3V3 
VCC_D_3V3 
VCCBAT_TW12 
A1 
A22 
AA11 
AA13 
AA9 
AB22 
AB1 
AA7 
AA15 
F16 
G19 
G6 
E8 
C6 
J11 
J12 
J13 
J10 
H6 
J14 
J22 
J5 
J9 
J21 
K10 
K12 
K14 
K13 
K11 
K16 
L10 
L11 
L12 
L13 
K9 
L9 
M1 
M10 
M11 
L14 
M14 
M16 
M17 
M13 
M12 
M4 
M5 
M6 
M3 
M2 
N10 
N11 
N12 
M9 
M7 
N9 
T16 
T6 
N14 
N13 
U6 
V10 
V12 
U11 
T7 
V14 
V16 
V8 
F11 
F10 
F8 
F7 
J6 
K5 
C7 
E4 
L16 
H7 
J7 
W17 
Y17 
T15 
T11 
R6 
R17 
P6 
P17 
N6 
N17 
K7 
H17 
G16 
F15 
F14 
F13 
T14 
T13 
T12 
T10 
AA17 
V17 
L17 
L6 
L5 
R7 
R16 
P9 
P7 
P16 
P14 
P13 
P12 
P11 
P10 
N7 
N16 
L7 
J16 
H16 
G9 
G8 
G7 
G15 
G14 
G13 
G12 
G11 
G10 
F6 
R22 
R21 
P22 
T8 
F12 
K6 
E5 
J17 
K17 
21
21
DO NOT SCALE DRAWING SHEET 
B
AA
B
B
SIZE 
SCALE: 
234
1234
DEPARTMENT CODE 
1
DOCUMENT NUMBER REV 
P3V3_STBY 
OUT 
PVCCIO_CPU0 
P3V3_STBY 
P3V3_STBY 
IN 
IN 
148 OF 270 
Wed Feb 08 16:35:10 2017 
TP FAB1 ADD RES 0314 
POWER PIN T11 (OLD NAME: PV33D) SUPPLIES THE DDR PHY PLL POWER. 
BMC (7 OF 7) 
WIWYNN CORPORATION 



ROOM=SM_CONTROLLER 
0402 
X6S 
1.0UF 
D97712-011 D97712-011 
5% 
HCB1608KF-800T30-GP 
50V 
X7R 
D97712-011 
C25W56 
1.0UF 
16V A36096-030 
0402 
X6S 
10% 10% 
16V 
1
0.1UF 
C25W58 
2
0402V 0402LF 
100.0PF 
A36095-026 
COG 
C25W57 
16V 
10UF 
D97712-011 
10% 
16V 
1.0UF 
C25W33 
0402 
D97712-011 
X6S 
16V 
X6S 
D97712-011 
FB2T5 
D97712-011 
C25W43 
1.0UF 
16V 
10% 
X6S 
0402 
C25W44 
0402 
X6S 
16V 
10% 
1.0UF 
D97712-011 
X6S 
0402 
10% 
0402 
C25W23 
1.0UF 
16V 
X6S 
16V 
1.0UF 
D97712-011 
C25W24 C25W25 
1.0UF 
10% 
16V 
C25W27 
1.0UF 
10% 
16V 
0402 
X6S 
0402 
16V 
1.0UF 
C25W60 
10% 
X6S 
D97712-011 
0402 
10% 
X6S 
C25W35 
1.0UF 
16V 
C25W48 
0402 
X6S 
16V 
1.0UF 
D97712-011 
X6S 
0402 
C25W37 
1.0UF 
C25W51 
0402 
X6S 
16V 
X6S 
D97712-011 
0402 
1.0UF 
10% 
16V 
C25W71 
D97712-011 
X6S 
0402 
10% 
C25W66 
1.0UF 
16V 
X6S 
D97712-011 
0402 
C25W67 
16V 
10% 
1.0UF 
0402 
X6S 
16V 
10% 
1.0UF 
D97712-011 
C25W52 
2
C25W31 
0.1UF 
A36096-030 
16V 
1
0402V 
X7R 
10% C25W34 
0.1UF 
A36096-030 
16V 
2
1
0402V 
X7R 
A36096-030 
0.1UF 
C25W38 
2
1
0402V 
X7R 
10% 
1 C25W45 
0.1UF 
A36096-030 2
0402V 
X7R 
16V 
10% 
A36096-030 
10% 
16V 
1 C25W49 
0402V 
2
0.1UF 
X7R 
0402V 
A36096-030 
X7R 
10% 
0.1UF 
C25W55 
16V 
2
1
0.1UF 
A36096-030 
16V 
2
1
0402V 
X7R 
10% 
C25W61 
X7R 
0402V 
1
2
A36096-030 
0.1UF 
C25W68 
16V 
10% 
10% 
X6S 
CHIP 
1/10W 
5.0% 
0 0603 
R25W93 
CHIP 
1/10W 
5.0% 
0603 
R25W120 
0G22178-002 
10% 
16V 
X6S 
D97712-011 
0402 
C25W54 
1.0UF 
16V 
10% 
0402 
X6S 
10% 
D97712-011 
1.0UF 
10% 
16V 
X6S 
0402 
D97712-011 
10% 
X6S 
0402 
C25W42 
1.0UF 
16V D97712-011 
16V 
1.0UF 
X6S 
D97712-011 
0402 
C25W32 
FB2T7 
HCB1608KF-800T30-GP 
FB2T1 
10% 
16V 
1.0UF 
HCB1608KF-800T30-GP 
FB2T3 
HCB1608KF-800T30-GP 
HCB1608KF-800T30-GP 
FB2T4 
16V 
1.0UF 
C25W40 C25W41 
10% 
G22178-002 
16V 
C25W53 
1.0UF 
X6S 
D97712-011 
0402 
D97712-011 
10% 
D97712-011 
10% 
10% 
1.0UF 
16V 
10% 
0805 
C95333-007 
C25W46 
0402 
C25W28 
0402 
D97712-011 
X6S 
10% 
C25W26 1
2
4V 
20% 
X6S 
10UF 
C25W29 
0603LF 
E15431-001 
10% 
D97712-011 
TP FAB3 CHANGE CAP FROM 0805 TO 0603 0922 
TP FAB3 DELETE FB2T6, C25W63, C25W64, C25W65 0922 
TP FAB3 CHANGE C25W57 FROM 1UF TO 100PF; NOPOP C25W59 0922 
80OHM@100MHZ 
DCR=4MOHM 
E15431-003 
X6S 
10% 
6.3V 
4.7UF 
C25W59 
0603 
E15431-003 
0603 
X6S 
C25W47 
3A 
DCR=4MOHM 
DCR=4MOHM 
3A 
10% 
6.3V 
4.7UF 
C25W69 
X6S 
0603 
E15431-003 
4.7UF 
C25W39 
E15431-003 
10% 
0603 
X6S 
4.7UF 
6.3V 
10% 
X6S 
0603 
E15431-003 
C25W50 
10% 
X6S 
0603 
E15431-003 
6.3V 
4.7UF 
0603 
X6S 
10% 
6.3V 
4.7UF 
C25W36 
E15431-003 
0603 
X6S 
10% 
6.3V 
4.7UF 
C25W70 
10% 
6.3V 
4.7UF 
DCR=4MOHM 
80OHM@100MHZ 
80OHM@100MHZ 
3A 
80OHM@100MHZ 
3A 
DCR=4MOHM 
80OHM@100MHZ 
3A 
6.3V 
E15431-003 
X6S 
10% 
6.3V 
0603 
E15431-003 
4.7UF 
C25W30 
C25W62 
2
1
2
1
2
1
1
NOPOP 
1
1 2
1 2
2
21
2
DO NOT SCALE DRAWING 
VCC_PA_3V3 
VCC_D_3V3 
VCC_VA_3V3 
P3V3_USB2A_ALG 
VCC_A_1V1 
P1V2_AUX_BMC 
VCC_DACAV3V3 
P1V15_AUX_BMC 
P1V15_AUX_BMC 
VCC_ADCAV3V3 
SHEET 
B
AA
B
B
SIZE 
SCALE: 
234
1234
DEPARTMENT CODE 
1
DOCUMENT NUMBER REV 
P3V3_STBY 
P3V3_STBY 
P3V3_STBY 
P3V3_STBY 
P3V3_STBY 
P3V3_STBY 
P3V3_STBY P3V3_STBY 
Wed Feb 08 16:35:10 2017 
149 OF 270 
80 OHM@100MHZ 3A 
PLACEMENT CLOSE K5,K6 PIN  OR  POWER  PLANE 
PLACEMENT CLOSE CHIP 
PLACEMENT CLOSE CHIP 
PLACEMENT CLOSE L5,L6 PIN OR POWER PLANE 
PLACEMENT CLOSE J7,H7 PIN OR POWER PLANE 
80 OHM@100MHZ 3A 
80 OHM@100MHZ 3A 
80 OHM@100MHZ 3A 
PLACEMENT CLOSE T8,10,12,13,14 PIN OR POWER PLANE 
PLACEMENT CLOSE F10,F11,F7,F8 PIN OR POWER PLANE 
PLACEMENT CLOSE J6  PIN  OR  POWER  PLANE 
PLACEMENT CLOSE K17,F13,F12 PIN  OR  POWER  PLANE 
80 OHM@100MHZ 3A 
PLACEMENT CLOSE Y17,W17 PIN OR POWER PLANE 
PLACEMENT CLOSE F6,AA17,G13 AND 1VDD PIN CHIP OR POWER PLANE 
PLACEMENT CLOSE J17,K17 PIN OR POWER PLANE 
BMC DECOUPLING CAPS 
1UF 6.3V NEED CHANGE TO 16V WAIT FOR SYMBOL 
WIWYNN CORPORATION 



1% 
0402 G21796-072 
1/16W 
G21796-072 
1/16W 
0402 
1/16W 
R25W95 
CHIP 
1% 
G21796-072 
1/16W 4.75K 
0402 
4.75K 
CHIP G21796-072 
1/16W 
0402 
1/16W 
G21796-072 
1% 4.75K R25W97 
EMPTY 0402 
1% 4.75K R25W105 
4.75K 
EMPTY 
R25W98 1/16W 1% 
G21796-072 
R25W99 4.75K 
G21796-072 EMPTY 
1/16W 
CHIP 
1% 1/16W 4.75K R25W100 
0402 EMPTY 
1% R25W103 
1% 
CHIP 
EMPTY 
4.75K 1% 
G21796-072 
1/16W 
0402 
R25W110 
0402 
1% 4.75K R25W152 1/16W 
G21796-072 CHIP 
G21796-072 
1% R25W109 
CHIP 
4.75K 
0402 
1/16W 
1
R25W116 
1
EMPTY 
R25W156 
2
2
1/16W 
0402 
1/16W 
G21796-072 
3.32K EMPTY 
3.32K 1% 1/16W 
1% 
0402 
0402 
1/16W 
G21796-072 
1% 4.75K 
0402 G21796-072 
1/16W 1% 4.75K R25W151 
CHIP 
0402 G21796-072 
1/16W 1% 4.75K R25W113 
EMPTY 
0402 G21796-072 
1/16W 4.75K 1% R25W150 
CHIP 
0402 G21796-072 
1/16W 1% 4.75K 
EMPTY 
R25W112 
1/16W 
0402 G21796-072 
1% R25W115 
CHIP 
4.75K 
CHIP 0402 G21796-072 
1/16W 4.75K 1% R25W149 
G21796-072 
1/16W 1% 4.75K 
EMPTY 
R25W114 
0402 CHIP 
R25W148 1/16W 
0402 
1/16W 
G21796-072 
1% 4.75K R25W108 
1% 
0402 CHIP G21796-072 
1/16W 4.75K R25W107 
0402 
1% 1/16W 4.75K R25W111 
EMPTY G21796-072 
0402 
4.75K 
CHIP 
R25W146 
G21796-072 
1/16W 1% 
0402 
G21796-072 
1% 4.75K 
EMPTY 
0402 EMPTY 
R25W106 
G21796-027 0402 
0402 
EMPTY 
1% G21796-027 
R25W104 
R25W96 
1% R25W102 
G21796-072 EMPTY 
0402 
4.75K 
4.75K 
EMPTY G21796-072 
4.75K 
0402 
R25W101 
G21796-072 
1/16W 1% 
4.75K TP FAB1 NOPOP RES 0227 
TP FAB1 POP R25W101 0217 
TP FAB4 NOPOP R25W101 20170124 
146 
147 
146 
147 
146 162 246 
144 
162 246 146 
147 
146 
147 
147 
147 186 
139 147 121 
147 
147 
147 
145 190 158 
146 162 246 
146 
146 
146 
146 
GPIOS7 
RMII_BMC_PCH_SPRNGVLLE_TXD0_R 
BMC_STRAP_BIT17 
TP_RGMII2TXD2_GPIOU2 
SPI_BMC_BT_DO 
PU_JTAG_BMC_RTCK 
SPI_BMC_BT_DI 
TP_RGMII2TXD3_GPIOU3 
BMC_STRAP_BIT3 
RMII_BMC_PCH_SPRNGVLLE_TXD1_R 
RMII_BMC_OCP_TXD1_R 
RMII_BMC_OCP_TXEN 
RMII_BMC_PCH_SPRNGVLLE_TXEN 
RMII_BMC_OCP_TXD0_R 
TP_RGMII1TXD2_GPIOT4 
TP_RGMII1TXD3_GPIOT5 
UART_BMC_TXD5 
SPI_BMC_BT_CLK 
BMC_STRAP_BIT5 
BMC_STRAP_BIT18 
BMC_STRAP_BIT20 
BMC_STRAP_BIT27 
BOM_COST=SM_MEM 
21
21
21
2
21
21
21
1
1
21
1 2
1 2
1
1 2
21
21
21
21
21
21
21
1 2
21
21
21
21
1 2
2
2
1 2
DO NOT SCALE DRAWING SHEET 
B
AA
B
B
SIZE 
SCALE: 
234
1234
DEPARTMENT CODE 
1
DOCUMENT NUMBER REV 
P3V3_STBY 
OUT 
OUT 
OUT 
OUT 
OUT 
OUT 
OUT 
OUT 
OUT 
OUT 
OUT 
OUT 
OUT 
OUT 
OUT 
OUT 
OUT 
OUT 
OUT 
P3V3_STBY 
IN 
OUT 
OUT 
Wed Feb 08 16:35:11 2017 
150 OF 270 
BIT:[15] 
BIT:[20] 
TP FAB3 ADD R25W156 0803 
BIT:[25] 
BIT:[7] 
TP FAB1 THIS PIN ALREADY HAS PD RES R9E13 IN PAGE 139 
BIT:[16] 
TP FAB1 ADD PD RES 0227 
BIT:[3] 
BIT:[23] 
BIT:[17] 
BIT:[30] 
BIT:[24] 
TP FAB1 ADD PD RES 0227 
TP FAB1 NOPOP RES 0227 
BIT:[5] 
BIT:[31] 
BIT:[0] 
TP FAB1 THIS PIN ALREADY HAS POP PU  RES RN8F1 IN PAGE 246 
BIT:[29] 
TP FAB1 POP RES 0227 
BIT:[13] 
BIT:[22] 
BIT:[21] 
BIT:[19] 
BIT:[12] 
BIT:[6] 
TP FAB1 NOPOP RES 0104 
TP FAB1 ADD PD RES 0227 
TP FAB1 POP RES 0104 
TP FAB1 NOPOP RES 0104 
TP FAB1 ADD PD RES 0227 
BIT:[26] 
TP FAB1 STRPA BIT[0] SPI_BMC_BT_CS0_N RES IS MOVED TO PAGE 137 0308 
BIT:[18] 
BIT:[27] 
TP FAB1 RENAME RGMII2TX2, TX3 0227 
BMC STRAPS 
WIWYNN CORPORATION 



BA1 
BA0 
DML#/DBIL# 
DMU#/DBIU# 
DQSL_T 
DQSL_C 
DQSU_T 
DQSU_C VSSQ 
VSSQ 
VSSQ 
VSSQ 
VSSQ 
VSSQ 
VSSQ 
VSSQ 
VSSQ 
VSSQ 
VSS 
VSS 
VSS 
VSS 
VSS 
VSS 
VSS 
VSS 
VSS 
ALERT# 
RESET# 
CS# 
ACT# 
VPP 
CK_C 
CK_T 
NC#T7 
PAR 
TEN 
BG0 
ODT 
CKE 
ZQ 
VREFCA 
RAS#/A16 
CAS#/A15 
WE#/A14 
A13 
A12/BC# 
A11 
A10/AP 
A9 
A8 
A7 
A6 
A5 
A4 
A3 
A2 
A1 
A0 
DQL7 
DQL6 
DQL5 
DQL3 
DQL2 
DQL4 
DQL0 
DQL1 
DQU3 
DQU2 
DQU1 
DQU0 
DQU7 
DQU6 
DQU5 
DQU4 
VDDQ 
VDDQ 
VDDQ 
VDDQ 
VDDQ 
VDDQ 
VDDQ 
VDDQ 
VDDQ 
VDDQ 
VDD 
VDD 
VDD 
VDD 
VDD 
VDD 
VDD 
VDD 
VDD 
VDD 
VPP 
ROOM=SM_CONTROLLER 
120R2F-GP 
G21796-072 
1% 
1/16W 
R9F29 
1
1% 
1/16W 
R25W2 
120R2F-GP 
R25W48 
120R2F-GP 
120R2F-GP 
120R2F-GP 
120R2F-GP 
R25W35 
R25W34 
G21796-344 
120R2F-GP 
R25W30 
G21796-271 
R9E24 
2
GREEN 
CHIP 
2.7K 21 1% 
IC 
FM_HEARTBEAT_LED_A 
CHIP 
1.0% 221 
A36096-030 
C25W13 
1/16W 
G21796-294 
C25W10 
0.01UF 
0402V 
0402 
2
240 0.1UF 
10% 
RST_BMC_DDR3_BUF_IN_N 
FM_HEARTBEAT_LED 
IC 
2
U9F3 
VCC=P3V3_STBY;GND=GND 
C88419-001 
74LVC1G07 
0402 
U25W5 
16V 
2
0402V 
X7R 
1
X7R 
C25W15 
X7R 
0402V 
1
2
16V 
2
1
X7R 
0402V 
10% 
0.01UF 
A36096-045 
C25W11 
25V 
2
C25W12 1
2 X6S 
10% 
0402V 
1.0UF 5% 
CHIP 
0.0 
1/16W 
G21497-005 
R25W118 
R25W119 
4.75K 
EMPTY 
1/16W 
G21796-072 
0402 
1% 
0402 
33.2 
EMPTY 
R9F34 
21
1
2
0402 
CHIP 
1% 
1.00K 
R1T29 
2
1.00K 
0402 
CHIP 
1% 
1
R1T30 
1
FET 
6
2
Q9E1 
NTJD4001N 
E40049-001 
4.75K 
1/16W 
2
G21796-072 
0402 
1% 
CHIP 
1
R8B25 1/16W 
R9E21 
1% 
1
2
0402 
CHIP 
4.75K 
G21796-072 
4
5
2 1
0402 
1
1/16W 
A36096-045 
X7R 
125V 
10% 
G21796-026 
1/16W 
G21796-026 
Q9E1 
C97278-010 
R25W117 
1.0% 
CHIP 
0402 
A36096-030 
1/16W 
A36096-030 
10% 
FM_BMC_HEARTBEAT_N 
6.3V 
D97712-004 
16V 
120R2F-GP R25W27 
120R2F-GP R25W28 
R25W29 
120R2F-GP R25W31 
120R2F-GP R25W32 
120R2F-GP 
120R2F-GP 
120R2F-GP 
R25W36 120R2F-GP 
120R2F-GP 
120R2F-GP 
120R2F-GP 
120R2F-GP 
120R2F-GP 
120R2F-GP 
120R2F-GP 
R25W51 120R2F-GP 
R25W52 120R2F-GP 
120R2F-GP 
R25W1 
R25W3 
R25W4 120R2F-GP 
R25W5 120R2F-GP 
120R2F-GP R25W6 
120R2F-GP R25W7 
120R2F-GP R25W8 
R25W12 120R2F-GP 
R25W11 120R2F-GP 
120R2F-GP R25W9 
120R2F-GP R25W10 
R25W13 120R2F-GP 
R25W16 120R2F-GP 
R25W15 120R2F-GP 
R25W14 120R2F-GP 
120R2F-GP R25W17 
120R2F-GP R25W18 
R25W20 120R2F-GP 
R25W19 120R2F-GP 
R25W24 120R2F-GP 
R25W23 120R2F-GP 
R25W22 120R2F-GP 
R25W21 120R2F-GP 
120R2F-GP R25W26 
R25W25 120R2F-GP 
E40049-001 
FET 
NTJD4001N 
3
FM_HEARTBEAT_LED_K 
R25W50 
R25W49 
120R2F-GP 
120R2F-GP 
120R2F-GP 
0.1UF 
16V 
0.1UF 
1C25W14 
1/16W 0402 
C25W18 
SC1U16V3KX-2GP 
COG 
C25W16 
A36095-026 
100.0PF 
1 0.22UF 
C1W20 
0402 
10% 
1 2
R1T40 
CHIP 0402 
49.9 1/16W 1% 
G21796-047 
1 2
G21796-047 
1% 
0402 CHIP 
R1T28 1/16W X7R 
A36096-155 
H5AN4G6NAFR-TFC-GP 
R25W33 
0402V 
2
10% 
DS9E1 
R25W47 
R25W46 
R25W45 
R25W44 
R25W43 
R25W42 
R25W41 
R25W40 
R25W39 
R25W38 
R25W37 
5% 
50V 
C25W17 
0402LF 
SC1U16V3KX-2GP 
49.9 
4
2
G21796-074 
CHIP 
RST_BMC_DDR3_R_N 
4.75K 
TP FAB3 CHANGE RES 0823 
TP FAB3 ADD RES AND CAP 0803 
R1T40 AND R1T28 SHOULD BE 50 OHM 
TP FAB4 NOPOP U9F3 AND R9F29 20170206 
143 
143 
143 
143 
143 151 
143 151 
143 151 
143 151 
143 151 
143 151 
143 151 
143 151 
146
151
143 151 
143 151 
143 151 
143 151 
143 151 
143 151 
143 151 
143 151 
143 151 
146 151 
143 151 
143 151 
143 151 
157 
146 151 
143 151 
151 
143 
143 
143 
143 
143 
143 
143 
143 151 
143 
143 
143 
143 
143 151 
143 151 
119 146 
143 
143 151 
143 
143 
143 
143 
143 151 
143 
143 151 
0402 
0402 
0402 
0402 
0402 
0402 
0402 
0402 
0402 
0402 
0402 
0402 
0402 
0402 
0402 
0402 
0402 
0402 
0402 
0402 
0402 
0402 
0402 
0402 
0402 
0402 
0402 1/16W 
120OHM 
1/16W 
1/16W 
1/16W 
0402 
0402 1/16W 
1% 120OHM 
120OHM 1/16W 
1/16W 
1/16W 1% 
1% 
120OHM 
120OHM 
120OHM 
120OHM 
120OHM 120OHM 1% 1/16W 
0402 
1/16W 
0402 
0402 
0402 
0402 
0402 
10% 
X6S 
0603 
NOPOP 
1% 120OHM 
1% 120OHM 
1% 1/16W 120OHM 
1% 1/16W 120OHM 
1% 1/16W 120OHM 
1% 1/16W 120OHM 
1% 1/16W 120OHM 
1/16W 1% 120OHM 
1% 1/16W 120OHM 
1% 1/16W 120OHM 
1% 120OHM 
1/16W 1% 
1% 
1% 120OHM 
1/16W 1% 120OHM 
1/16W 1% 120OHM 
1/16W 1% 120OHM 
1/16W 1% 
1% 120OHM 
1% 
1/16W 
1% 120OHM 
1/16W 1% 120OHM 
1/16W 
1% 1/16W 120OHM 
1/16W 1% 120OHM 
1/16W 1% 
1% 1/16W 
1% 1/16W 
1% 1/16W 
1% 1/16W 
1/16W 120OHM 
1% 120OHM 
1% 1/16W 120OHM 
120OHM 
1% 120OHM 
1/16W 1% 120OHM 
1% 1/16W 
1% 1/16W 120OHM 
1/16W 1% 120OHM 
1% 1/16W 120OHM 
1% 1/16W 120OHM 
1% 1/16W 120OHM 
1% 1/16W 120OHM 
1% 120OHM 
1% 1/16W 120OHM 
1% 1/16W 120OHM 
1% 1/16W 120OHM 
1% 1/16W 120OHM 
1% 120OHM 
120OHM 
120OHM 
120OHM 1% 
1/16W 
1/16W 
1/16W 
1/16W 
0402 
0402 
0402 
0402 
0402 
0402 
0402 
0402 
0402 
0402 
0402 
0402 
0402 
0402 
0402 
0402 
0603 
X5R 
10% 
1UF 
E15431-003 
C25W19 
6.3V 
4.7UF 
1UF 
10% 
16V 
X5R 
0603 
120OHM 
16V 
NOPOP 
NOPOP 
143 151 
143 151 
143 151 
143 151 
143 151 
143 151 
143 151 
143 151 
143 151 
143 151 
151 
151 143 
143 151 
146 151 
143 151 
143 151 
143 151 
143 151 
143 151 
143 151 
143 151 
143 151 
143 151 
143 151 
143 151 
143 151 
143 151 
143 151 
146 151 
143 151 
BMC_M_A11 
BMC_M_A7 
BMC_M_A8 
BMC_M_A9 
BMC_M_A10 
BMC_M_A3 
BMC_M_A2 
BMC_M_A1 
BMC_M_BG0 
BMC_M_BA1 
BMC_M_DQ11 
BMC_M_DQ10 
BMC_M_DQ9 
BMC_M_DQS1_DP 
BMC_M_MACT_N 
BMC_M_CLK_DN 
BMC_M_A11 
BMC_M_A9 
BMC_M_A7 
BMC_M_A13 
BMC_M_A5 
BMC_M_A0 
BMC_M_RST_N 
BMC_M_A6 
BMC_M_A8 
BMC_M_A10 
BMC_M_A12 
BMC_M_WE_N 
BMC_M_CAS_N 
BMC_M_CKE 
BMC_M_RAS_N 
BMC_M_CLK_DP 
BMC_M_RST_N 
BMC_M_CS_N 
BMC_M_BG0 
BMC_M_A3 
BMC_M_PAR 
BMC_M_VREFCA 
BMC_M_MALERT_N 
BMC_M_ODT 
BMC_M_PAR 
BMC_M_DQ7 
BMC_M_DQ6 
BMC_M_DQ5 
BMC_M_DQ4 
BMC_M_DQ3 
BMC_M_DQ2 
BMC_M_DQ1 
BMC_M_A4 
BMC_M_DQS0_DN 
BMC_M_DQS0_DP 
BMC_M_DQ15 
BMC_M_DQ0 
BMC_M_A1 
BMC_M_A2 
BMC_M_ODT 
BMC_M_RST_N 
BMC_M_RAS_N 
BMC_M_CAS_N 
BMC_M_WE_N 
BMC_M_A0 
BMC_M_BA0 
BMC_M_A4 
BMC_M_A5 
BMC_M_A6 
BMC_M_DQ8 
BMC_ZQ 
BMC_M_VREFCA 
BMC_M_DQ12 
BMC_M_DQ13 
BMC_M_DQ14 
BMC_M_DQS1_DN 
BMC_M_DM1 
BMC_M_CLK_DP 
BMC_M_BA0 
BMC_M_DM0 
BMC_M_BA1 
BMC_M_CLK_DN 
BMC_M_CLK 
BMC_M_MACT_N 
BMC_M_A13 
BMC_M_A12 
BMC_M_CKE 
BMC_M_MALERT_N 
BMC_M_CS_N 
S
D
G
S
D
G
0402 
D97712-011 
X6S 
10% 
16V 
1.0UF 
C25W5 C25W6 
16V 
X6S 
D97712-011 
0402 
X6S 
C25W1 C25W3 
10% 10% 
16V 
X6S 
1.0UF 
0402 
D97712-011 
1.0UF 
16V 16V 
1.0UF 1.0UF 
10% 
0402 
16V 
10% 
X6S 
D97712-011 
0402 
C25W2 
1.0UF 
0402 
D97712-011 
X6S 
10% 
C25W4 
D97712-011 
CAD NOTE: 
1
1 2
D9 
1
2
2
1
A9 
F9 
M7 
T2 
R1 
D2 
D1 R3 
P3 
A7 
K2 
F8 
L2 
M3 
B3 
F7 
H7 
B9 
L9 
E9 
F3 
B7 
E8 
D8 
C9 
N1 
M9 
K9 
K1 
G8 
B2 
P9 
P1 
L3 
K8 
K7 
N9 
K3 
M8 
P7 
J7 
D7 
D3 
C8 
G9 
G1 
F2 
C1 
T9 
J9 
J1 
T8 
R8 
P2 
L8 
C3 
G2 
G3 
F1 
H1 
C2 
L7 
M2 
H2 
H8 
J3 
N7 G7 
C7 
J2 
E3 
H3 
R9 
M1 
J8 
R7 
A1 
R2 
1
2
1
2
2
1
P8 
L1 
B1 
T7 
N3 
N8 
21
21
1 2
1
1 2
1 2
1 2
2
1 2
1 2
21
1 2
1 2
1 2
1 2
1 2
2
1 2
1
1 2
1 2
1 2
1 2
1 2
2
21
1 2
21
1 2
1 2
1 2
1 2
1 2
1 2
1 2
1 2
1 2
21
1 2
1 2
21
21
21
21
21
1 2
21
21
21
21
2
1
2
1
A3 
B8 
A8 
A2 
E1 
H9 
N2 
E2 
E7 
T1 
T3 
DO NOT SCALE DRAWING 
P1V2_AUX_BMC 
P1V2_AUX_BMC 
P2V5_AUX_BMC 
P1V2_AUX_BMC 
P1V2_AUX_BMC 
P1V2_AUX_BMC 
P1V2_AUX_BMC 
SHEET 
B
AA
B
B
SIZE 
SCALE: 
234
1234
DEPARTMENT CODE 
1
DOCUMENT NUMBER REV 
BI 
BI 
BI 
BI 
BI 
BI 
BI 
BI 
BI 
BI 
BI 
BI 
BI 
BI 
BI 
BI 
BI 
BI 
BI 
BI 
BI 
BI 
BI 
BI 
BI 
BI 
BI 
BI 
BI 
BI 
BI 
BI 
BI 
BI 
BI 
IN OUT 
BI 
OUT 
IN 
P3V3_STBY 
P3V3_STBY 
P3V3_STBY 
BI 
BI 
BI 
BI 
BI 
BI 
BI 
BI 
BI 
BI 
BI 
BI 
BI 
BI 
BI 
2 1
1 2
TTL1G07_A 
Wed Feb 08 16:35:11 2017 
151 OF 270 
TP FAB3 NOPOP R25W3, 4, 29 0803 
TRACE WIDTH >= 15 MILS 
TP FAB3 NOPOP CAP 0805 
TP FAB3 CHANGE R25W30 0803 
TP FAB1 CHANGE CONNECTION 0330 
TP FAB1 NOPOP R9F34 0121 
PLEASE PLACE LED NEAR BMC 
NOPOP NOPOP 
NOPOP 
BMC DDR4 MEMORY 
WIWYNN CORPORATION 



1% 
PLACE PU RESISTORS NEAR GTL2014 
5% 
150.0 
CHIP 
H_CPU1_MEMGHJ_MEMHOT_G_N 
H_CPU0_MEMDEF_MEMHOT_G_R_N 
1/16W 
H_CPU0_DEF_MEMHOT_LVT3_R_N 
1
USE SHARED PADS FOR 0OHM 
150.0 
1% 
16V 
G21796-017 
1/16W 
1% 
100.0 0.1UF 
P0V7_GTL2014_2 
EMPTY 
1/16W 
1% 
49.9 
R1W35 
374R2F-1-GP 
R1U43 
R1U37 
0402V 
C1U22 
0402 
X7R 
10% 
A36096-030 
CHIP 
10% 
D97712-011 
CHIP 
1
CHIP 
USE SHARED PADS FOR 0OHM 
2
1
G21497-005 CHIP 
R9G32 
R9G28 
G21497-005 
5% 
1/16W 
0402 
H_CPU1_MEMKLM_MEMHOT_G_R_N 
H_CPU1_MEMGHJ_MEMHOT_G_R_N 
H_CPU0_MEMABC_MEMHOT_G_R_N 
H_CPU0_MEMABC_MEMHOT_G_N 
H_CPU0_MEMDEF_MEMHOT_G_N H_CPU0_ABC_MEMHOT_LVT3_R_N 
H_CPU0_MEMDEF_MEMHOT_G_PCH_N 
P0V7_GTL2014_2 
PD_DIR_2 
H_CPU1_MEMGHJ_MEMHOT_G_PCH_N 
H_CPU1_MEMKLM_MEMHOT_G_PCH_N 
H_CPU0_MEMABC_MEMHOT_LVT3_N 
H_CPU0_MEMABC_MEMHOT_PCH_N 
H_CPU0_MEMDEF_MEMHOT_LVT3_BMC_N 
H_CPU0_MEMDEF_MEMHOT_PCH_N 
H_CPU1_MEMKLM_MEMHOT_LVT3_BMC_N 
H_CPU1_MEMGHJ_MEMHOT_LVT3_BMC_N 
H_CPU1_MEMGHJ_MEMHOT_PCH_N 
H_CPU1_MEMKLM_MEMHOT_LVT3_N 
H_CPU0_MEMABC_MEMHOT_LVT3_BMC_N 
H_CPU1_GHJ_MEMHOT_LVT3_R_N 
H_CPU1_KLM_MEMHOT_LVT3_R_N H_CPU1_MEMGHJ_MEMHOT_LVT3_K_N 
H_CPU1_MEMKLM_MEMHOT_LVT3_K_N H_CPU1_MEMKLM_MEMHOT_L VT3_N 
H_CPU0_MEMDEF_MEMHOT_LVT3_K_N 
H_CPU0_MEMABC_MEMHOT_LVT3_K_N 
H_CPU0_MEMDEF_MEMHOT_LVT3_N 
H_CPU0_MEMABC_MEMHOT_LVT3_N 
H_CPU1_MEMGHJ_MEMHOT_LVT3_N 
H_CPU1_MEMKLM_MEMHOT_PCH_N 
H_CPU0_MEMDEF_MEMHOT_LVT3_N 
H_CPU1_MEMGHJ_MEMHOT_LVT3_N 
H_CPU1_MEMKLM_MEMHOT_G_N 
H_CPU0_MEMABC_MEMHOT_G_PCH_N 
PLACE PU RESISTORS NEAR 
USE SHARED PADS WITH 
USE SHARED PADS WITH 0OHM 
0.0 
G21497-005 
R9G30 
1/16W 5% EMPTY 0402 
0.0 
5% 1/16W EMPTY 
R3N30 
0402 
G21497-005 
0.0 
CHIP 
2
5% 
1
R2U46 
0402 
G21497-005 
1/16W 
0.0 1
R1U54 
G21497-005 
2
1/16W 5% CHIP 0402 
0.0 
1/16W 
1 2
5% CHIP 
G21497-005 
R9G29 
0402 
2
5% 1/16W 
0.0 1
0402 CHIP 
R2U47 
G21497-005 
G21497-005 
2
R1U59 
0.0 
0402 5% CHIP 
1
1/16W 
1/16W 0402 5% 
R9G33 
20.0 
0.0 
2
0402 5% 1/16W 
1
G21497-005 
0.0 2
2
1
0402 
R1U61 
EMPTY 
G21497-005 
1/16W 
5% 
0.0 1
G21497-005 
1/16W 
5% 
0.0 
R1U57 
2 EMPTY 
0402 
G21497-005 
2
0402 
5% 
1/16W 
EMPTY 
0.0 1
R1U62 R1U55 
0.0 
5% 
1/16W G21497-005 
1
2
0402 
EMPTY 
G21497-005 
2
0402 
1/16W 
EMPTY 
1
5% 
0.0 
R2U49 
0402 
CHIP 
1/16W 
2
5% 
G21497-005 
1
R1U60 
0.0 
0402 
1/16W 5% 
G21497-005 CHIP 
2
R1U53 
10.0 
1/16W 
CHIP 
0402 
1% 
150.0 
G21796-009 
R7P21 
2
1
R7P5 
2
1
1/16W 
CHIP 
1% 
150.0 
G21796-009 
0402 
0402 CHIP 1% 
R1U46 
1
33.2 1/16W G21796-074 
2
150.0 
1% 
1
R4P20 
2
1/16W 
0402 
G21796-009 
150.0 1
0402 
G21796-009 
1% 
1/16W 
CHIP 2
R4P17 
R1U35 
CHIP 
G21796-009 
0402 
2
1
1/16W 
2
1% 
CHIP 
0402 
R1U41 
G21796-009 
CHIP 2
0402 
1/16W 
150.0 
R2U41 
1
G21796-009 
2 CHIP 
0402 
1 150.0 
R2U40 
1% 
1/16W 
G21497-005 
0402 
2
5% 
1/16W 
EMPTY 
0.0 1
R2U51 
G21497-005 
1
2
0402 
1/16W 
EMPTY 
0.0 
R1U56 
1/16W 
0402 
CHIP 
2
G21497-005 
5% R1U58 
0.0 1
2
1
1/16W 
0402 
5% 
0.0 
G21497-005 
R9G27 
EMPTY 
0402 
1/16W 
CHIP G21497-005 
2
5% R9G34 
10.0 
1.00K 
R1U30 
1% 1/16W 0402 G21796-026 
2 1
CHIP 
X6S 
0402 
1
16V 
C1U19 
1.0UF 
2
CHIP 
R1U34 
1
0402 G21796-074 1/16W 1% 33.2 
1/16W G21796-074 0402 
1 2
R1U36 
CHIP 1% 33.2 
2 1
CHIP 0402 1/16W 33.2 1% 
R9G31 
G21796-074 
1/16W 
0.0 
5% 
R2U45 
G21497-005 
EMPTY 0402 
5% EMPTY 0402 
G21497-005 
R3P63 
0.0 
1/16W 
9
14 
6
3
5
7
8
11 
D66151-001 
13 
12 
10 
IC 
4
1
U9G1 
2
2
1
G21796-047 
0402 
55 94 95 
152 
94 95 21 
94 95 21 
152 
152 
121 
147 
121 
147 
147 
121 
152 
147 
152 
152 
152 
152 
121 
152 
152 
55 94 95 
1/16W 
1% 
374 OHM 
CORRESPONDING CPU 
STEERING RESISTORS 
33.2OHM RESISTORS 
STEERING RESISTORS 
STEERING RESISTORS 
0402 
1
2
1
2
21
1 2
21
21
CAD NOTE: 
CAD NOTE: 
CAD NOTE: 
CAD NOTE: 
CAD NOTE: 
CAD NOTE: 
DESIGN NOTE: 
DESIGN NOTE: 
VREF IS SET AT 2/3 OF VCCIO 
THE PINS 'BX' ARE INPUTS & 'AX' OUTPUTS ARE PUSH-PULL. 
THE GTL2014 IS BEING USED AS GTL TO LVTTL CONVERTER, SO 
DO NOT SCALE DRAWING SHEET 
B
AA
B
B
SIZE 
SCALE: 
234
1234
DEPARTMENT CODE 
1
DOCUMENT NUMBER REV 
OUT 
OUT 
OUT 
OUT 
OUT 
OUT 
OUT 
IN 
IN 
IN 
IN 
PVCCIO_CPU1 PVCCIO_CPU0 
PVCCIO_CPU1 PVCCIO_CPU0 P3V3 
IN 
OUT 
IN 
IN 
IN 
IN 
OUT 
OUT 
OUT 
PVCCIO_CPU0 P3V3 
OUT 
OUT 
2 1
152 OF 270 
Wed Feb 08 16:35:11 2017 
DIR 
VREF 
VCC 
GND<0> 
GND<1> 
GND<2> 
B0 
B1 
B2 
B3 
A0 
A1 
A2 
A3 
TARGET 0.7V 
IE ONLY (NO BMC) 
STUFF UNSTUFF 
R9G33 
R1U59 
R9G32 
R9G28 
R2U47 
R9G29 
R2U46 
U9G1 
R1U54 
R1U60 
R9G34 
R1U53 
R1U58 
R9G30 
R7D35 
R2U45 
R3N30 
R1U55 
R9G27 
R1U61 
R2U49 
R1U57 
R2U51 
ROOM=PROC_SIDEBAND 
R1U62 
R1U56 
TP FAB3 CHANGE R1U43 AND CONNECT TO P3V3 0805 
TP FAB3 ADD R1W35 0803 
MEMHOT LVT3 LEVEL TRANSLATION 
GTL2014 
WIWYNN CORPORATION 



CLK 
DI/IO0 
NC#14 
NC#13 
NC#12 
NC#11 
GND 
WP#/IO2 
DO/IO1 
CS# 
NC#6 
NC#5 
NC#4 
RESET# 
VCC 
HOLD#/IO3 
1% 
CHIP 
USE ALT SYMBOL ASSOCIATED WITH PART FOOTPRINT 
THIS PART WILL BE IN SOCKET, PLEASE 
0402 
C7F1 
0.01UF 
X6S 
D97712-004 
4
0402V 
16 
TP_SPI_0_2 
2 X7R 
10% 
A36096-045 
TP_SPI_0_1 
TP_SPI_0_0 
D97712-004 
R3T9 
G21796-016 
1/16W 
10.0K 
CHIP 
1% 
TP_SPI_1_6 
TP_SPI_1_4 
EMPTY 
0402 
1/16W 
G21796-072 
0402 
CHIP 
G21796-074 
EMPTY 
1% 
SPI_SWITCH_MOSI_R1 
SPI_MISO_R1 
CHIP 
G21796-074 
CHIP 
33.2 
33.2 
G21796-074 
0402 
0402 
0402 
0402 
21
R8F7 
SPI_CS0_SECONDARY_R_N 
SPI_SWITCH_MISO 
SPI_SWITCH_MOSI 
SPI_SWITCH_CLK 
SPI_BIOS_SOCKET_IO2 
1% 1/16W 33.2 
PU_BIOS_SPI_WP1_N 
PU_BIOS_SPI_HOLD1_N 
R3U1 
33.2 
1/16W 
R3T12 
PU_BIOS_SPI_WP1_N 
1/16W 
G21796-016 0402V 0402V 
A36096-045 
C3T5 
0.01UF 
25V 
C3T4 
1.0UF 
6.3V 
TP_SPI_1_5 
TP_SPI_1_3 
TP_SPI_1_2 
TP_SPI_1_0 
X6S 
TP_SPI_1_1 
G21796-074 
0402 
SPI_CS0_PRIMARY_R_N 
1/16W 0.0 
R7W5 
2
33.2 1% 
0402 
2
R8F8 
SPI_SWITCH_CLK 
1.0UF 1 C7F2 
0402V 
6.3V 
1
2
25V 
10% 
2
10% 
1
0402 
1 2
R7F32 
CHIP 
G21796-016 
1/16W 10.0K 1% 
3
7
15 
8
10 
14 
13 
12 
11 
2
U7F1 
5
6
9
IC 
1
R3T3 
4.75K 
22
1
R3T2 1 2
1/16W 
R3T1 
1
1/16W 33.2 
G21796-016 
CHIP 
1% 
R7F28 
1/16W 
1
2
0402 
10.0K 
R7F30 
10.0K 1
1% 
EMPTY 
1/16W 
2
0402 
2
R3T4 
1
0402 10.0K CHIP 
1
2
10.0K 
1% 2
1
R3T10 
1
2
2
PU_BIOS_SPI_HOLD0_N 
SPI_BIOS_SOCKET_IO3 
PU_BIOS_SPI_WP0_N 
TP_SPI_0_6 
TP_SPI_0_5 
TP_SPI_0_4 
TP_SPI_0_3 
PU_BIOS_SPI_HOLD1_N 
X7R 
W25Q256FVFIG-GP 
U3T1 
1% 
G21796-016 
0402 
1/16W 
G21796-074 
R7F3 
CHIP 
SPI_BIOS_SOCKET_IO3 
H25002-001 
1% 
R3T5 
4.75K 
CHIP 
1% 
33.2 
1
1
5% 
1
2
4.75K 
1/16W 
G21796-072 
R7F5 
4.75K 
R7F6 
R7F29 
2
1
CHIP 
1SPI_SWITCH_MOSI 
SPI_SWITCH_MISO 
G21796-072 
1/16W 
1% 
EMPTY 
1% 
G21497-005 
R7F37 
PU_SPI1_RST 
SPI_CLK_R1 
1% 
G21796-072 
1/16W 
33.2 
33.2 1% 
G21796-074 
R7F4 
33.2 
1/16W 
CHIP 
0402 
0402 
1/16W 
CHIP 
SPI_BIOS_SOCKET_IO2 
PU_BIOS_SPI_WP0_N 
PU_BIOS_SPI_HOLD0_N 
10% 
0402 
G21796-016 
TP FAB3 ADD RES 1017 
154 
153 154 
154 153 
154 153 
154 153 
153 
153 
153 
154 
154 153 
153 
154 153 
153 
153 
154 153 
154 153 
153 154 
154 153 
154 
153 
153 
1% 
SPI_CLK_R0 
SPI_SWITCH_MOSI_R0 
GROUP=NI_BIOS_ROM2 
GROUP=NI_BIOS_ROM2 
GROUP=NI_BIOS_ROM2 
GROUP=NI_BIOS_ROM2 
GROUP=NI_BIOS_ROM2 
GROUP=NI_BIOS_ROM2 
GROUP=NI_BIOS_ROM2 
GROUP=NI_BIOS_ROM2 
0402 
G21796-074 
G21796-074 
GROUP=NI_BIOS_ROM2 
GROUP=NI_BIOS_ROM2 
CHIP 
CHIP 
GROUP=NI_BIOS_ROM2 
1/16W 
1/16W 
GROUP=NI_BIOS_ROM2 
GROUP=NI_BIOS_ROM2 
PU_SPI0_RST 
1% 
1% 
0402 
1/16W 
SPI_MISO_R0 
CHIP 1% 
CHIP 
0402 
1/16W 
0402 
G21796-074 
SPI_SWITCH_CS0_N 
G21796-074 
ROOM=SM_MEM 
CAD NOTE: 
DESIGN NOTE: 
CAD NOTE: 
CAD NOTE: 
PLACE CAPS NEAR VCC PIN ON W25Q256 COMPONENT 
PLACE CAPS NEAR VCC PIN ON W25Q256 COMPONENT 
12 
13 
10 
1 2
1
7
16 
2
2
21
2 4
1
3
14 
15 
11 
8
5
6
9
21
21
1 DO NOT SCALE DRAWING SHEET 
B
AA
B
B
SIZE 
SCALE: 
234
1234
DEPARTMENT CODE 
1
DOCUMENT NUMBER REV 
P3V3_STBY 
IN 
IN 
IN 
OUT 
P3V3_STBY 
P3V3_STBY 
OUT 
OUT 
P3V3_STBY 
IN 
IN 
IN 
IN 
IN 
OUT 
IN 
P3V3_STBY 
OUT 
P3V3_STBY 
IN 
IN 
IN 
IN 
OUT 
IN 
IN 
153 OF 270 
Wed Feb 08 16:35:11 2017 
CLK 
CS_N 
DI_IO<0> DO_IO<1> 
GND 
NC<6> 
NC<5> 
NC<4> 
NC<3> 
NC<2> 
NC<1> 
NC<0> 
VCC 
WP_N_IO<2> HOLD_N_IO<3> 
RESET_N 
U7F1 IS SOCKET. 
SECONDARY FLASH - BOTTOM SIDE OF BOARD 
PRIMARY FLASH - TOP SIDE OF BOARD 
32MB FLASH = H25002-001 
WINBOND W25Q256FVFIQ 
MICRON MT25QL512ABA8ESF 
64MB FLASH = H60781-001 
BMC AND PCH SHARED SPI FLASH 
W25Q256 
WIWYNN CORPORATION 



VCC 
YA 
ID1 
ID0 
IC0 
IA1 
GND 
YD 
YC 
IB0 
IB1 
IC1 
YB 
IA0 
S
EN_N 
PI3B3257A 
VCC 
YA 
ID1 
ID0 
IC0 
IA1 
GND 
YD 
YC 
IB0 
IB1 
IC1 
YB 
IA0 
S
EN_N 
PI3B3257A 
SPI_CS0_SECONDARY_N 
E60229-001 
VCC=P3V3_STBY;GND=GND 
SPI_CS0_PRIMARY_N 
VCC=P3V3_STBY;GND=GND 
U2T3 
SPI_CS0_SECONDARY_R_N 
CHIP 
G21796-267 
74LVC1G32 
IC 
1
2 200.0 
G21796-004 
1/16W 
R2T13 
1% 
SPI_CS0_PRIMARY_R_N 4
E60229-001 
C79254-001 
0402 
15 
G21796-072 
Q8F1 
G21796-072 
1
1% 
CHIP 2
2
1/16W 
1
0402V 
A36096-030 
CHIP 
E16801-001 
1/16W 
1 2
0402 5% 
R8F6 
CHIP 0.0 
G21497-005 
13 
1
1% 
1/16W 
CHIP 
R2T11 C2T12 
0.1UF 
1.0% 
74LVC1G32 
2
1
4.75K 
1
0402 
2
3
2N7002 
2
1
CHIP 
1/16W 
1% 
G21796-016 
CHIP 
1/16W 
R1U6 
10.0K 
1% 
0402 
2
1
0402V 
A36096-030 
X7R 2
10% 
16V 
1
C2T8 
0.1UF 
2
1
X7R 
16V 
10% 
C8E18 
A36096-030 
0.1UF 
10% 
16V 
X7R 
1
2
75 
2
R2T9 
U8F1 IC 
12 
9
7
4
16 
1
14 
10 
11 
6
5
3
2
8
42
U2T1 
E16801-001 
IC 
12 
9
7
16 
1
13 
14 
10 
11 
6
5
3
8
15 
G21497-005 
0402 
CHIP 
1/16W 5% 
1
0.0 R2T2 
2
1
0.0 1/16W 0402 
CHIP 
5% 
G21497-005 2
R2R12 
0402V 
A36096-030 
C2T1 
0.1UF 
10% 
16V 
X7R 
1
2
FM_BACKUP_BIOS_SEL_N 
SPI_SWITCH_CS0_N 
SPI_BMC_DI 
SPI_SWITCH_MISO 
SPI_SWITCH_CLK 
SPI_SWITCH_MOSI 
SPI_SWITCH_CS0_N 
SPI_PCH_IO3_R1 SPI_PCH_IO3 
FM_BIOS_SPI_BMC_CTRL 
SPI_PCH_IO2 SPI_PCH_IO2_R1 
TP_SPI_SWITCH1_11 
TP_SPI_SWITCH1_6 
TP_SPI_SWITCH1_3 
TP_SPI_SWITCH1_10 
TP_SPI_SWITCH1_13 
TP_SPI_SWITCH1_14 
SPI_PCH_CS0_N 
SPI_PCH_MISO 
SPI_BMC_DO 
SPI_PCH_MOSI 
FM_BIOS_SPI_BMC_CTRL 
SPI_PCH_CLK 
SPI_BMC_CLK 
SPI_BIOS_SOCKET_IO2 
SPI_BIOS_SOCKET_IO3 
TP_SPI_SWITCH1_9 
SPI_PCH_MISO_R 
FM_BIOS_SPI_BMC_CTRL 
TP_SPI_SWITCH1_12 
0402 
0402V 
FET 
U2T2 
IC 
4
R2T6 
FM_DUAL_BIOS_SEL_N 
4.75K 
0402 
G21796-016 
1/16W 
R2T8 
0402 
10.0K 
153 
153 
120 147 
154 153 
144 
153 
153 
153 
153 154 
121 125 
147 154 
111 121 125 
144 
121 
184 121 
144 
111 121 125 184 
147 154 
121 184 
144 
153 
153 
147 154 
GROUP=NI_BIOS_ROM2 
GROUP=NI_BIOS_ROM2 
GROUP=NI_BIOS_ROM2 
GROUP=NI_BIOS_ROM2 
GROUP=NI_BIOS_ROM2 
GROUP=NI_BIOS_ROM2 
GROUP=NI_BIOS_ROM2 
SPI_BMC_CS0_N 
S
D
G
CAD NOTE: 
CAD NOTE: 
DESIGN NOTE: 
CAD NOTE: 
SPI_SWITCH_CS0_N FM_BACKUP_BIOS_SEL_N 
N
O
1
BIOS 
1
2
FM_BIOS_SPI_BMC_CTRL NET SHOULD BE PULLED DOWN 
SO THAT PCH IS DEFAULT BUS AND FOR 
BMC SKU, THE BMC CAN PULL THIS NET HIGH 
TO CONNECT BMC TO SPI FLASH 
DO NOT SCALE DRAWING SHEET 
B
AA
B
B
SIZE 
SCALE: 
234
1234
DEPARTMENT CODE 
1
DOCUMENT NUMBER REV 
P3V3_STBY 
IN 
IN 
IN 
OUT 
OUT 
IN 
IN 
IN 
OUT 
IN 
IN 
IN 
IN 
IN 
OUT 
OUT 
OUT 
IN 
P3V3_STBY 
P3V3_STBY 
P3V3_STBY 
OUT 
OUT 
P3V3_STBY 
P3V3_STBY 
P3V3_STBY 
IN 
OUT 
OUT 
154 OF 270 
Wed Feb 08 16:35:12 2017 
PI3B3257A TRUTH TABLE 
L
H
E# 
X
(DEFAULT) 
L
X
FUNCTION 
S=0 
S=1 
H
L L
H
HIZ 
N
N
Y
H
L
L
S
X
PRIMARY 
(DEFAULT) 
SECONDARY 
DISABLE 
PLACE 0.1UF CAP NEXT TO VCC PIN 
PLACE 0.1UF CAP NEXT TO VCC PIN 
ON 74LVC1G32 
ON 74LVC1G32 
PLACE R8F6 CLOSE TO U8F1 
PCH AND BMC SHARED SPI FLASH MUX 
WIWYNN CORPORATION 



ROOM=MIO_VIDEO 
LED_POSTCODE_3 
G21796-066 
VCC=P3V3_STBY;GND=GND 
C88419-001 
R9A7 
1/16W 1/16W 0402 
SPA_SIN_SW_R 
R6W19 
G21497-005 
2.21K 
1% 
SPA_5V_SIN_SW_D 
0402 
C73510-001 
1
LED_POSTCODE_7_R 
SPA_5V_SIN_SW 4
2
G21796-016 
CHIP 
1/16W 
10.0K 
R6W40 
2
BAT54WS 
CR9W1 
SMLF 
1% 
1
IC 
2
R9A5 
A36096-030 
1
LED_POSTCODE_4_R 
LED_POSTCODE_6_R 
LED_POSTCODE_0_R 
LED_POSTCODE_5 
LED_POSTCODE_6 
LED_POSTCODE_4 
LED_POSTCODE_7 
LED_POSTCODE_2 
LED_POSTCODE_7_R 
LED_POSTCODE_2_R 
LED_POSTCODE_6_R 
LED_POSTCODE_5_R 
LED_POSTCODE_4_R 
LED_POSTCODE_3_R 
LED_POSTCODE_0_R LED_POSTCODE_0 
LED_POSTCODE_2_R 
LED_POSTCODE_1_R 
P5V_STBY_DBG 
FM_CPLD_DBG_PWR_EN_R_N FM_CPLD_DBG_PWR_EN_N 
FM_CPLD_DBG_PWR_EN 
LED_POSTCODE_1 
0402 1/16W 1% 
1 2
R1L11 
10.0 
G21796-066 
R1L14 
1 2
1/16W 
G21796-066 
1% 10.0 0402 
0402 
21
R1L18 
1/16W 10.0 1% 
G21796-066 
G21796-066 
0402 1% 1/16W 
R1L20 
1 2
10.0 
0402 
R1L24 
1
1/16W 
2
1% 
G21796-066 
10.0 
0402 10.0 
G21796-066 
1% 1/16W 
2
R1L25 
1
0402 
G21796-066 
1/16W 1% 
R1L30 
1 2
1% 10.0 1/16W 
R1L32 
0402 
21
NTJD4001N 
FET 
E40049-001 
Q1L2 
Q1L2 
NTJD4001N 
FET 
4
3
5
0402 1% 10.0 1/16W 
G21796-066 
1
R1L2 
2
16V 
10% 
2 X7R 
1 C1T56 
11 
13 
7
5
3
12 
8
10 
6
2
4
CONN 
J9A2 
G21796-010 
0402 
CHIP 
100.0K 
1% 
1/16W 
R1L9 
1
2
H45581-001 
21
IC 
F1L1 
10% 
0402 
CHIP 
1/16W 
0402V 
E40049-001 
16V 
H54902-001 
LED_POSTCODE_3_R 
LED_POSTCODE_1_R 
X7R 
CHIP 2
G21796-112 
1
2
5% 
1
R9A8 
0402 CHIP 
5% 
2
G21497-005 
0402 
CHIP 
G21796-040 
SPA_MID_DBG1_RX 
0.1UF 
A36096-030 
0402V 
9
FM_DEBUG_RST_BTN_N 
10.0 
1/16W 
0.0 
20.0K 1
FM_UART_SWITCH_N 
0.0 
14 
LED_POSTCODE_5_R 
1% 0.1UF 
C9A1 
U9A1 
IC 
74LVC1G07 
CHANGE NET NAME FOR RX AND  GATE1123 
TP FAB3 ADD DIODE 1027 
TP FAB3 CHANGE R9A5 0803 
155 247 
176 
155 247 
155 247 
155 247 
146 
146 
146 
146 
146 
247 155 
155 247 
247 155 
247 155 
247 155 
247 155 
247 155 146 
247 155 
247 155 
190 
146 
155 247 
155 247 
176 
111 247 175 190 
146 
168 247 
155 247 
CHIP 
CHIP 
CHIP 
CHIP 
CHIP 
CHIP 
CHIP 
CHIP 
CHIP 
CONFIG=069.50018.0001 
SPA_MID_DBG1_TX 
S
D
G
P5V_STBY_DGB_FS 
2
6
1
CAD NOTE: 
1 2
DO NOT SCALE DRAWING 
S
D
G
SHEET 
B
AA
B
B
SIZE 
SCALE: 
234
1234
DEPARTMENT CODE 
1
DOCUMENT NUMBER REV 
P3V3_STBY 
IN 
IN 
IN 
OUT 
OUT 
OUT 
OUT 
OUT 
OUT 
OUT 
OUT 
IN 
IN 
IN 
IN 
IN 
BI 
OUT IN 
OUT 
IN 
IN 
IN 
IN 
IN 
IN 
IN 
IN 
P3V3_STBY 
P5V_STBY 
P5V_STBY 
P12V_STBY 
P3V3_STBY 
IN 
TTL1G07_A 
155 OF 270 
Wed Feb 08 16:35:13 2017 
CONN14 
IO13 
IO11 IO9 IO7 IO5 IO3 IO1 IO2 
IO14 
IO12 IO10 IO8 
IO4 
IO6 
TP FAB3 ADD R6W40 0803 
TP FAB1 CHANGE R9A5 FRO 20K TO 15K 
TP FAB3 CHANGE CONNECTION OF J9A2.9 0803 
TP FAB1 CHANGE FUSE 0428 
0.5A 8V 
1119 
TP FAB1 RESERVE R6W19 1119 
NOPOP 
PLACE 0.1UF CAP NEXT TO VCC PIN 
ON TTL1G07_A 
BMC DEBUG HEADER 
WIWYNN CORPORATION 



1Y 
VCC 
2Y 2A 
GND 
1A 
1Y 
VCC 
2Y 2A 
GND 
1A 
ROOM=SM_THERM 
C95678-002 
10.0K 
SMB_HOST_STBY_LVC3_SCL 
RST_BMC_SYSRST_BTN_OUT_N 
SMB_SMLINK0_STBY_LVC3_SDA 
SMB_SMLINK0_STBY_LVC3_SCL 
PD_PIROM_CPU1_ADDR2 
PD_PIROM_CPU1_ADDR1 
PU_PIROM_CPU1_ADDR0 
PD_PIROM_CPU0_ADDR2 
PD_PIROM_CPU0_ADDR1 
PD_PIROM_CPU0_ADDR0 
FM_CPU_BMC_INIT H_CPU1_BMCINIT 
H_CPU0_BMCINIT 
SMB_PIROM_CPU0_SCL 
SMB_PIROM_CPU1_SCL 
SMB_PIROM_CPU0_SDA 
SMB_PIROM_CPU1_SDA 
SMB_LAN_STBY_LVC3_SCL 
SMB_LAN_STBY_LVC3_SDA 
FM_CPU1_SM_WP FM_CPU0_SM_WP 
FM_MEM_THERM_EVENT_LVT3_N FM_ADR_SMI_GPIO_N 
FM_PCH_PWRBTN_OUT_N 
RST_PCH_SYSRST_BTN_OUT_N 
FM_PCH_PWRBTN_R_N 
IRQ_BMC_PCH_NMI_STBY_R_N 
FM_BMC_PWRBTN_OUT_N 
IRQ_BMC_PCH_NMI_STBY_N 
SMB_HOST_STBY_LVC3_SDA 
SN74LVC2G07DCKR-GP 
U8G1 
SN74LVC2G07DCKR-GP 
U8F3 
1% 
1.00K 
R1C36 
1
2 CHIP 
1/16W 
0402 
G21796-026 
R1C35 
0402 
1
2
1% 
3.32K 
1/16W 
EMPTY 
G21796-027 
1% 
1
0402 
2
R3P56 
1.00K 
1/16W 
CHIP 
G21796-026 
3.32K 
R3P54 
1
2
1% 
1/16W 
EMPTY 
G21796-027 
0402 
1
R4A9 0.0 
G21497-005 
2
0402 
1
R9M20 0.0 
2
G21497-005 0402 
1
R4A8 0.0 
0402 
2
G21497-005 
1
R9M21 0.0 
2
G21497-005 0402 
G21796-016 1/16W 1% 10.0K 
21
R1C34 
1% 
2
1.00K 
1
R1C33 1/16W G21796-026 
1.00K 1% 1/16W G21796-026 
2
R1C32 
1
R6N15 
1 2
1.00K G21796-026 1/16W 1% 
1/16W 1% 
2
1.00K G21796-026 
1
R6N13 
G21796-026 1/16W 1% 
2
1.00K R6N14 
1
EMPTY 
R3D31 
1 G21497-005 0402 2
0.0 
EMPTY 0402 G21497-005 
0.0 R6D16 
1 2
33.2 G21796-074 
R2T28 
1
1% 
2
0402 CHIP 
R2T18 
G21796-047 CHIP 0402 1% 49.9 
1 2
1
CONN 
2
3
J8C1 
2
3
CONN 
C95678-002 
1
J9B2 
21
5% 
0402 
G21497-005 
R8E11 
0.0 
1/16W EMPTY 
0402V 
A36096-030 
10% 
16V 
1
X7R 2
C8F16 
0.1UF 
2 X7R 
10% 
A36096-030 
C2T35 
0.1UF 
16V 
0402V 
1
R8G2 
1
1% 
2
1/16W 
CHIP 
0402 
G21796-072 
4.75K 
R2U2 
1
2 CHIP 
4.75K 
1% 
1/16W 
0402 
G21796-072 
1
1% 
CHIP 2
1/16W 
4.75K 
R8E22 
G21796-072 
0402 
0402 1/16W 
1
R8E24 
2
33.2 1% 
CHIP 
G21796-074 
G21796-016 
CHIP 2
1
1% 
1/16W 
0402 
R8F26 
CHIP 2
0402 
1
R2T22 
10.0K 
1% G21796-016 
1/16W CHIP 
1
1% 
2
R2T35 
0402 
G21796-072 
1/16W 
4.75K 
R2T34 
4.75K 
1/16W 
G21796-072 
1% 
0402 
CHIP 2
1
FM_PCH_PWRBTN_N 
RST_BMC_SYSRST_BTN_OUT_B_N 
CONFIG=021.60545.0103 
138 159 101 102 111 247 
145 
138 159 
138 159 
55 
55 
55 
21 
21 
21 
119 164 90 55 
90 21 
21 
55 
21 
55 
138 160 182 
138 160 182 
55 21 
94 191 89 157 191 120 
119 
119 
119 
145 
120 145 
101 102 111 138 159 247 
191 118 
191 118 
CHIP 
5% 
CHIP 
1/16W 
5% 
CHIP 
1/16W 
5% 
CHIP 
1/16W 
5% 1/16W 
CHIP 
0402 
0402 CHIP 
CHIP 0402 0402 CHIP 
CHIP 0402 
0402 CHIP 
5% 1/16W 
1/16W 5% 
1/16W 
1/16W 
CONFIG=021.60545.0103 
RST_BMC_SYSRST_BTN_OUT_B_R_N 
CAD NOTE: 
CAD NOTE: 
6
43
2
1
5
3
6
2
4
5
1
DO NOT SCALE DRAWING SHEET 
B
AA
B
B
SIZE 
SCALE: 
234
1234
DEPARTMENT CODE 
1
DOCUMENT NUMBER REV 
P3V3_STBY 
OUT 
P3V3_STBY 
OUT 
OUT 
BI 
BI 
IN 
BI 
P3V3_STBY 
OUT 
OUT 
OUT OUT 
OUT 
OUT 
OUT OUT 
OUT 
IN 
BI 
IN 
IN 
BI 
IN OUT 
P3V3_STBY 
P3V3_STBY 
IN 
IN 
P3V3_STBY 
P3V3_STBY 
OUT IN 
P3V3_STBY P3V3_STBY 
OUT 
OUT 
IN 
IN 
CONN3 
CONN3 
156 OF 270 
Wed Feb 08 16:35:13 2017 
ME DEBUG HEADER 
TP FAB1 CHANGE CONFIG 0422 
BMC DEBUG HEADER 
TP FAB1 CHANGE PN 1225 
TP FAB1 CHANGE PN 1225 
PLACE 0.1UF CAP 
74LVC2G07 
NEXT TO VCC PIN OF 
NEXT TO VCC PIN OF 
PLACE 0.1UF CAP 
74LVC2G07 
BMC MISC (1 OF 2) 
WIWYNN CORPORATION 



1Y 
VCC 
2Y 2A 
GND 
1A 
ROOM=SM_CONTROLLER 
G21497-005 
1
R8F23 
1/16W 
2
G21796-112 
2.21K 1% 0402 CHIP 
2
R2T29 
1
2.21K 1% 0402 1/16W CHIP G21796-112 
1 2
0402 1.0% 
R2N25 
51.1 
G21796-208 
1/16W 
CHIP 
R8F24 
2
1/16W 
1
4.75K 
G21796-072 
1% 0402 
CHIP 
1
2
R2T5 
1.00K 
1% 
1/16W 
CHIP 
G21796-026 
0402 
1
2
R2T7 
1.00K 
1% 
1/16W 
CHIP 
G21796-026 
0402 
C52245-001 
SM 
IC 
3
2
1 Q2T1 
MMBT3904 
2
1
R8D25 
4.75K 
1% 
1/16W 
CHIP 
0402 
C79254-001 
Q2T2 
2N7002 
3
FET 1
2
1
R3N12 
1/16W 0402 
2
1% 4.75K 
G21796-072 CHIP 
1
R3N11 
2
1/16W 4.75K 
G21796-072 
1% 0402 
CHIP 
1 2
1/16W 4.75K 
G21796-072 
1% 0402 
CHIP 
1
G21796-072 
R2M5 
2
4.75K 1% 0402 
CHIP 
1/16W 
S8E1 
IC 
21
D90553-001 
G21796-004 
1 2
1% 200.0 
CHIP 1/16W 
0402 
R2R9 
2
1 C2R12 
1.0UF 
6.3V 
10% 
X6S 
D97712-004 
0402V 
4.75K 
1
G21796-072 
1% 
2
0402 
EMPTY 
1/16W 
R8E19 
1 2
1/16W 1% 0402 
CHIP G21796-072 
4.75K 
R2U4 
0402 
1
R4R1 
1.00K 
1/16W 
G21796-026 
CHIP 
1% 
2
2
1 C2T3 
0.1UF 
10% 
0402V 
2
74LVC1G07 
IC 
U8D2 
4
C88419-001 
VCC=P3V3_STBY;GND=GND 
RST_BMC_SRST_R2_N 
1
R1L7 
2
1/16W 
CHIP 
0402 4.75K 
G21796-072 
1% 
2
1
R8E32 
4.75K 
1% 
1/16W 
CHIP 
G21796-072 
0402 
21
1/16W 
33.2 1% 
CHIP 0402 
R8D22 
1 2
1% 33.2 
1/16W CHIP 
U2R1 
TC7PZ14FU-GP 
2
R2R10 
G21796-074 
1
33.2 1% 
CHIP 1/16W 
0402 
21
0.0 
1/16W 0402 EMPTY 
5% 
2 4
C88419-001 
VCC=P3V3_STBY;GND=GND 
IC 
74LVC1G07 
U25W9 
2
1
R25W153 
4.75K 
1% 
CHIP 
G21796-072 
0402 
1/16W 
2
1
R2N27 
1% 
4.75K 
1/16W 
CHIP 
G21796-072 
0402 
FM_ADR_SMI_GPIO_N 
FM_BMC_CPLD_GPO 
FM_BMC_CPLD_MP_RST_N 
IRQ_MEZZ_LAN_ALERT_N 
FP_NMI_BTN_N 
FM_MP_PS_FAIL_N 
FM_MP_PS_REDUNDANT_LOST_N 
H_CPU0_FAST_WAKE_B_N 
H_CPU0_FAST_WAKE 
H_CPU0_FAST_WAKE_LVT3_N 
PWRGD_DSW_PWROK 
FP_NMI_BTN 
FP_NMI_BTN_OUT_R_N 
FP_NMI_BTN_R_N 
FM_CPLD_BMC_PWRDN_N 
FM_BMC_NMI_N 
FP_NMI_BTN_N 
FM_BMC_ENABLE_N 
FP_NMI_BTN_OUT_N 
H_CPU0_FAST_WAKE_N 
FM_NMI_EVENT_N 
FM_BIOS_TOP_SWAP 
IRQ_OOB_MGMT_RISER_ALERT_N 
R2M2 
16V 
X7R 
A36096-030 
G21796-072 
R9E14 
G21796-074 
R8D36 
G21796-074 
0402 
RST_BMC_DDR3_BUF_IN_N 
0402V 
A36096-030 
X7R 
10% 
16V 
0.1UF 
C8D1 1
2
TP FAB4 NOPOP R8D36 20170206 
89 156 191 120 
119 146 190 
118 147 190 
185 186 119 145 
157 119 145 
181 120 144 190 
146 181 120 
119 
144 
196 200 118 191 247 
118 135 
145 
119 145 190 
120 146 
157 
119 
145 
119 
21 97 
120 
120 136 145 
108 119 145 
119 184 249 
151 
RST_BMC_SRST_N 
NOPOP 
FM_TPM_PRES_RST_N 
S
D
G
SWITCH_D90553001 
CAD NOTE: 
CAD NOTE: 
3
2
4
5
61
DO NOT SCALE DRAWING SHEET 
B
AA
B
B
SIZE 
SCALE: 
234
1234
DEPARTMENT CODE 
1
DOCUMENT NUMBER REV 
OUT 
P3V3_STBY 
OUT 
P3V3_STBY 
OUT 
OUT 
P3V3_STBY 
OUT IN 
P3V3_STBY 
OUT 
P3V3_STBY 
OUT 
OUT 
OUT 
OUT 
OUT 
OUT 
P3V3_STBY 
P3V3_STBY 
P3V3_STBY 
OUT 
IN 
OUT 
P3V3 
IN OUT 
OUT 
P3V3_STBY 
OUT 
TTL1G07_A 
TTL1G07_A 
157 OF 270 
Wed Feb 08 16:35:13 2017 
TP FAB1 NOPOP R9E14 0121 
NMI BUTTON 
TP FAB1 CHANGE U2R1 PN 1222 
TP FAB1 ADD CIRCUIT 0228 
TP FAB1 FOR BMC TPM 1120 
PLACE 0.1UF CAP NEXT TO VCC PIN ON 74LVC2G14 
TTL1G07_A 
PLACE 0.1UF CAP 
NEXT TO VCC PIN OF 
BMC MISC (2 OF 2) 
BMC DISABLE JUMPER (ON PAGE 134 PINS 3 AND 5) 
WIWYNN CORPORATION 



1/16W 
G21796-072 
SP2_BMC_CM_UART_RX_R 
0402 
G21796-072 
CHIP 
1/16W 
4.75K 
R9W35 
0402 
G21796-072 
1/16W 
1% 
4.75K 
R9W33 
0402 
G21497-005 
1
1% 
1/16W 
CHIP 
3
0402 
SP1_BMC_HOST_UART_RX 
1% 
EMPTY 5% 
SP2_BMC_CM_UART_RX 
UART_BMC_RXD5 7UART_MUX_IN_R 
G21796-017 0402 
5
R9F69 
0.0 
1/16W EMPTY 
1
R9W34 
4.75K 
1/16W 
G21497-005 
1
5% 
2
R9F24 
D14725-022 
GREEN 
2
IC 
DS9A4 
1
0402 CHIP 
1
330 
1/16W 
5% 
2
R1L43 
G21497-028 
GREEN 
2
IC 
DS9A7 
D14725-022 
1
5% 
0402 
2
R1L44 
1
CHIP 
330 
1/16W 
G21497-028 1/16W 
R9F65 
CHIP 5% 
G21497-005 
0.0 0402 
0.0 
R9F66 
EMPTY 0402 
C1T10 
0.1UF 
10% 
16V 
X7R 2
1
4
8
72
5
6
IC 
1
3
1
C63273-001 
U9F1 
6
4
2
8
IC 
100.0 
1
R9F25 
2
1% CHIP 1/16W 
5% 
0402V 
2 X7R 
10% 
1
0.1UF 
C1T11 
A36096-030 
16V 
21
5% 0.0 
1/16W 
R9F26 
0402 
FM_UARTSW_LSB_R_N 
UART_BMC_TXD5 
SP1_BMC_HOST_UART_TX 
FM_UARTSW_LSB_N 
FM_UARTSW_MSB_N FM_UARTSW_MSB_R_N 
FM_UARTSW_MSB_N 
SP2_BMC_CM_UART_TX_R1 
FM_UARTSW_LSB_N 
R9F27 
1
G21497-005 
G21497-005 
1/16W 
5% 
FM_UARTSW_MSB_N 
FM_UARTSW_LSB_N 
SP2_BMC_CM_UART_TX 1/16W 
UART_MUX_OUT_R 
0402V 
A36096-030 
2
CHIP 
SPA_MID_DBG_TX 
0402 
C63273-001 
SP2_BMC_CM_UART_TX_R 0.0 
U9F2 
G21497-005 
EMPTY 
1 2
5% CHIP 0.0 
G21497-005 
0.0 0402 
R9F68 
2 CHIP 
1
2
0402 
2
SP2_BMC_CM_UART_RX_R1 
TP FAB3 ADD RES 1021 
176 181 
145 
150 
190 145 
190 
190 120 144 158 
190 120 144 158 
190 120 144 158 
181 
190 120 144 158 
190 120 144 158 
190 120 144 158 
145 
176 181 
181 
NOPOP NOPOP NOPOP 
SPA_MID_DBG_RX 
CAD NOTE: 
CAD NOTE: 
DESIGN NOTE: 
CAD NOTE: 
FM_UARTSW_MSB_N FM_UARTSW_MSB_N FM_UARTSW_LSB_N FM_UARTSW_LSB_N 
LED VALUES THE OPPOSITE OF MUX SELECT BITS 
1
21
USE SHARED PADS FOR RESISTORS 
FSA3357, WHILE PAST MUXES DID THIS WHEN S1 AND S2 
TO MEET LEGACY REQUIREMENTS. THIS IS BECAUSE 
WERE 11 
00 DISCONNECTS THE OUTPUT FROM THE INPUTS ON THE 
ON NET SP2_BMC_CM_UART_TX_R 
ON NET SP2_BMC_CM_UART_RX_R 
USE SHARED PADS FOR RESISTORS 
2
DO NOT SCALE DRAWING SHEET 
B
AA
B
B
SIZE 
SCALE: 
234
1234
DEPARTMENT CODE 
1
DOCUMENT NUMBER REV 
IN 
IN 
IN 
IN 
IN 
OUT 
P3V3_STBY 
P3V3_STBY 
P3V3_STBY 
OUT 
IN 
IN 
P3V3_STBY 
IN 
OUT 
OUT 
OUT 
IN 
IN 
IN 
158 OF 270 
Wed Feb 08 16:35:13 2017 
S1 
B2 B1 B0 
GND 
S2 
A
FSA3357 
VCC 
S1 
B2 
B1 
B0 
GND 
S2 
A
FSA3357 
VCC 
NOPOP R9F66 1123 
FROM MIDPLANE CONN A 
TO MIDPLANE CONN A 
NOPOP R9F68 1123 TP FAB1 POP R9F69 
UART5: DEBUG UART (IE/BMC) 
UART2: IPMI OVER SERIAL (IE/BMC) 
NO CONNECTION 
MSB GREEN 
TP FAB1 POP R9F65 
1
0 ON 
CPLD MAPPING 
1
ON 
LSB GREEN 
OFF 
ON 
OFF 
OFF 
OFF 
0
1
0
1
0 ON 
UART1: HOST UART/EMS (IE/BMC) 
MIDPLANE/DEBUG CONNECTOR CONNECTED TO 
HEADER. WHEN LOOKING FROM BOARD EDGE, PLACE BOTH LEDS TO THE 
LEFT OF THE BMC DEBUG CONNECTOR. PLACE MSB LED ON 
PLACE LEDS NEAR BOARD EDGE NEXT TO BMC DEBUG 
THE LEFT OF THE LSB LED 
UART MUX 
ROOM=UART_MUX 
BOM_COST=DEBUG 
WIWYNN CORPORATION 



ROOM=SMBUS 
R9G12 
SMB_SMLINK0_STBY_LVC3_SDA_R 
SMB_SMLINK0_STBY_LVC3_SCL_R 
20.0 
SMB_SMLINK0_STBY_LVC3_SCL 
SMB_SMLINK0_STBY_LVC3_SDA 
SMB_VR_STBY_LVC3_SDA_R 
SMB_OCP_LAN_STBY_LVC3_SDA 
SMB_OCP_LAN_STBY_LVC3_SDA_R 
SMB_OCP_LAN_STBY_LVC3_SCL_R 
SMB_BMC_PMBUS_STBY_LVC3_SDA_R 
SMB_OCP_FRU_STBY_LVC3_SDA_R 
SMB_BMC_PMBUS_STBY_LVC3_SCL 
SMB_BMC_PMBUS_STBY_LVC3_SDA 
SMB_OCP_FRU_STBY_LVC3_SCL_R 
SMB_BMC_PMBUS_STBY_LVC3_SCL_R 
SMB_HOST_STBY_LVC3_SDA 
SMB_HOST_STBY_LVC3_SCL 
SMB_OCP_FRU_STBY_LVC3_SDA 
SMB_OCP_FRU_STBY_LVC3_SCL 
SMB_VR_STBY_LVC3_SDA 
SMB_OCP_LAN_STBY_LVC3_SCL 
SMB_OCP_LAN_STBY_LVC3_SCL 
SMB_SPRINGVILLE_STBY_LVC3_SDA 
SMB_SPRINGVILLE_STBY_LVC3_SCL 
SMB_VR_STBY_LVC3_SCL SMB_VR_STBY_LVC3_SCL_R 
SMB_OCP_LAN_STBY_LVC3_SDA 
SMB_SMLINK0_STBY_LVC3_SCL 
SMB_SMLINK0_STBY_LVC3_SDA 
SMB_HOST_STBY_LVC3_SDA_R 
SMB_HOST_STBY_LVC3_SCL_R 
1/16W 
G21796-001 
0402 
R8C16 
2.0K 
1% 
CHIP 
2.0K 
R8C15 
1/16W 
G21796-001 
CHIP 
1% 
0402 
20.0 1% 21CHIP 
R1U10 
R1U9 
CHIP 1 2 1% 20.0 
R2U33 
1CHIP 2 1% 
1
R2U34 
20.0 CHIP 2 1% 
20.0 2
R8G4 
1% CHIP 1
1% 20.0 
R8G5 
1 2CHIP 
20.0 1CHIP 2
R9G13 
1% 
20.0 CHIP 1
R1U19 
1% 2
20.0 CHIP 1 1% 2
R1U20 
20.0 21 1% CHIP 
0.0 1 5% 
R1U8 
2CHIP 
5% 0.0 2
R1U11 
CHIP 1
20.0 CHIP 1 2
R2U10 
1% 
1 2
R2U7 
CHIP 1% 20.0 
1% 2 20.0 1
R2T49 
CHIP 
1% 
R2U1 
1CHIP 2 20.0 
R2U13 
2.26K 
1.0% 
1/16W 
CHIP 
0402 
G21796-311 
0402 
R2U5 
2.26K 
1.0% 
1/16W 
CHIP 
G21796-311 
R8G6 
2.26K 
1.0% 
G21796-311 
EMPTY 
1/16W 
0402 
R8G3 
2.26K 
1/16W 
1.0% 
0402 
G21796-311 
EMPTY 
144 
144 
138 159 156 
138 156 159 
144 
159 185 186 
144 
144 
144 
144 
138 181 247 
199 
138 181 199 
247 
144 
144 
101 102 111 138 156 247 
138 101 102 111 156 247 
91 138 186 
188 
138 91 186 188
138 193 194 201 
206 211 213 215 
218 223 226 235 
159 185 186 
159 185 186 
139 
139 
138 211 213 235 193 194
201 206 215 218 223 226
144 
159 185 186 
138 156 159 
138 156 159 
144 
144 
G21796-173 0402 1/16W 
G21796-173 1/16W 0402 
G21796-173 1/16W 0402 
1/16W 0402 G21796-173 
0402 1/16W G21796-173 
0402 1/16W G21796-173 
1/16W 0402 G21796-173 
1/16W 0402 G21796-173 
0402 1/16W G21796-173 
0402 1/16W G21796-173 
0402 1/16W G21497-005 
0402 1/16W G21497-005 
1/16W 0402 G21796-173 
1/16W G21796-173 0402 
G21796-173 0402 1/16W 
G21796-173 1/16W 0402 
CAD NOTE: 
CAD NOTE: 
CAD NOTE: 
RUN TRACES THROUGH RESISTOR PADS ON OCP AND SMLINK0 CONNECTIONS 
FOR QUESTIONS, ASK MAX 
1
2
2
1
1
2
1
2
1
2
1
2
DO NOT SCALE DRAWING SHEET 
B
AA
B
B
SIZE 
SCALE: 
234
1234
DEPARTMENT CODE 
1
DOCUMENT NUMBER REV 
OUT 
BI 
BI 
BI 
OUT 
OUT 
P3V3_STBY 
P3V3_STBY 
P3V3_STBY P3V3_STBY 
P3V3_STBY P3V3_STBY 
OUT 
BI 
IN 
BI 
IN 
BI 
IN 
BI 
IN 
BI 
IN 
BI 
OUT 
BI 
OUT 
BI 
OUT 
BI 
IN 
BI 
BI 
IN 
IN 
BI 
159 OF 270 
Wed Feb 08 16:35:14 2017 
TP FAB1 CHANGE CONNCETION 0314 
PLACE RESISTORS CLOSE TO BMC 
PLACE RESISTORS CLOSE TO BMC 
SMBUS PULLUPS (1 OF 2) 
WIWYNN CORPORATION 



1.0% 
G21796-235 
SMB_LAN_STBY_LVC3_SCL 
SMB_SLOTX24_BMC_STBY_LVC3_SCL 
SMB_LAN_STBY_LVC3_SDA_R 
SMB_SLOTX24_STBY_LVC3_SDA_R 
SMB_SLOTX24_STBY_LVC3_SCL_R 
SMB_SLOTX24_BMC_STBY_LVC3_SDA 
SMB_LAN_STBY_LVC3_SCL_R 
SMB_LAN_STBY_LVC3_SDA 
REMOVE 0 OHM RESISTOR  AND STUFF PULL-UP RES ON VR SMBUS IN MASS PRODUCTION 
20.0 1% 2
R9F22 
1CHIP 
R9F23 
CHIP 20.0 1 2 1% 
2 20.0 1
R1T7 
CHIP 1% 
G21796-235 
1.0% 
0402 
1/16W 
CHIP 
665 
R1T2 
0402 
CHIP 
665 
R1T3 
1/16W 
1 2 20.0 
R1T8 
CHIP 1% 
138 156 182 
108 
144 
144 
144 
108 
144 
138 156 182 
0402 
0402 1/16W 
G21796-173 
G21796-173 1/16W 
G21796-173 0402 1/16W 
G21796-173 0402 1/16W 
DESIGN NOTE: 
CAD NOTE: 
2
1
2
1
DO NOT SCALE DRAWING SHEET 
B
AA
B
B
SIZE 
SCALE: 
234
1234
DEPARTMENT CODE 
1
DOCUMENT NUMBER REV 
OUT 
P3V3_STBY P3V3_STBY 
IN 
BI 
BI 
BI 
IN 
BI 
OUT 
160 OF 270 
Wed Feb 08 16:35:14 2017 
PLACE RESISTORS CLOSE TO BMC 
SMBUS PULLUPS (2 OF 2) 
WIWYNN CORPORATION 



TP FAB3 DELETE CIRCUIT 0901 
TP FAB3 CHANGE TO TP 0823 
TP FAB3 CHANGE TO TP 0823 
TP FAB3 CHANGE FROM 6 PIN TO 4 PIN 0823 
TP FAB3 EXCHANGE LOCATION TO J10W1 0824 
TP FAB3 CHANGE FROM 6 PIN TO 4 PIN 0823 
TP FAB3 EXCHANGE LOCATION TO J1F2 0824 
TP FAB3 DELETE CIRCUIT 0902 
TP FAB3 EXCHANGE LOCATION TO J10W1 0824 
181 198 
181 147 
147 
200 
181 191 198 
147 161 
181 147 161 181 
161 181 
161 
C95333-007 
25V 
G21796-072 
0402 
G21796-072 
G21796-017 
R1B22 
1% 
CHIP 
TO IC 
1/16W 
2
PLACE CAP CLOSE 
FM_ENABLE_FAN_POWER 
FAN_TACH2 
10% 
1% 
10% 
X7R 
A36096-030 
J10W1 
IC 
H71799-001 
G21796-017 
16V 
0.1UF 
C9M5 
2
R1B21 
H71799-001 
SM 
1% 
0402 
FAN_PWM_OUT_SYS0 
FM_DISABLE_FAN_N 
FM_CTNR_PS_ON 
FAN_PWM_OUT_SYS0_BUF 
FAN_PWM_OUT_SYS1 FAN_PWM_OUT_SYS1_BUF FAN_PWM_OUT_SYS1_R 
FAN_TACH0 FAN_PWM_OUT_SYS0_R 
PLACE CAP CLOSE 
TO IC 
TO IC 
PLACE CAP CLOSE 
CHIP 
1.0% 
2
R2U42 
G21796-271 
1
1/16W 
221 
2
1
X7R 
16V 
0402V 
10% 
A36096-030 
C2U28 
0.1UF 
2 4
VCC=P3V3_STBY;GND=GND 
U8G3 
74LVC1G07 
IC 
C88419-001 
A36096-030 
X7R 
10% 
0.1UF 
C2U27 
0402V 
16V 
1
2
VCC=P3V3_STBY;GND=GND 
C88419-001 
4
IC U8G2 
74LVC1G07 
2
0402 
CHIP 
1% 
2
1 4.75K 
0402V 
X7R 
1
1 2
2
1
1
2
CR1B2 
1
1
2
1
2
0.01UF 
25V 
1C1F9 
10% 
2
0402V 
X7R 
A36096-045 
G21796-072 
CHIP 
0402 
1/16W 
R1F1 
4.75K 1
2
1% 
CHIP 
100.0 
1/16W 
R1F2 
0402 
21 12
SM 
IC 
1
2
X6S 
0805 
2
16V 
C1E21 
10UF 
10% 
1
1 1
2
4
VCC=P3V3_STBY;GND=GND; 
D10321-001 
U1E2 
SOTLF 
IC 
1
2
NC7SZ08 
G21796-016 
EMPTY 
1/16W 
R1E11 
10.0K 
1% 
0402 
1
2
10% 
X7R 
A36096-030 
0402V 
16V 
0.1UF 
C1E22 1
2
1 2
1/16W CHIP 0402 
1.0% 221 
G21796-271 
R2U44 
0805 
X6S 
10% 
16V 
0402V 
4.75K 
FAN_TACH2_CPU1_D2 
0402 100.0 
FAN_PWM_OUT_SYS0_R 
0402V 
X7R 
10% 
16V 
0.1UF 
C1E20 
A36096-030 
FAN_TACH0_CPU0_D1 
J1F2 
LOTES-CON4-S1-GP 
G21796-072 
1% 
1/16W 
CHIP 
1/16W 
H71799-001 
CR1F1 
FAN_TACH0_CPU0_D2 
CR1E1 
4.75K 
R1E12 
SDMK0340L 
EMPTY 
SDMK0340L 
CHIP 
1/16W 
C9M4 
10UF 
C95333-007 
LOTES-CON4-S1-GP 
SM 
R7F33 
SM 2
CR1B1 
SDMK0340L 
H71799-001 
EMPTY 
SDMK0340L 
FAN_TACH2_CPU1_D1 
C1B15 
0.01UF 
A36096-045 
FAN_PWM_OUT_SYS1_R 
0402 
CAD NOTE: 
CAD NOTE: 
CAD NOTE: 
3 NP1 
2
1
4
NP1 
1
2
3
4
DO NOT SCALE DRAWING SHEET 
B
AA
B
B
SIZE 
SCALE: 
234
1234
DEPARTMENT CODE 
1
DOCUMENT NUMBER REV 
OUT 
P3V3_STBY 
IN 
IN 
OUT 
P5V_STBY 
P3V3_STBY 
IN 
P5V_STBY 
OUT 
P3V3_STBY 
P3V3_STBY 
P3V3_STBY 
IN 
IN 
OUT 
P12V_FAN 
P12V_FAN 
P3V3_STBY 
OUT IN 
161 OF 270 
Wed Feb 08 16:35:14 2017 
TTL1G07_A 
TTL1G07_A 
ROOM=CPU_FANS 
BOM_COST=SM_THERM 
FAN HEADERS 
WIWYNN CORPORATION 



THIS PART WILL BE IN SOCKET, PLEASE 
TP_SPI_2_0 
4.75K 
R8F16 
EMPTY 
1/16W 
G21796-072 
0.01UF 
25V D97712-004 
TP_SPI_2_6 
TP_SPI_2_4 
6
5
TP_SPI_2_2 
TP_SPI_2_3 
TP_SPI_2_5 
0402V 
H12709-001 
PU_SPI_FLASH_RESET_2_N 
TP_SPI_2_1 
SPI_BMC_BT_DI 
PU_SPI_BMC_BT_HOLD_N 
SPI_BMC_BT_CS_N 
SPI_BMC_BT_CLK 
SPI_BMC_BT_DI_R 
PU_SPI_BMC_BT_WP_N 
SPI_BMC_BT_DO 
SOCKET IS D91187-001 
USE ALT SYMBOL ASSOCIATED WITH PART FOOTPRINT 
G21796-072 
0402 
1/16W 
1% 
CHIP 
4.75K 
R8F14 
2
1
0402 
2
1
1% 
0402 
G21796-072 
1/16W 
CHIP 
4.75K 
R8F13 
1% 
14 
13 
12 
11 
4
10 
U8F2 
IC 
16 
1
9
2
3
7
8
15 
10% 
X6S 
C8F4 
1.0UF 
6.3V 
0402V 
10% 
A36096-045 
C8F5 
X7R 
R8F35 
1.00K 
1/16W 
EMPTY 
G21796-026 
0402 
1% 
G21796-072 
0402 
1/16W 
CHIP 
4.75K 
R8F34 
1% 
33.2 
1 2R8F12 246 146 150 
146 
146 150 246 
146 150 246 1/16W 0402 G21796-074 CHIP 1% 
CAD NOTE: 
CAD NOTE: 
BOM NOTE: 
2
1
1
2
1
2
1
2
1
2
DO NOT SCALE DRAWING SHEET 
B
AA
B
B
SIZE 
SCALE: 
234
1234
DEPARTMENT CODE 
1
DOCUMENT NUMBER REV 
IN 
OUT 
IN 
IN 
P3V3_STBY 
162 OF 270 
Wed Feb 08 16:35:14 2017 
DI_IO<0> 
WP_N_IO<2> 
VCC 
NC<6> 
NC<5> 
NC<4> 
NC<3> 
GND 
NC<2> 
NC<1> 
NC<0> 
DO_IO<1> 
HOLD_N_IO<3> 
CS_N CLK RESET_N 
U8F2 IS SOCKET. 
TP FAB1 NOPOP R8F13  1215 
TP FAB POP R8F13 0227 PLACE CAPS NEAR VCC PIN ON W25Q128 COMPONENT 
BMC DEDICATED SPI FLASH 
W25Q128 
WIWYNN CORPORATION 



EN 
SDAB 
SCLB 
VCCB 
GND 
SDAA 
SCLA 
VCCA 
G21796-001 
2.0K 
G21796-294 
SMB_PEHPCPU1_STBY_LVC3_R_SDA 
TP_SMB_PEHPCPU1_EN 
SMB_PEHPCPU1_STBY_LVC3_SDA 
SMB_PEHPCPU1_STBY_LVC3_SCL 
SMB_CPU1_PE_HP_GTL_SDA 
SMB_CPU1_PE_HP_GTL_SCL SMB_PEHPCPU1_STBY_LVC3_R_SCL 
SMB_CPU1_PE_HP_GTL_R_SDA 
SMB_CPU1_PE_HP_GTL_R_SCL 
R9M19 
240 
1.0% 
CHIP 
1/16W 
1
2
0402 
R9M18 
G21796-294 
240 
1.0% 
0402 
CHIP 
1/16W 
1
2
R6N9 
G21796-066 
10.0 1% 
0402 CHIP 1/16W 
1 2
TCA9517DGKR-GP 
U1B2 
0402 
1% 20.0 
CHIP 
G21796-173 
R9M13 
1/16W 
CHIP 1/16W 
20.0 
0402 
G21796-173 
R9M14 
1% 
R6N8 
G21796-066 
10.0 1% 
0402 CHIP 1/16W 
1 2
R9M16 
CHIP 
G21796-001 
1% 
0402 
1/16W 
1
2
R9M17 
2.0K 
1/16W 
1% 
CHIP 2
0402 
12
1
X7R 
16V 
10% 
0.1UF 
C9M7 
A36096-030 
0402V 
1
2 X7R 
16V 
0402V 
10% 
0.1UF 
A36096-030 
C9M8 
145 182 
145 182 
55 
55 
CAD NOTE: 
DESIGN NOTE: 
CAD NOTE: 
PLACE SEIRES RESISTORS NO MORE 
THAN 3"  FROM CPU1 
5
1
2
3
4
8
7
6 21
21
DO NOT SCALE DRAWING SHEET 
B
AA
B
B
SIZE 
SCALE: 
234
1234
DEPARTMENT CODE 
1
DOCUMENT NUMBER REV 
PVCCIO_CPU1 
PVCCIO_CPU1 
BI 
IN 
P3V3_STBY 
P3V3_STBY 
OUT 
BI 
163 OF 270 
Wed Feb 08 16:35:14 2017 
PLACE CAPS & PU RESISTORS NEAR TCA9517 
TP FAB1 CHANGE TO TCA9517 0106 
PE HP SMBUS ADDRESS 0X22 
ROOM=SMB_PE_HP_CPU1 
SMBUS: CPU PCIE HP 
WIWYNN CORPORATION 



VCC 
SDA 
SCL 
INT# 
P7 
P6 
P5 
P4 
GND 
P3 
P2 
P1 
P0 
A2 
A1 
A0 
GROUP=PU_SKU_ID0 
GROUP=PD_SKU_ID1 
GROUP=PD_SKU_ID0 GROUP=PD_SKU_ID4 
GROUP=PU_SKU_ID1 
GROUP=PD_SKU_ID3 
GROUP=PU_SKU_ID3 
GROUP=PU_SKU_ID4 
2.7K 
G21796-072 
4.75K 
0402 
1/16W 
0402 
FM_BOARD_SKU_ID2 
FM_BOARD_SKU_ID3 
CHIP 
G21796-026 
0402 
1/16W 
1% 
1.00K 
R1U18 
FM_BOARD_SKU_ID0 
1% 
1.00K 
R1U16 
CHIP 
1/16W 1/16W 
1.00K 
R1U17 
1% 
CHIP 
G21796-026 
2
CHIP 
0402 
16V 
0.1UF 
G21796-026 
FM_BOARD_REV_ID1 
0402 CHIP 
0402 
G21796-026 
0402 
CHIP 
1/16W 
R1T10 
2
1% 
1 1.00K 
R1T12 
2 CHIP 
1/16W 
1% 
1 1.00K 
G21796-026 G21796-026 
1/16W 
1% 
G21796-344 
C6W14 
0402V 
X7R 
10% 
1
2
22
R2N17 1
CHIP 
1R1U21 2
0402 
2.7K 
1
1
2.7K 1% 
2
1% 
21
R1U22 
1/16W 
1/16W 1% 
21
EMPTY 
CHIP 
1.00K 1
0402 
2
R1T11 
G21796-344 
0402 
FM_BOARD_SKU_ID4 
FM_BOARD_REV_ID2 
0402 
1% 
0402 
G21796-072 
EMPTY 
1/16W 
R6W43 
1% 
EMPTY 
1/16W 
4.75K 
1/16W 
4.75K 
1/16W 
1% 
R6W46 
CHIP 
G21796-072 
1% 
4.75K 
R6W47 
0402 
4.75K 
R6W41 
U6W11 
CHIP 
1/16W 
CHIP 
1% 
1/16W 
1% 
0402 
A36096-030 
PCA9554PWR-GP 
G21796-072 
0402 
G21796-072 
R6W44 
0402 
R6W42 
4.75K 
1% 
EMPTY 
G21796-072 
0402 
R6W45 
4.75K 
1/16W 
CHIP 
G21796-072 
0402 R1T5 
2.7K 
1 2
2.7K 1% 0402 
R1T6 
G21796-344 
1/16W CHIP 
1 2
2.7K 1% 1/16W 
R1T4 FM_BOARD_REV_ID0 
R2N18 
R1U24 
G21796-344 
R1U23 
2.7K 
1
G21796-344 
1% 
1/16W 
0402 
1/16W CHIP 
1
CHIP 
G21796-026 
CHIP 
1% 
1.00K 1
G21796-344 
1% 
1% 
G21796-344 
2
1/16W 
1/16W 
2
1/16W 
G21796-026 
1.00K 
R1U15 
FM_BOARD_SKU_ID1 
0402 CHIP 
CHIP 0402 
0402 2.7K 
G21796-344 
1% 
TP FAB3 POP R1T6 AND NOPOP R1T12 0803 
TP FAB3 RECONNECT 0922 
TP FAB3 RECONNECT 0922 
TP FAB4 POP R1T4 AND NOPOP R1T10 20170116 
TP FAB3 NOPOP R6W42, R6W43; POP R6W45, R6W46 0922 
TP FAB1 CHANGE CONFIGURATION 0310 
TP FAB1 CONFIG FM_BOARD_SKU_ID<4:0> TO 00001. 
TP FAB4 NOPOP R1U24, AND POP R1U17 20170206 
120 147 
120 147 
120 147 
119 145 
120 147 
119 145 
181 119 
181 119 
181 119 
119 156 167 184 191 
167 184 191 
119 145 
120 147 
FM_MB_SLOT_ID0 
FM_MB_SLOT_ID1 
FM_MB_SLOT_ID2 
FM_CPU_BMC_INIT 
NOPOP 
164 
164 
164 
164 
164 
164 
PCA9554_A1 
PCA9554_A0 
PCA9554_A2 
PCA9554_A2 
PCA9554_A1 
PCA9554_A0 
PCA9554_INT_N 
SMB_SENSOR_STBY_LVC3_SDA 
SMB_SENSOR_STBY_LVC3_SCL 
1
NOPOP NOPOP 
2
1
22
1
1
2
1
1
2
13 
8
3
2
1
2
1
12 
16 
4
5
6
7
2
15 
14 
2
1
2
9
10 
11 
1
DO NOT SCALE DRAWING SHEET 
B
AA
B
B
SIZE 
SCALE: 
234
1234
DEPARTMENT CODE 
1
DOCUMENT NUMBER REV 
BI OUT 
IN 
IN 
IN 
P3V3_STBY 
P3V3_STBY 
P3V3_STBY 
IN 
OUT 
OUT 
OUT 
P3V3_STBY 
OUT 
OUT 
OUT 
OUT 
OUT 
P3V3_STBY 
164 OF 270 
Wed Feb 08 16:35:15 2017 
FAB4 (DVT) 
FAB3 (EVT3, PRE-DVT) 
REV 
FAB1 (POWER ON/EVT) 
FAB2 (EVT2) 
0 0 0
0 0 1
TP FAB3 CHANGE TCA9555 TO PCA9554 0920 
ADDRESS 0X42 
0 0
10
1
1
TP FAB3 ADD TCA9555 0920 
FM_BOARD_REV_ID[2:0] 
BOARD AND SKU ID STRAPS 
WIWYNN CORPORATION 



DO NOT SCALE DRAWING SHEET 
B
AA
B
B
SIZE 
SCALE: 
234
1234
DEPARTMENT CODE 
1
DOCUMENT NUMBER REV 
165 OF 270 
Wed Feb 08 16:35:15 2017 
TP FAB1 DELETE ADC128D818 AND RELATED COMPONENT (NO USE IE) 0118 
VOLTAGE MONITORING IC 
ROOM=HEC_VOLT_MONITOR 
BOM_COST=SM_HM 
WIWYNN CORPORATION 



ROOM=SM_CONTROLLER 
PULL-UP FOR BMC IF 
PLACE ALL 3 STUFFING OPTION RESISTORS 
PECI_CPU_G 
PECI_BMC 
PECI_PCH 
AS CLOSE AS POSSIBLE TO THE COMMON NODE 
POSSIBLE WHEN ANY OF THEM IS UNSTUFFED 
SO THAT THE PECI BUS STUB IS AS SHORT AS 
EMPTY FOR BMC SKU OR NM DEBUG 
PD STUFFED IN PECI_PCH 
BMC PECI IS NOT USED 
0402 
G21796-016 
1% 
1
2 EMPTY 
1/16W 
10.0K 
R7W3 
10.0K 
1% 
1/16W 
EMPTY 
G21796-016 
0402 
2
1
R7W2 
0402V 
A36096-030 
0.1UF 
C7W1 
2
1
X7R 
10% 
16V 
PI5A3157BC6E-GP 
U7W1 
0402 
G21796-340 
CHIP 
1/16W 
1% 
1
2
348 
R7D15 
R7C17 
1/16W 
2
14.75K 
G21796-072 
0402 
CHIP 
1% 
146 
21 55 
145 
118 
PECI_SEL 
CAD NOTE: 
DESIGN NOTE: 
DESIGN NOTE: 
2
43
1
5
6
DO NOT SCALE DRAWING SHEET 
B
AA
B
B
SIZE 
SCALE: 
234
1234
DEPARTMENT CODE 
1
DOCUMENT NUMBER REV 
P3V3_STBY 
P3V3_STBY 
BI 
IN 
PVCCIO_CPU0 
BI 
BI 
166 OF 270 
Wed Feb 08 16:35:15 2017 
TP FAB1 ADD SW 0311 
PUT C7W1 NEAR IC TP FAB1 DEL SERIAL RES 0311 
PECI SEL = 1: S1, PIN1, BMC PECI SEL = 0: S0, PIN3, PCH (DEFAULT) 
TP FAB1 DEL PU AND SERIAL RES 0311 
PECI 
WIWYNN CORPORATION 



ROOM=SM_THERM 
SMB_SENSOR_STBY_LVC3_SDA 
1R9B6 
1/16W1.00K 
CHIP 
0402 
2
G21796-026 G21796-235 
R2U38 
Q9B1 
G21796-047 
CHIP 
CHIP 
2SB2907A-B0-00001-GP 
G21796-026 
EMPTY 
ISENSE_TMP421_1_BC 
G21796-047 
2
49.9 CHIP 
R9B4 
G21796-047 
1/16W 
1/16W 
0402 
ISENSE_TMP421_2_DXP 
R9R6 
1.00K 
SMB_SENSOR_STBY_LVC3_SCL 
SMB_SENSOR_STBY_LVC3_SDA SMB_SENSOR_BMC_STBY_LVC3_SDA 
SMB_SENSOR_BMC_STBY_LVC3_SCL 
SMB_SENSOR_STBY_LVC3_SCL 
SMB_SENSOR_STBY_LVC3_SCL SMB_SENSOR_STBY_LVC3_SDA 
SMB_SENSOR_TMP421_1_SDA 
SMB_SENSOR_TMP421_1_SCL 
PU_AT24C64_A2 
SMB_SENSOR_STBY_LVC3_SCL_R2 
ISENSE_TMP421_2_DXN 
PD_TMP421_2_A1 
SMB_SENSOR_STBY_LVC3_SDA_R2 
SMB_SENSOR_TMP421_2_SCL 
SMB_SENSOR_TMP421_2_SDA 
PU_TMP421_2_A0 
PD_FRU_WP 
G21796-173 
R8D23 
1/16W 
20.0 1% 
CHIP 0402 
R8D24 
20.0 
1/16W CHIP 
1% 
0402 
1 2
G21796-173 
R2U39 
665 
0402 
1.0% 
1
2 CHIP 
1/16W 
G21796-235 
665 
1.0% 
1
2
0402 
1/16W 
CHIP 
G21796-173 
2
R1M9 
1% 
1
CHIP 
20.0 
1/16W 
0402 
21
20.0 CHIP R9G14 G21796-173 1% 1/16W 0402 
0402 
21
1/16W 
20.0 
G21796-173 
R9R7 
1% 
2
20.0 
1
1/16W 
0402 
21
1% 
1/16W 
20.0 
R1M8 
G21796-173 
CHIP 
0402 
CHIP 
1/16W 
1.00K 
1% 
0402 
1
R8D28 
0402LF 
EMPTY 2
5% 
47.0PF 1 C1M4 
50V 
21
CHIP 
1
R9G15 20.0 1% CHIP 
2
0402 1/16W G21796-173 
G21796-026 
CHIP 
1/16W 
0402 
2
R8D27 
1 1.00K 
1% 
1% 
1 2
R9B5 
CHIP 49.9 
7
VCC=P3V3_STBY;GND=GND; 
1
56
2
U8D4 
3
C47049-001 
IC 0402V 
10% 
16V 
0.1UF 
C9R13 
X7R 
A36096-030 
1
2
16V 
10% 
0.1UF 
X7R 
A36096-030 
0402V 
1
2
C9R14 
0.1UF 1
2
0402V 
A36096-030 
X7R 
10% 
16V 
C9B7 
2
1.00K 
1
CHIP 
1% R1E10 
1/16W 
G21796-026 
0402 
2
1% 
G21796-026 
1 2
G21796-026 
1/16W 
1.00K 1% 
CHIP 
0402 
R1E9 
IC 
8
5
6
72
3
4
1
G62962-001 
U1E1 
1
1%1/16W 
G21796-047 
2
0402 
1
R9R5 
1/16W 
49.9 1% 0402 
2
1 C1E19 
47.0PF 
5% 
50V 
0402LF 
A36095-025 
1/16W 
R9B8 
1
0402 
1% 
2 CHIP 
3
G62962-001 
1
4
7
5
6
U9B4 
IC 
8
2
Q1E1 
ISENSE_TMP421_2_BC 
ISENSE_TMP421_2_E 
1% 
R9R8 
G21796-173 
CHIP 
ISENSE_TMP421_1_DXN 
PU_TMP421_1_A1 
PD_TMP421_1_A0 
49.9 1% 0402 
ISENSE_TMP421_1_DXP 
2SB2907A-B0-00001-GP 
ISENSE_TMP421_1_E 
TP FAB1 ADD BJT 0316 
TP FAB3-DVT DELETE BJT Q9W5 20161114 
TP FAB3 CHANGE SYMBOL 0902 TP FAB3 DEL RES 0902 TP FAB3 CHANGE SYMBOL 0902 TP FAB1 ADD RES 0316 
TP FAB3 CHANGE SYMBOL 0902 
TP FAB3 RECONNECTION 0902 
164 167 184 191 
167 164 184 191 
164 167 184 191 144 
144 
167 164 184 191 
167 164 184 191 164
167
184
191
A36095-025 
DESIGN NOTE: 
CAD NOTE: 
CAD NOTE: 
DESIGN NOTE: 
CAD NOTE: 
CAD NOTE: 
CAD NOTE: 
DESIGN NOTE: 
PLACE SERIES RESISTORS ON SMB_SENSOR_STBY_LVC3_SDA/SCL NETS CLOSE TO AT24C64 
PLEASE CONTACT DE WHEN CONNECTING THESE RESISTORS 
C
C
21
E
B
PLACE LOWER TMP421 ON EDGE OF BOARD NEAR AIRMAX CONNECTORS 
B
E
DO NOT SCALE DRAWING SHEET 
B
AA
B
B
SIZE 
SCALE: 
234
1234
DEPARTMENT CODE 
1
DOCUMENT NUMBER REV 
BI IN 
P3V3_STBY P3V3_STBY 
P3V3_STBY 
P3V3_STBY 
P3V3_STBY 
OUT IN 
BI BI 
P3V3_STBY 
P3V3_STBY 
P3V3_STBY 
P3V3_STBY 
BI 
IN 
P3V3_STBY 
A2 
A1 
A0 
SCL 
WP 
SDA 
AT24C64 
167 OF 270 
GND 
SCL DXN DXP 
A<0> 
SDA 
A<1> 
VP 
GND 
SCL DXN DXP 
A<0> 
SDA 
A<1> 
VP SMBUS ADDRESS 0X9E 
TP FAB1 DELETE RES (NO USE IE) 0118 
SMBUS ADDRESS 0XA8 
SMBUS ADDRESS 0X9C 
TP FAB1 CHANGE CONNECTION 0317 
PLACE CAP CLOSE 
TO AT24C64 
PLACE UPPER TMP421 ON EDGE OF BOARD NEAR RJ 45 
TEMPERATURE SENSORS AND FRU 
TMP421 
TMP421 
Wed Feb 08 16:35:15 2017 
WIWYNN CORPORATION 



FM_SOL_UART_CH_SEL 
G21796-026 
0402 
Q6W2 
3
IC 
SM 
2 C52245-001 
IC 
MMBT3904 
Q1L3 
SM 
2 C52245-001 
3
1FM_DB_UART_SEL4_N 
IC IC 
CR1L3 
D89194-001 
SM 
2N7002 
FM_POST_CARD_PRES_BMC_N 
2
Q6W4 
3
1
D24280-001 
1/16W CHIP 
FM_DB_UART_SEL1_N FM_DB_UART_SEL2_N 
TP_FET_Q56_3 
TP_FET_Q56_4 
FM_DB_PRESENT 
R1L6 
G21497-005 
0.0 5% 
21 2 1
SM 
1N4148W 1N4148W 
1
SM 
CR1L2 
IC 
D89194-001 
2
0402 
G21796-026 
CHIP 
1/16W 
1 1.00K 
R1L38 
1% 
2
CR1L1 
D89194-001 
SM 
IC 
12
Q1L4 
2N7002DW 
6
FET 2
1
3
5
4
FET 
2N7002DW 
D24280-001 
Q1L4 
FM_DB_UART_SEL0_N 
1N4148W 
FM_DB_UART_SEL3_N 
1N4148W 
CR1L4 
1
D89194-001 
2
C79254-001 
FET 
0402 
G21796-026 
1/16W 
CHIP 
1
2
1% 
1.00K 
R1L36 
R6W16 
1/16W 
1
2
1.00K 
1% 
CHIP 
0402 
1 MMBT3904 1
FM_UART_SWITCH_N 
1/16W 
CHIP 
0402 
40.2K 
1% 
G21796-133 
2
R6W49 
176 
120 145 190 
120 146 
155 247 
DEBUG_CARD2_PRSNT 
FM_UART_SEL_N 
S
D
G
S
D
G
S
D
G
DO NOT SCALE DRAWING SHEET 
B
AA
B
B
SIZE 
SCALE: 
234
1234
DEPARTMENT CODE 
1
DOCUMENT NUMBER REV 
IN 
P3V3_STBY 
OUT 
P3V3_STBY 
OUT 
P3V3_STBY 
IN 
168 OF 270 
Wed Feb 08 16:35:16 2017 
TP FAB3 CHANGE UART SELECT CIRCUIT 0926 
TP FAB3 CHANGE DIODE TO RES 0920 
TP FAB1 ADD FOR UART SELECT 1117 
TP FAB3 DELETE RES 0920 
UART MUX CONTROL 
WIWYNN CORPORATION 



ROOM=SM_HM 
R1U29 
A_P3V_BAT_R 
E40049-001 
A_PVNN_STBY_PCH_SENSOR 
G21796-140 
R1U44 
1K82R2F-1-GP 47.0PF 
G21796-140 
2
0402LF 
A36095-025 
A_P3V3_STBY_SCALED 
A_P1V05_STBY_PCH_SENSOR 
693286-021 
R1U28 
47.0PF 
A36095-025 
A_P5V_SCALED 
1K82R2F-1-GP 1 C9G15 
G21796-140 
R1U33 0402 
R1U47 
5% 
50V 
1 C9G17 
A_P12V_STBY_SCALED 
47.0PF 
R9G26 
G21796-010 
100.0K 
1% 
0402 
CHIP 
1/16W 
2
1 C9G22 
10.0PF 
50V 
COG 
2
1
5% 
0402LF 
A36094-025 
1% 
CHIP 
1 5.11K 
G21796-080 
R1U50 
1% 
0402 
CHIP 
1/16W 
2
1 200.0K 
5% 
COG 
2
0402LF 
50V 
CHIP 
1/16W 
2
1 5.11K 
1% 
2
1
50V 
5% 
COG 
47.0PF 
C9G14 
0402LF 
A36095-025 
1
1% 
5.11K 
R1U26 
0402 
CHIP 2
G21796-140 
1/16W 
C9G18 
5% 
0402LF 
50V 
2
1 47.0PF 
COG 
A36095-025 
30 
SMLF 
1
693286-021 
FB1U4 2
FB 
Q9G1 
FET 
4
5
NTJD4001N 
3
Q9G1 
1
2
6
E40049-001 
FET 
NTJD4001N 
G21796-344 
2.7K 
1% 
0402 
CHIP 
1/16W 
2
1
R1U49 
5% 
50V 
COG 
2
1 C1U21 
47.0PF 
A36095-025 
0402LF 
2
1 SMLF 
30 
FB1U3 
FB 
5% 
1
2
50V 
C9G21 
0402LF 
A36095-025 
COG 
2 A36095-025 
COG 
0402LF 
CHIP 
5.11K 
R1U32 
2
0402 
1
1% 
1/16W 
1
2
C9G20 
COG 
5% 
50V 
47.0PF 
1/16W 
1% 
5.11K 
2
G21796-140 
R1U39 
1
CHIP 
0402 
47PF BYPASS CAP SHOULD BE LOCATED NEAR THE BMC 
AVIN SCALING RESISTORS SHOULD BE PLACED AT THE VOLTAGE RAIL SOURCE 
A_P3V3_SCALED 
A_P5V_STBY_SCALED 
A_P3V_BAT_SCALED 
FM_BATTERY_SENSE_EN 
FM_BATTERY_SENSE_EN_N 
0402 
R9G35 
2.7K 1
2
1/16W 
CHIP 
1% 
G21796-344 
0402 
1/16W 
649R2F-GP 
196 
147 
147 
147 
147 
147 
147 
147 
147 
118 145 
0402 
G21796-279 
CHIP 
1/16W 
3.48K 
R1U38 
0402 
0402 
1.0% 
0402 
1/16W 
CHIP 
0402 
R1U27 
G21796-279 
3.48K 
1.0% 
1/16W 
1% 
649OHM 
1/16W 
1% 
1.82KOHM 
1% 
1/16W 
1.82KOHM 
S
D
G
S
D
G
P3V_BAT_SOURCE_R 
CAD NOTE: 
DESIGN NOTE: 
1
2
1
2
1
2
DO NOT SCALE DRAWING SHEET 
B
AA
B
B
SIZE 
SCALE: 
234
1234
DEPARTMENT CODE 
1
DOCUMENT NUMBER REV 
OUT OUT 
OUT 
OUT 
P3V3_STBY 
P3V3_STBY 
IN 
PVNN_PCH_STBY 
OUT 
P3V3 
OUT 
P5V 
OUT 
P12V_STBY P3V3_STBY 
P1V05_PCH_STBY 
P5V_STBY 
IN 
OUT 
2
2 1
1
169 OF 270 
Wed Feb 08 16:35:16 2017 
1.31V 1.34V 
TP FAB1 CHANGE VALUE OF R1U38, R1U44 AND R1U33 1215
1.05V 
TP FAB1 CHANGE VALUE OF R1U28 AND R1U27 1215 
1.31V 
1.35V 
1.34V 
0.85V~1V 
1V 
FETS. 
E40049-001 WAS USED INSTEAD OF A C79254-001 
DUE TO ITS LOWER VGS(TH) THAN THE C79254-001 
VOLTAGE MONITORING 
WIWYNN CORPORATION 



G21497-005 
FM_OC_DETECT_N 
VCC=P3V3_STBY;GND=GND;TH=GND 
A36096-049 
1/16W 
R2P8 
4.75K 
1/16W 
G21796-072 U8D5 
IC 
G21796-072 
0402 
CHIP 
R2P5 
4.75K 
2
1
1% 
2
1
0402 
CHIP 
1/16W 
1% 
4.75K 
FM_FAST_PROCHOT_AND_OUT_1_N 
FM_FAST_PROCHOT_AND_OUT_0_N 
IRQ_FORCE_NM_THROTTLE_N 
FM_HSC_TIMER_EXP_N 
IRQ_UV_DETECT_N 
FM_FAST_PROCHOT_THROTTLE_IN_N 
IRQ_FORCE_NM_THROTTLE_R_N 
IRQ_SML1_PMBUS_ALERT_BUF_N 
FM_FAST_PROCHOT_EN_N 
FM_THROTTLE_N FM_THROTTLE_R1_N FM_FAST_PROCHOT_THROTTLE_DLY_BUF_N 
FM_PMBUS_ALERT_BUF_EN 
IRQ_SML1_PMBUS_ALERT_N 
FM_FAST_PROCHOT_EN 
FM_FAST_PROCHOT_THROTTLE_DLY_N 
FM_PMBUS_ALERT_BUF_EN_N 
A36096-030 
16V 
1
0402V 
10% 
X7R 2
0.1UF 
C2P1 
33.2 1% 
1/16W 
R2P4 
G21796-074 
CHIP 0402 
G21796-072 
1/16W 
4.75K 
R1R5 
1
1% 
0402 
CHIP 2
R8D26 
1% 
CHIP 
0402 
1
2
G21796-072 
3
C79254-001 
FET 
2N7002 
2
1
Q8F2 
1/16W 
CHIP 
0402 
4.75K 
G21796-072 
R9F3 
1
1% 
2
1/16W 
R2P11 
1% 
G21796-026 
EMPTY 
0402 
1.00K 
G21796-072 
4.75K 
R2P13 
1
1% 
1/16W 
CHIP 
0402 
2
Q2P1 
3
1
2N7002 
2 C79254-001 
FET 
1/16W 
4.75K 
R2T3 
1
1% 
CHIP 
0402 
G21796-072 
2
CHIP 
0.0 
0402 
21
R1R8 
5% 
1/16W 
X7R 
16V 
0402V 
10% 
0.1UF 
A36096-030 
C1R28 1
2
2 4
U1R1 
74LVC1G07 
IC 
C88419-001 
VCC=P3V3_STBY;GND=GND 
470PF 
C8D3 
EMPTY 
10% 
50V 
0402LF 
1
2
0402V 
A36096-030 2 X7R 
10% 
16V 
1 C8E2 
0.1UF 
VCC=P3V3_STBY;GND=GND 
74LVC1G07 
C88419-001 
IC 
2
U8D3 
4
74HC1G126 
A79322-001 
1
42
VCC=P3V3_STBY;GND=GND; 
0402V 
A36096-030 
X7R 
10% 
16V 
0.1UF 
C8D2 
2
1
X7R 
16V 
0402V 
10% 
0.1UF 
A36096-030 
C1R27 1
2
VCC=P3V3_STBY;GND=GND; 
4
1
A79322-001 
IC 
74HC1G126 
U1R2 
2
4.75K 
R2P3 
0402 
2
1
1% 
CHIP 
1/16W 
G21796-072 
13 
D90404-001 
11 
IC 
12 
U8E1 
74LVC08A 
U8E1 
74LVC08A 
6
VCC=P3V3_STBY;GND=GND;TH=GND 
4
5
D90404-001 
IC 
VCC=P3V3_STBY;GND=GND;TH=GND 
74LVC08A 
IC 
U8E1 
1
2
D90404-001 
3
200 
119 145 120 
200 120 145 
200 120 145 
191 
119 147 
119 133 95 146 
199 120 146 
191 
119 145 
S
D
G
S
D
G
CAD NOTE: 
CAD NOTE: 
CAD NOTE: 
CAD NOTE: 
DESIGN NOTE: 
CAD NOTE: 
COMES FROM A PUSH-PULL TRI-STATE BUFFER 
AN OPEN DRAIN NET. IRQ_SML1_PMBUS_ALERT_BUF_N 
74LVC1G07 USED TO MAKE IRQ_SML1_PMBUS_ALERT_BUF_N 
1 2
1
2
DO NOT SCALE DRAWING SHEET 
B
AA
B
B
SIZE 
SCALE: 
234
1234
DEPARTMENT CODE 
1
DOCUMENT NUMBER REV 
P3V3_STBY 
P3V3_STBY 
IN 
P3V3_STBY 
P3V3_STBY 
P3V3_STBY 
IN 
P3V3_STBY 
P3V3_STBY 
IN 
P3V3_STBY 
OUT 
IN 
P3V3_STBY 
P3V3_STBY 
P3V3_STBY 
P3V3_STBY 
IN 
OUT 
IN 
IN 
IN 
TTL1G07_A 
TTL1G07_A 
170 OF 270 
Wed Feb 08 16:35:16 2017 
FROM HSC TIMER 
FROM UNDER VOLTAGE MONITOR 
TO CPLD 
FROM CPLD 
FROM BMC AND IE 
TP FAB1 CHANGE R2P8 RES 0523 
FROM OVER CURRENT MONITOR 
PLACE CAP CLOSE TO VCC ON 
PLACE CAP CLOSE TO VCC ON 
TRI STATE BUFFER 
74HC1G126 PLACE CAP CLOSE TO VCC ON 
1G07 BUFFER PLACE CAP CLOSE TO VCC ON 
74LVC1G07 PLACE CAP CLOSE TO VCC ON 
74LVC08 
FAST PROCHOT LOGIC 
WIWYNN CORPORATION 



DO NOT SCALE DRAWING SHEET 
B
AA
B
B
SIZE 
SCALE: 
234
1234
DEPARTMENT CODE 
1
DOCUMENT NUMBER REV 
171 OF 270 
Wed Feb 08 16:35:16 2017 
SPARE 
WIWYNN CORPORATION 



ROOM=ST_SATA 
2.6A, 16V, POLY 
A36096-045 
SATA6G_S1_RX_C_DN 
SATA6G_S1_RX_C_DP 
SKT-SATA7P-6P-165-GP-U1 
C9B1 
10UF 
16V 
10% 
10UF 
1
16V 
C95333-007 2 X6S 
0805 
10% 
C9B2 1
X6S 2 C95333-007 
0805 
1 2
10% 
C2L49 
0.01UF 
0402V 
X7R 
25V 
A36096-045 
25V 
10% 
C2L52 
0402V 
21
X7R 
0.01UF 
2 1
C94311-016 
F9B1 
IC 
J2W1 
SKT-SATA7P-6P-165-GP-U1 
J2W2 
1
0.01UF 
2
C2L50 
A36096-045 
10% 
0402V 
X7R 
25V 
FUSE-3A75V-GP 
F8B1 
1
A36096-045 
2
X7R 
0402V 
10% 
25V 0.01UF 
C2L51 
SATA6G_S1_RX_DP 
P12V_HDD_SATA 
SATA6G_S1_TX_C_DP 
SATA6G_S1_RX_DN 
SATA6G_S1_TX_DN 
SATA6G_S1_TX_DP 
SATA6G_S1_TX_C_DN 
P5V_HDD_SATA 
116 
116 
116 
116 
DESIGN NOTE: 
DESIGN NOTE: 
S4 
S2 
S3 
H2 
H1 
NP2 
NP1 
P5 
P4 
S6 
S5 
S4 
S2 
S1 
P2 
P6 
S7 
P1 
P3 
P4 
S1 
S3 
S5 
S6 
S7 
P1 
P3 
P5 
NP1 
NP2 
H1 
P2 
H2 
P6 
21POPULATE FOR 2-SIDED BOARD 
POPULATE FOR SINGLE SIDED BOARD 
DO NOT SCALE DRAWING 
PLACE ON THE SECONDARY SIDE 
PLACE ON THE PRIMARY SIDE 
SHEET 
B
AA
B
B
SIZE 
SCALE: 
234
1234
DEPARTMENT CODE 
1
DOCUMENT NUMBER REV 
OUT 
P5V 
P12V 
IN 
IN 
OUT 
172 OF 270 
TP FAB1 CHANGE FUSE FOR FOLLOW LEOPARD DESIGN 0128 
CHANGE TO 5V 
TP FAB1 CHANGE TO SATA 13 PIN CONNECTORS 0104 
CHANGE TO GND 
CHANGE TO 12V 
CHANGE TO 12V 
TP FAB1 CHANGE PN TO 022.10014.0121 0121 
CHANGE TO GND 
BOM_SS=NOPOP 
BOM_DS=NOPOP 
SATA DOWN CONNECTOR Wed Feb 08 16:35:17 2017 
WIWYNN CORPORATION 



A36096-045 
1D7 
A36096-045 
0402V 
SATA6G_P6_TX_C_DP 
PU_DATAIN1_SATA_0_R 
SATA6G_P1_RX_C_DP 
TP_FM_QAT_CBL_PRSNT0_R_N 
SATA6G_P2_TX_C_DN 
SATA6G_P4_TX_C_DP 
SATA6G_P0_RX_C_DP 
SATA6G_P0_RX_C_DN 
SATA6G_P4_TX_C_DN 
SGPIO_PCH_SATA_CLOCK_R 
SGPIO_PCH_SATA_LOAD_R 
TP_SGPIO_SATA_LOAD1_R 
TP_SGPIO_SATA_CLOCK1_R 
SGPIO_PCH_SATA_DOUT0_R 
TP_SGPIO_SATA_DATA1_R 
TP_FM_QAT_CBL_PRSNT1_N_R 
PU_DATAIN1_SATA_1_R 
SATA6G_P5_RX_C_DN 
SATA6G_P5_RX_C_DP 
SATA6G_P4_RX_C_DP 
SATA6G_P1_RX_C_DN 
SATA6G_P2_RX_C_DP 
SATA6G_P3_RX_C_DP 
SATA6G_P4_RX_C_DN 
PD_SATA1_CONTROLLER_TYPE_R 
SATA6G_P3_TX_C_DP 
SATA6G_P3_TX_C_DN 
SATA6G_P6_TX_C_DN 
SATA6G_P5_TX_C_DN 
SATA6G_P5_TX_C_DP 
SATA6G_P0_TX_C_DP 
SATA6G_P1_TX_C_DN 
SATA6G_P7_TX_C_DP SATA6G_P7_RX_C_DP 
SATA6G_P7_RX_C_DN 
SATA6G_P6_RX_C_DN 
SATA6G_P6_RX_C_DP 
SATA6G_P2_TX_C_DP 
PD_SATA0_CONTROLLER_TYPE_R 
SATA6G_P0_TX_C_DN 
SATA6G_P7_TX_C_DN 
SATA6G_P3_RX_C_DN 
SATA6G_P2_RX_C_DN 
SATA6G_P1_TX_C_DP 
SATA6G_PCH_PCIE_UP_SATA_RXN<7:0> 
SATA6G_PCH_PCIE_UP_SATA_RXP<7:0> 
SATA6G_PCH_PCIE_UP_SATA_TXP<7:0> 
SATA6G_PCH_PCIE_UP_SATA_TXN<7:0> 
1
1
2
1/16W 
CHIP 
0402 
1% 
1.00K 
G21796-026 
R2L18 
1
2
1/16W 
CHIP 
0402 
1% 
1.00K 
G21796-026 
R2L22 
1
2
1/16W 
CHIP 
0402 
1% 
2.0K 
G21796-001 
R2L21 
1/16W 
1 2
CHIP 0402 
1% 2.0K 
G21796-001 
R2L23 
0.01UF 
1 2
X7R 
25V 
0402V 
10% 
A36096-045 
C2L21 
A36096-045 
1 2
0402V 
C2L24 
X7R 
25V 
10% 
0.01UF 
C2L48 
1 2
X7R 
25V 
0402V 
10% 
0.01UF 
A36096-045 
0.01UF 
A36096-045 
1 2
X7R 
25V 
10% 
C2L38 
21
X7R 
25V 
0402V 
10% 
0.01UF 
A36096-045 
C2L26 
6
7
6
5
A36096-045 
25V 
1 2
X7R 
0402V 
10% 
0.01UF 
C2L41 
21
X7R 
25V 
0402V 
10% 
0.01UF 
A36096-045 
C2L23 
2
A36096-045 
0.01UF 25V 
1
X7R 
0402V 
10% 
C2L27 
1 2
X7R 
25V 
0402V 
10% 
0.01UF 
A36096-045 
C2L47 
21
X7R 
25V 
0402V 
10% 
0.01UF 
A36096-045 
C2L37 
4
5
4
21
X7R 
25V 
0402V 
10% 
0.01UF 
A36096-045 
C2L22 
A36096-045 
21
X7R 
25V 
0402V 
10% 
0.01UF 
C2L42 
3
2
3
2
1 2
X7R 
25V 
0402V 
10% 
0.01UF 
A36096-045 
C2L44 
C2L43 
A36096-045 
0.01UF 25V 
1 2
X7R 
0402V 
10% 
0.01UF 
0402V 
21
X7R 
25V 
10% 
C2L39 
21
X7R 
25V 
0402V 
10% 
0.01UF 
A36096-045 
C2L40 
0
1
1
0
7
7
6
7
6
5
C2L5 
A36096-045 
21
X7R 
25V 
0402V 
10% 
0.01UF 
X7R 
0402V 
21
25V 
10% 
0.01UF 
A36096-045 
C2L14 
A36096-045 
21
X7R 
25V 
0402V 
10% 
0.01UF 
C2L9 
0402V 
X7R 
25V 
1 2
10% 
0.01UF 
A36096-045 
C2L7 
0.01UF 
21
X7R 
25V 
0402V 
10% 
A36096-045 
C2L16 
4
5
4
3
3
2
2
C2L18 
A36096-045 
21
X7R 
25V 
0402V 
10% 
0.01UF C2L12 
A36096-045 
0.01UF 
1 2
X7R 
25V 
0402V 
10% 
21
X7R 
25V 
0402V 
10% 
0.01UF 
A36096-045 
C2L20 
21
X7R 
25V 
0402V 
10% 
0.01UF 
C2L3 
0.01UF 
1 2
X7R 
25V 
0402V 
10% 
A36096-045 
C2L4 
0402V 
1 2
X7R 
25V 
10% 
0.01UF 
A36096-045 
C2L15 
1
0
0 21
X7R 
25V 
10% 
0.01UF 
A36096-045 
C2L17 
0402V 
C2L10 
1 2
X7R 
25V 
0402V 
10% 
0.01UF 
A36096-045 
A36096-045 
1 2
X7R 
25V 
0402V 
10% 
0.01UF 
C2L19 
1 2
X7R 
25V 
0402V 
10% 
0.01UF 
A36096-045 
C2L6 
21
X7R 
25V 
0402V 
10% 
0.01UF 
A36096-045 
C2L13 
2A7 2C7 
2C8 
2D7 
2D8 
2D4 
2D5 
1C7 
1C8 
1D8 
1C4 
1C5 
1D4 
1D5 
2A1 
2D2 2D1 
2C1 
2B1 
2C2 
2B2 
2A2 
1A1 
1D2 1D1 
1C1 
1B1 
1C2 
1B2 
1A2 
2A8 
2B7 
2B8 
2A4 
2A5 
2B4 
2B5 
1A7 
1A8 
1B7 
1B8 
1A4 
1A5 
1B4 
1B5 
1A3 
1A6 
1A9 
1B3 
1B6 
1B9 
1C3 
1C6 
1C9 
1D3 
1D6 
1D9 
2A3 
2A6 
2A9 
2B3 
2B6 
2B9 
2C3 
2C6 
2C9 
2D3 
2D6 
2D9 
2C5 
2C4 
CONN 
G97614-002 
J8A1 
178 
178 
178 
116 
116 
116 
116 
CAD NOTE: 
CAD NOTE: 
CAD NOTE: 
DESIGN NOTE: 
CAD NOTE: 
DO NOT SCALE DRAWING 
MINI-SAS CONN SATA 
PLACE COMPONENTS CLOSE TO CONNECTOR 
PLACE COMPONENTS CLOSE TO CONNECTOR 
PLACE CAPS CLOSE TO PCH 
PLACE CAPS CLOSE TO PCH 
SHEET 
B
AA
B
B
SIZE 
SCALE: 
234
1234
DEPARTMENT CODE 
1
DOCUMENT NUMBER REV 
IN 
IN 
IN 
P3V3 
P3V3 
IN 
IN 
OUT 
OUT 
173 OF 270 
Wed Feb 08 16:35:17 2017 
SIDEBANDB_0 SIDEBANDB_1 SIDEBANDB_2 
SIDEBANDB_6 
SIDEBANDA_3 SIDEBANDA_7 
RXA3_DP 
GND<19> 
RXA2_DN 
GND<20> 
SIDEBANDA_5 
SIDEBANDA_4 
GND<9> 
RXB1_DP 
RXB1_DN 
GND<6> 
RXB3_DN 
GND<7> 
RXB2_DN RXB2_DP 
GND<8> 
SIDEBANDB_4 SIDEBANDB_3 SIDEBANDB_7 
GND<10> 
GND<23> 
GND<22> 
GND<21> 
GND<17> 
GND<16> 
GND<15> 
GND<14> 
GND<13> 
GND<12> 
GND<11> 
GND<4> 
GND<3> 
GND<2> 
GND<1> 
GND<0> 
RXA0_DN RXA0_DP 
RXA1_DN RXA1_DP 
RXA2_DP 
RXA3_DN 
RXB0_DN RXB0_DP 
RXB3_DP 
SIDEBANDA_0 SIDEBANDA_1 SIDEBANDA_2 
SIDEBANDA_6 
SIDEBANDB_5 
TXA0_DN TXA0_DP 
TXA1_DN TXA1_DP 
TXA2_DN TXA2_DP 
TXA3_DN TXA3_DP 
TXB0_DN 
TXB1_DN TXB1_DP 
TXB2_DN TXB2_DP 
TXB3_DN TXB3_DP 
TXB0_DP 
GND<5> 
GND<18> 
VERTICAL MINI-SAS 
MINI_SAS (1/2) 
CONN72_G97614002_A 
WIWYNN CORPORATION BOM_COST=ST_SATA 
ROOM=ST_SATA 



DO NOT SCALE DRAWING SHEET 
B
AA
B
B
SIZE 
SCALE: 
234
1234
DEPARTMENT CODE 
1
DOCUMENT NUMBER REV 
174 OF 270 
TP FAB3 DELETE MINI-SAS X4 0920 
MINI_SAS (2/2) Wed Feb 08 16:35:17 2017 
WIWYNN CORPORATION 



1Y 
VCC 
2Y 2A 
GND 
1A 
1Y 
VCC 
2Y 2A 
GND 
1A 
RST_SYSTEM_BTN_N 
FP_RST_BTN_BUF1_N 
1% 
5% 
470.0 
R1L8 
G21497-024 
0402 
2 CHIP 
1/16W 
1
FP_ID_LED_XOR_R 
G21796-074 
0.1UF 
FP_ID_LED_P5V_STBY_N 
A36096-030 
C1L4 
C96565-012 
2
FM_PWR_BTN_R_N 
FP_PWR_BTN_BUF1_N 
FP_PWR_BTN_R_N 
RST_SYSTEM_BTN_BUF_N 
PWRGD_P3V3_R 
FP_PWR_ID_LED_N 
FM_BIOS_TOP_SWAP_SPKR PWRGD_P3V3 
FM_PWR_BTN_N 
FP_PWR_BTN_R1_N 
FP_RST_BTN_R_N 
FM_BEEP_LED_P FM_SPEAKER_PCH_N 
FM_DEBUG_RST_BTN_N 
0402 
G21796-072 
CHIP 
1/16W 
1% 
4.75K 
R1L19 
U9A4 
TC7PZ14FU-GP 
0402 
CHIP 1/16W 
100.0 1% 
2
R9A9 
G21796-017 
1
TC7PZ14FU-GP 
U9A3 
S9A2 
D37771-002 
IC 
YELLOW 
C96565-003 
2
IC 
1
DS9A3 
1
16V 
0402V 
X7R 2
10% 
CHIP 
21
0402 
5% 
R1L12 
G21497-005 
0.0 
1/16W 
U1L2 
IC 
2
D39848-001 
VCC=P5V_STBY;GND=GND; 
1
4
74AHCT1G86 
BLUE 
IC 
DS9A1 
1
R1L27 
2
1 4.75K 
1% 
CHIP 
1/16W 
0402 
G21796-072 
3
1
2
FET 
2N7002 
Q9A3 
C79254-001 
1/16W 
1.0% 0402 
1
CHIP 
2
G21796-271 
R1L33 
221 
0402V 
A36096-030 
2 X7R 
10% 
C9A3 
0.1UF 
16V 
1
1
1/16W 
200.0 
G21796-004 
R1L31 
2
CHIP 0402 
2
0.1UF 
C1L9 1
10% 
0402V 
A36096-030 
X7R 
16V 
10% 
X7R 
C1L17 
2
0402V 
1
16V 
0.1UF 
A36096-030 
G21796-004 
0402 CHIP 1/16W 
200.0 
1
R1L22 
2
1% 
10% 
X6S 
D97712-004 
0402V 
6.3V 
1 C1L10 
1.0UF 
2
2
R1L26 
1% 
1
33.2 
1/16W CHIP 
0402 
10% 
C1L18 
2
1
X6S 
0402V 
1.0UF 
6.3V 
D97712-004 
119 145 
247 
118 
120 133 
146 
119 136 196 190 248 
119 145 
190 
111 155 247 190 
S
D
G
1
D37771-002 
IC 
S9A1 
4 3
2
CAD NOTE: 
CAD NOTE: 
CAD NOTE: 
CAD NOTE: 
CAD NOTE: 
2
1
6
5
43
2
1
3
2
1
4
5
6
DO NOT SCALE DRAWING SHEET 
B
AA
B
B
SIZE 
SCALE: 
234
1234
DEPARTMENT CODE 
1
DOCUMENT NUMBER REV 
OUT 
IN 
P5V_STBY 
P3V3_STBY 
P3V3_STBY 
IN 
IN 
P3V3_STBY 
P5V_STBY 
IN 
P3V3_STBY 
P3V3_STBY 
IN 
P3V3_STBY 
OUT 
OUT 
175 OF 270 
12
4 3
ID LED LIGHT WHEN NORMAL POWER IS UP. 
PIN1 PIN2 | PIN4 
1 0 | 1
U1L2 TRUTH TABLE 
0 0 | 0
1 1 | 0
0 1 | 1
IF = 25MA 
TP FAB1 ADD OFFPAGE 1117 
TP FAB1 CHANGE U2R1 PN 1222 
IR = 14.9MA 
IF = 25MA 
IR = 10.6MA 
TP FAB1 CHANGE U9A3 PN 1222 
TP FAB1  CH ANGE SYMBOL AS S9A1 1207 
TP FAB1 CHANGE TO POP FOR CONTROL BOM 0128 
PLACE 0.1UF CAP CLOSE TO VCC OF 74AHCT1G86 
PLACE 0.1UF CAP NEXT TO VCC PIN ON 74LVC2G14 
PLACE YELLOW LED IN BETWEEN BMC 
DEBUG HEADER AND BOARD EDGE 
YELLOW LED SHOULD BE LEFT-MOST LED 
ON BOARD EDGE 
PLACE 0.1UF CAP NEXT TO VCC PIN 
ON TTL1G07_A 
PLACE 0.1UF CAP NEXT TO VCC PIN ON 74LVC2G14 
PWR, RESET BTN & LEDS Wed Feb 08 16:35:17 2017 
WIWYNN CORPORATION 



G21497-005 
G21497-005 1/16W 
1/16W 
1/16W CHIP 
CHIP 1/16W 
CHIP 
C99406-001 
R6W30 5
IC SMLF 
100.0K 
1
1
VCC=P3V3_STBY;GND=GND; 
1/10W 
J9B1 
SPA_MID_DBG2_TX 
4
SPA_MID_DBG2_RX_BUF 
USB2_P01_ESD_DP 
USB2_P01_ESD_DN 
USB2_P01_DP 
0.0 
1
5% 0402 CHIP 
R1M5 
2
USB2_P01_DN 
0402 
R1M6 
21
5% 
CHIP 0.0 
TP_USB_ESD_AC3 
0402 
G21497-005 
H66405-001 
10V 
G21497-005 
TP_USB_ESD_AC2 
SPA_MID_DBG2_RX 9
10.0 
SPA_MID_DBG1_TX_R 
VCC=P3V3_STBY;GND=GND; 
G21796-066 
SPA_MID_DBG1_TX 
0402 
R6W37 
VCC=P3V3_STBY;GND=GND; 
1% 
R6W36 
G21796-016 
SPA_MID_DBG2_TX_R 
U6W5 
P5V_USB 
ESD3V3U4ULC 
4
5
G21796-040 
0402 
74HC1G126 
1
2
IC 
GND=GND 
10% 
16V 
G81764-001 
5% 0402 
0402V 
A36096-030 
0402 
10.0K 
1% 
X7R 
G21497-005 R1W38 
42
0603 
2
G22026-050 
CHIP 
74HC1G126 IC 
SPA_MID_DBG2_RX 
IC 
4
1
1
1
2
2
G21796-066 1/16W 
CHIP 
CHIP 
1
2
1/16W 
1
1/16W 
SPA_MID_DBG2_TX 
7
1
4
5 6
2
TP_USB_ESD_OUT2 
TP_USB_ESD_OUT3 
0402 
2 CHIP 
1
1 C9B8 
2
4
3
IC 
1
2
A36096-030 
2
1 0.1UF 
16V 
10% 
5% 
FM_CPLD_USB_P0_EN_N 
0.0 
CHIP 1% 
1/16W 
20% 
P5V_USB 
FM_OC0_USB_N 
R6W39 
5% 
R1W12 
R1W13 
0.0 
5
C1M38 
G21497-005 
1% 
2
G21796-016 
CHIP 
1/16W 
FM_USB_P0_EN_BOOT_BIOS_STRAP_N 
C1W19 
X7R 
6
330UF 
0402 
7343HLF 
POSCAP 
1
0402 
U1W3 
IC 
2
0.1UF 0.1UF 
8
G18435-001 
U1M3 
G22179-004 
5% 
0805 
0.0 
1/8W 
CHIP 
8
6
7
MH4 
MH3 
R1M25 
10.0K 1
724613-043 
0.0 0402 
21
5% 
2
0.0 
0402 
1
2
0.0 5% 
G21497-005 0.0 
2
1
R1W39 
5
3
1
10% 
X7R 
16V 
2
0402V 
2A36096-030 
C1W18 1
9
8
1
5% 
PLACE CAP CLOSE 
TO IC 
0402V 
OVERLAPPING FOOTPRINT 
G21796-016 
3
SPA_MID_DBG1_TX_EN 
U6W4 
A79322-001 
2
U6W6 
1
0402 
1/16W 
H51826-001 
2
20.0K 
R1M24 
MH2 
MH1 
2
0402 
10.0 
1% 
1% 
7
G21497-005 
R6W38 
1% 
A79322-001 
A79322-001 
10.0K 
74HC1G126 
R1W34 
R1W33 
CONN 
1
3
R1W10 
CR1M2 
IC 
4
3
6
U6W12 
A36096-030 
2
0402V 
X7R 
10% 
16V 
1 0.1UF 
C6W10 
2
SPA_MID_DBG1_RX 
TP FAB1 ADD AND GATE TO ISOLATE RX SIGNAL 1119 
TP FAB4 CHANGE AND GATE TO MUX 20170125 
TP FAB3-DVT ADD RES R6W50 20161114 
TP FAB4 NOPOP RES R6W50 20170124 
TP FAB1 CHANGE NET NAME 1117 
TP FAB3 POP L1M2 AND NOPOP R1M5 AND R1M6 0830 
TP FAB1 DEL USB3.0 SIGNAL 1117 
TP FAB3-DVT CHANGE L1M2 TO THE CORRECT HDL/LAYOUT SYMBOL 20161208 
181
158
115 
115 
176 
155 
176 
190 
176 
120 190 
119 125 
145 247 
168 
176 
158 181 
145 247 
155 
CHIP 
G21796-072 
NOPOP 
1/16W 
0402 
R6W50 
1% 
752402-015 
L1M2 
IND 
90 OHM 
0805 
G22179-004 
NOPOP 
1/16W 
1% 
R1W37 
4.75K 
5% 
1/8W 
EMPTY 
R1W11 
1/16W 
1/16W 
NOPOP 
0.0 
1/16W 
CHIP 
G21796-072 
0402 
1/16W 
R1W36 
4.75K 
1% 
1/16W 
0402 
G21796-072 
CHIP 
4.75K 
176 
176 168 
176 
176 
176 
176 
176 
176 
176 
176 
176 168 
176 
176 
176 
176 
176 
176 
176 168 
176 168 
SPA_MID_DBG_RX 
DEBUG_CARD2_PRSNT 
SMB_DEBUG_STBY_LVC3_SCL_R1 
SMB_DEBUG_STBY_LVC3_SCL_R1 
SMB_DEBUG_STBY_LVC3_SDA_R1 
SMB_DEBUG_STBY_LVC3_SCL_CONN 
SMB_DEBUG_STBY_LVC3_SDA_CONN 
SMB_DEBUG_STBY_LVC3_SCL_CONN 
SMB_DEBUG_STBY_LVC3_SDA_CONN 
DEBUG_CARD2_PRSNT 
SMB_DEBUG_STBY_LVC3_SCL 
SMB_DEBUG_STBY_LVC3_SCL_CONN 
SMB_DEBUG_STBY_LVC3_SDA_CONN 
DEBUG_CARD2_PRSNT 
SMB_DEBUG_STBY_LVC3_SDA 
SMB_DEBUG_STBY_LVC3_SDA_R1 
SMB_DEBUG_STBY_LVC3_SCL_R1 
SMB_DEBUG_STBY_LVC3_SDA_R1 
DEBUG_CARD2_PRSNT 
DEBUG_CARD2_PRSNT 
SPA_MID_DBG_TX 
PLACE AS CLOSE AS POSSIBLE TO USB CONNECTOR 
CAD NOTE: 
CAD NOTE: 
DESIGN NOTE: 
CAD NOTE: 
ROOM=USB_REAR 
3
41
2
2
2
2
1
1
P5V_TPS2061 
1
2
1 1
2
FM_USB_P0_EN_R_N 
1
2
2
1
DO NOT SCALE DRAWING 
S
B0 
B1 
VCC 
A
GND 
SHEET 
B
AA
B
B
SIZE 
SCALE: 
234
1234
DEPARTMENT CODE 
1
DOCUMENT NUMBER REV 
IN 
BI 
BI 
NC7SB3157 
P3V3_STBY 
P3V3_STBY 
P3V3_STBY P3V3_STBY 
P3V3_STBY P3V3_STBY 
P3V3_STBY 
OUT 
IN 
BI 
IN 
P3V3_STBY 
IN 
IN 
P5V_STBY 
OUT 
IN 
P3V3_STBY 
OUT 
OUT 
P3V3_STBY 
OUT 
OUT 
P5V 
CHOKE 4PIN 
Wed Feb 08 16:35:18 2017 
176 OF 270 
OUT0 
GND 
OUT1 
OUT3 
OUT2 
AC0 AC1 AC2 AC3 
MH4 MH3 MH1 
GND GND_DRAIN 
MH2 
DN DP 
VBUS 
STDA_SSTXP 
STDA_SSTXN STDA_SSRXP STDA_SSRXN 
PCA9617 VCCA 
SCLA 
SDAA SCLB SDAB 
VCCB 
EN 
OC_N 
GND 
OUT IN 
EN_N 
S=1: B1 
S=0: B0 
NC7SB3157 
TP FAB3 ADD R6W30 0803 
TP FAB3 CHANGE R6W30 0803 
THIS UART AND GATE IS FOR THE CASE THAT BOTH OF DEBUG INPUTS ARE PUSH-PULL. 
TP FAB3 ADD CIRCUIT 0803 
TP FAB1 ADD R1W10 AND R1W11 1221 
TARGET 3.3V 
FM_USB_P0_EN_R_N 
ENABLE 
TP FAB3 ADD BUF 0803 
TP FAB3 ADD I2C CIRCUIT 0803 
TP FAB1 ADD R1W12 AND R1W13 1221 
TP FAB1 NOPOP R1W13 0427 
S0 OR S5 
NEAR U1W3 
TP FAB3 ADD RES 0803 
SYSTEM STATUS 
NOPOP 
NOPOP 
SHORT-CIRCUIT OUTPUT CURRENT 1.1A MIN - 1.9A MAX 
TPS2061 
NOPOP 
USB3 EXTERNAL RIGHT ANGLE CONNECTOR 
CONN9_H51826001 
TPS2061 
WIWYNN CORPORATION 



ROOM=MIO_CHASSIS 
G21796-076 
FP_LED_HDD_ACTIVITY_AND_N 
C96565-011 
LED_P5V_STBY FM_RED_LED_ANODE 
FM_RED_LED_CATHODE 
LED_PCH_SATA_HDD_N 
LED_PCH_SSATA_HDD_N 
FM_BMC_FAULT_LED 
FM_BMC_FAULT_LED_N 
FP_LED_HDD_ACTIVITY_AND_R_N 
LED_SAS_ACT_R_N 
LED_SATA_ACT_R_N 
1/16W 
10.0K 
R1M11 
0402 
1
2CHIP 
1% 
G21796-016 
R9F52 
G21796-072 
4.75K 
1% 
0402 
CHIP 
1/16W 
2
1
Q9F1 
E40049-001 
NTJD4001N 
FET 
1
2
6
G21796-016 
0402 
CHIP 
1
2
1/16W 
1% 
10.0K 
R1M12 
3
5
4
FET 
NTJD4001N 
E40049-001 
Q9F1 
R9F30 
4.75K 
1% 
0402 
CHIP 
1/16W 
2
1
G21796-072 
1
2
1/16W 
CHIP 
0402 
1.0% 
221 
G21796-271 
R9F28 
RED 
1
2
IC 
D14725-005 
DS9F1 
IC 
SOTLF 
VCC=P3V3;GND=GND; 
D10321-001 
U1M1 
1
2
4
NC7SZ08 
2
1/16W 
0402 R1M10 
1CHIP 
5% 0.0 
G21497-005 
R1L21 
1/16W 
64.9 
1.0% 
1
CHIP 
0402 
2
G21796-298 DS9A2 
1 2
IC 
GREEN 
1/16W 
CHIP 
0402 
1% 
301.0 
R1L37 
GREEN 
1
2
IC 
C97278-010 
DS9A6 
0.0 
5% 1/16W 
0402 
G21497-005 
R1M13 
2
CHIP 
1
2
1
X6S 
6.3V 
0402V 
10% 
1.0UF 
D97712-004 
C1M3 
120 
120 
119 147 
S
D
G
S
D
G
CAD NOTE: 
DO NOT SCALE DRAWING SHEET 
B
AA
B
B
SIZE 
SCALE: 
234
1234
DEPARTMENT CODE 
1
DOCUMENT NUMBER REV 
P3V3 
IN 
P3V3_STBY 
P3V3_STBY 
P3V3_STBY 
P3V3 
IN 
P5V_STBY 
P3V3 
IN 
177 OF 270 
Wed Feb 08 16:35:18 2017 
TP FAB1 CHANGE RES AND LED 0422 
POWER PINS 
CAD NOTE: 
ADD 0.1UF CAPS FOR VCC 
NEW_PN=83.00320.A70 
PLEASE PLACE LED NEAR BMC 
CONFIG=64.12005.6DL 
SYSTEM LEDS 
WIWYNN CORPORATION 



SGPIO_PCH_SATA_LOAD 
SGPIO_PCH_SSATA_DOUT0_R 
SGPIO_PCH_SSATA_CLOCK_R 
0402 
R2L5 
2.0K 
G21796-001 
0402 
0402 
G21796-047 
G21796-047 
SGPIO_PCH_SSATA_LOAD_R 
SGPIO_PCH_SATA_CLOCK 
SGPIO_PCH_SATA_DOUT0 SGPIO_PCH_SATA_DOUT0_R 
SGPIO_PCH_SATA_CLOCK_R 
SGPIO_PCH_SATA_LOAD_R 
SGPIO_PCH_SSATA_CLOCK 
SGPIO_PCH_SSATA_LOAD 
SGPIO_PCH_SSATA_DOUT0 
1 2
1/16W CHIP 0402 1% 49.9 G21796-047 
R8D19 
1 2
1/16W CHIP 0402 1% 49.9 G21796-047 
R2N22 
1 2
1/16W CHIP 1% 49.9 
R2N19 
1 2
1/16W CHIP 1% 49.9 
R8B29 
1
2
1/16W 
CHIP 
0402 
1% 
1
2
1/16W 
CHIP 
0402 
1% 
2.0K 
G21796-001 
R2L12 
1
2
1/16W 
CHIP 
0402 
1% 
2.0K 
G21796-001 
R2L4 
1
2
1/16W 
CHIP 
0402 
1% 
2.0K 
G21796-001 
R2L6 
G21796-001 
1
2
1/16W 
CHIP 
1% 
2.0K 
R2L11 
1
2
1/16W 
CHIP 
0402 
1% 
2.0K 
G21796-001 
R2L15 
1 2
1/16W CHIP 0402 1% 49.9 G21796-047 
R2N31 
1 2
1/16W CHIP 0402 1% 49.9 G21796-047 
R8D20 
120 
120 
120 173 
173 
173 
120 
120 
119 
DESIGN NOTE: 
DESIGN NOTE: 
DESIGN NOTE: 
DESIGN NOTE: 
DO NOT SCALE DRAWING SHEET 
B
AA
B
B
SIZE 
SCALE: 
234
1234
DEPARTMENT CODE 
1
DOCUMENT NUMBER REV 
IN 
OUT IN 
P3V3_STBY 
OUT IN 
IN 
IN 
IN 
P3V3_STBY 
OUT 
178 OF 270 
Wed Feb 08 16:35:18 2017 
X4 SSATA DOWN CONN 
X8 MINI-SAS VERTICAL PCH PCIE_UP 
PLACE RESISTORS CLOSE TO MINI SAS CONNECTOR 
PLACE RESISTORS <2 INCHES FROM PCH 
PLACE RESISTORS <2 INCHES FROM PCH 
PLACE RESISTORS CLOSE TO MINI SAS CONNECTOR 
SATA SGPIO CONNECTORS 
BOM_COST=ST_SATA 
ROOM=ST_SATA 
WIWYNN CORPORATION 



DO NOT SCALE DRAWING SHEET 
B
AA
B
B
SIZE 
SCALE: 
234
1234
DEPARTMENT CODE 
1
DOCUMENT NUMBER REV 
179 OF 270 
Wed Feb 08 16:35:18 2017 
SPARE 
WIWYNN CORPORATION 



DO NOT SCALE DRAWING SHEET 
B
AA
B
B
SIZE 
SCALE: 
234
1234
DEPARTMENT CODE 
1
DOCUMENT NUMBER REV 
180 OF 270 
Wed Feb 08 16:35:19 2017 
SPARE 
WIWYNN CORPORATION 



MB_SLOT_ID1 
MB_SLOT_ID2 
PCIE_PERST# 
PMBUS_ALERT# 
PCIE_CLK_100M_DN 
J4 
PCIE_CLK_100M_DP 
GND14 
FAN_PWM0 
FAN_TACH1 
MATED_IN# 
FAN_TACH0 
FAN_TACH2 
FAN_TACH3 
MB_ON# 
COM_RX 
GND11 
COM_TX 
PCIE_RX_DN7 
GND4 
PCIE_RX_DP7 
PCIE_RX_DN6 
PCIE_RX_DP6 
J2 
PCIE_RX_DN5 
PCIE_RX_DN4 
PCIE_RX_DP5 
GND13 
GND7 
PCIE_RX_DP4 
PCIE_RX_DN3 
GND1 
PCIE_RX_DP3 
GND17 
PCIE_RX_DN2 
PCIE_RX_DP2 
GND10 
PCIE_RX_DP1 
PCIE_RX_DN1 
GND3 
PCIE_RX_DN0 
PCIE_RX_DP0 
J8 
PCIE_TX_DN2 
PCIE_TX_DP2 
GND16 
PCIE_TX_DN1 
GND9 
PCIE_TX_DP1 
PCIE_TX_DN0 
GND2 
PCIE_TX_DP0 
PCIE_TX_DN5 
GND18 
GND12 
PCIE_TX_DP5 
PCIE_TX_DN4 
GND6 
PCIE_TX_DP4 
PCIE_TX_DN3 
PCIE_TX_DP3 
PCIE_TX_DN7 
J6 
PCIE_TX_DP7 
GND15 
PCIE_TX_DN6 
GND8 
PCIE_TX_DP6 
PMBUS_CLK 
PMBUS_DATA 
MNG_RX_DP 
MNG_RX_DN 
GND5 
MNG_TX_DN 
MNG_TX_DP 
MB_SLOT_ID0 
Notice:20.82092.076 
SMB_BMC_PMBUS_STBY_LVC3_SCL 
1/16W 
SMB_BMC_PMBUS_STBY_LVC3_SDA 
1.0% 
2
R3P61 
IRQ_SML1_PMBUS_ALERT_R_N 
FM_MATED_IN_N 
FM_MP_PS_FAIL_N 
FM_MP_PS_REDUNDANT_LOST_N 
H62179-001 
G21796-074 10% 0402V 
0402 
15.0K 
FM_P12V_HOTSWAP0_EN 
FM_CTNR_PS_ON 
J1F3 
CONN 
2
3
C8E1 
1/16W 
CHIP 
1
G21796-072 
4.75K 
1% 
R9T9 
1
1/16W 
CHIP 2
0.0 
5% 
FM_MATED_IN_D2_N 
G21796-107 
2
0.22UF 
P3E_CPU1_PE3_MP_C_TXP<2> 
P3E_CPU1_PE3_MP_C_TXN<2> 
SM 
IC 
Q9T1 6.19K 
R9T3 
1 FM_MB_SLOT_ID2 
D90404-001 
VCC=P3V3_STBY;GND=GND;TH=GND 
0402LF 
SDMK0340L 
DM-FCI-CONN76-8R-GP-U-01 
P3E_CPU1_PE3_MP_C_TXN<5> 
P3E_CPU1_PE3_MP_C_TXP<4> 
1.0% 
P3E_CPU1_PE3_MP_TXP<7:0> 
0402 
5
R7D5 
2
0402 
CHIP 
G21796-161 
1
1% 
1/16W 
74LVC08A 
C52245-001 
U8E1 
NIC_MDI_MNG_TX_DP 
NIC_MDI_MNG_TX_DN 
IRQ_SML1_PMBUS_ALERT_R_N 
SMB_BMC_PMBUS_STBY_LVC3_SDA 
SMB_BMC_PMBUS_STBY_LVC3_SCL 
P3E_CPU1_PE3_MP_C_TXN<6> 
P3E_CPU1_PE3_MP_C_TXP<7> 
P3E_CPU1_PE3_MP_C_TXN<3> 
PWRGD_P12V_HSC_DLY 
FM_PS_EN 
P3E_CPU1_PE3_MP_C_TXP<3> 
P3E_CPU1_PE3_MP_C_TXP<1> 
P3E_CPU1_PE3_MP_C_TXN<0> 
P3E_CPU1_PE3_MP_C_TXP<5> 
NIC_MDI_MNG_RX_DP 
NIC_MDI_MNG_RX_DN 
FM_MB_SLOT_ID0 
FM_MB_SLOT_ID1 
FM_MB_SLOT_ID2 
P3E_CPU1_PE3_MP_C_TXN<7> 
P3E_CPU1_PE3_MP_C_TXP<0> 
RST_PCIE_MIDPLANE_N 
P3E_CPU1_PE3_MP_C_TXP<6> 
P3E_CPU1_PE3_MP_C_TXN<4> 
P3E_CPU1_PE3_MP_C_TXN<1> FM_MATED_IN_N 
CLK_100M_AIRMAX8_PE1_DP 
SP2_BMC_CM_UART_TX_R1 
FAN_TACH3 
FM_MB_SLOT_ID0 
SPA_MID_DBG_RX 
FM_MB_SLOT_ID1 
FM_CTNR_PS_ON_R 
FAN_TACH2 
SP2_BMC_CM_UART_RX_R1 
SPA_MID_DBG_TX SPA_MID_DBG_TX_R 
SPA_MID_DBG_RX_R 
FM_ENABLE_FAN_POWER 
FAN_TACH0 
FAN_TACH1 
FAN_PWM_OUT_SYS0_R 
FAN_TACH2_R 
FAN_TACH1_R 
FAN_PWM_OUT_SYS0_R1 
FAN_TACH3_R 
P3E_CPU1_PE3_MP_RXN<7:0> 
P3E_CPU1_PE3_MP_TXN<7:0> 
P3E_CPU1_PE3_MP_RXP<7:0> 
3
6
7
0
4
5
0.22UF X7R 10% 
A36096-155 
0402 
2
16V 
1
C1F4 
1
10% 0402 0.22UF 
C1F2 2
X7R 16V 
A36096-155 
A36096-155 
2
0402 10% 0.22UF 
1
X7R 16V 
C1F13 
10% 0402 X7R 
1
0.22UF 
C1F6 2 A36096-155 
16V 
A36096-155 
0402 
2
16V 
1
0.22UF 10% X7R 
C1F10 
A36096-155 
0.22UF 16V 0402 10% X7R 
1
C1F20 
2
2
1
G21796-311 CHIP 
1
2.26K 
1/16W 0402 
2
G21796-311 CHIP 
0402 
2.26K 
G21796-311 CHIP 1.0% 2.26K 
1/16W 
2
R7D9 
0402 
1
16V X7R 0402 10% 
C1F16 
1
0.22UF 
A36096-155 2
A36096-155 
0402 10% X7R 
21
16V 
C1F15 
0.22UF 
0.22UF 10% 
C1F5 
A36096-155 
X7R 0402 16V 
1 2
0402 0.22UF 
A36096-155 
1 2
C1F3 
10% X7R 16V 
A36096-155 
2
16V X7R 
C1F12 
0.22UF 
1
0402 10% 
X7R 0.22UF 
A36096-155 
1
10% 
C1F11 
16V 
2
16V 0.22UF 10% 
A36096-155 C1F8 
1
X7R 
2
0402 
16V 
C1F18 
1
A36096-155 
0.22UF X7R 10% 
2
0402 
0.22UF 10% X7R 
1 2
C1F17 A36096-155 
16V 0402 
A36096-155 
16V 
1 2
0402 
C1F14 
10% X7R 
CHIP 
1/16W 
1% 
1
0402 
R9T6 
0402 CHIP 
1% 33.2 
R8E5 
1 2
1/16W 
8
10 
9
IC 
0
0
1
2
3
1
2
3
4
6
5
6
7
7
MMBT3904 1
IC 
SM 
3
2
A36096-049 
EMPTY 
C2R6 
2
1
470PF 
50V 
CR1F3 
H71799-001 
12
0402 
0.0 R9F67 5% 1/16W 
G21497-005 
CHIP 
0.0 
1R9R9 G21497-005 2
CHIP 0402 5% 1/16W 
0.0 
G21497-005 
5% 0402 
R9R10 21
CHIP 1/16W 
1/16W 0.0 
1 2
R9F70 
EMPTY 
G21497-005 
5% 
1/16W G21497-005 
R9F64 
CHIP 1
0402 
2
0.0 5% 
G21497-005 
0.0 
2
R9F63 
1EMPTY 
CHIP 
2
R9R12 
5% 
1
0402 
G21497-005 
1/16W 0.0 
G21497-005 1 2R9T1 
0402 1/16W 5% CHIP 0.0 
0.0 R1F8 1 2
G21497-005 
1/16W 5% CHIP 0402 
J1F1 
4 6
7
3
4
5
0
2
1
7
6
5
4
8
16V 
1
A36096-030 
2 X7R 
10% 
0.1UF 
2 1FM_MATED_IN_N 
SM 
CR1F4 
SDMK0340L 
H71799-001 
FM_MATED_IN_D1_N 
IC R9T8 
FAN_TACH0_R 
CLK_100M_AIRMAX8_PE1_DN 
2
0402 
G21497-005 
1
TP FAB4 DELETE 3PIN JUMPER J9W1 20170109 
TP FAB3-DVT DELETE 0OHM R9T8 20170103 
TP FAB1 POP 0OHM 1120 
TP FAB3-DVT ADD 3PIN JUMPER J9W1 20170103 
TP FAB4 ADD 0OHM R9T8 20170109 
TP FAB4 NOPOP J1F3 20170206 
138 159 181 247 199 
138 159 181 199 247 
181 199 
181 
157 120 144 190 
146 157 120 
199 
161 191 198 
181 119 164 
66 
141 
141 
181 199 
138 159 181 199 247 
138 159 247 
181 199 
196 241 248 
191 
141 
141 
181 119 164 
181 119 164 
181 119 164 
191 
181 
114 
158 
147 
181 119 164 
176 
158 
181 119 164 
161 147 
158 
158 176 
161 198 
161 147 
147 
161 
182 
182 
182 
182 
66 
66 
66 
181 
182 
114 
NOPOP 
SPA_MID_DBG_TX_R 
SPA_MID_DBG_RX_R 
NETS FROM AIRMAX B TO AIRMAX A FOR COMPATIBILITY 
WITH BULLDOG CREEK. WHEN USING WITH BULLDOG 
AND FAN_PWM_OUT_SYS0_R ARE USED FOR STEERING 
SERIES RESISTORS ON FAN_TACH3, FAN_TACH2, FAN_TACH1
CREEK, DEPOPULATE THESE RESISTORS. 
USE SHARED PADS FOR RESISTORS ON FOLLOWING NETS: 
DESIGN NOTE: 
CAD NOTE: 
CAD NOTE: 
CAD NOTE: 
TO CONNECTOR PIN 
PLACE 0.22UF TX CAPS CLOSE 
I8 
A5 
A4 
I3 
D5 
A6 
C3 
J2 
A2 
H1 
G1 
F1 
A7 
H8 
D8 
C8 
B8 
A8 
I7 
H7 
G7 
F7 
D7 
B5 
C5 
E5 
B6 
C6 
D6 
E6 
F6 
I6 
F5 
J6 
B7 
C7 
E7 
E8 
F8 
G8 
J8 
A1 
B1 
C1 
E1 
D1 
I1 
B2 
C2 
E2 
D2 
G2 
H2 
F2 
I2 
A3 
B3 
D3 
E3 
G3 
F3 
H3 
B4 
D4 
E4 
C4 
F4 
G4 
H4 
J4 
I4 
I5 
H5 
G5 
G6 
H6 
DO NOT SCALE DRAWING SHEET 
B
AA
B
B
SIZE 
SCALE: 
234
1234
DEPARTMENT CODE 
1
DOCUMENT NUMBER REV 
OUT 
IN 
IN 
P3V3_STBY 
OUT 
IN 
P12V_PSU 
OUT 
OUT 
IN 
OUT 
IN 
IN 
P3V3_STBY 
BI 
IN 
IN 
P12V_PSU 
IN 
OUT 
IN 
OUT 
OUT 
OUT 
IN 
OUT 
IN 
OUT 
IN IN 
IN 
BI 
OUT 
OUT 
OUT 
OUT 
OUT 
IN 
IN 
OUT 
BI 
OUT 
OUT 
OUT 
OUT 
P3V3_STBY 
OUT 
IN 
OUT 
BI 
BI 
IN 
181 OF 270 
Wed Feb 08 16:35:19 2017 
IO2 IO1 
IO3 
IO4 
IO5 
IO6 
IO7 
IO8 
NOPOP R9F63,R9F70 1123 
TP FAB1 POP R9F64 R9F67 
TP FAB1 CHANGE SYMBOL TO ZZ.82092.07601 0310 
ROOM: IO_SLOT 
BOM_COST:IO_SLOT 
NEXT TO VCC PIN OF 
CONFIG=H22707-001 
NEW_PN=20.82092.076 
PLACE 0.1UF CAP 
74LVC08A 
CONN8_H62179001 
AIRMAX 1X8 MID-PLANE CONNECTOR A 
WIWYNN CORPORATION 



MB_SLOT_ID1 
MB_SLOT_ID2 
PCIE_PERST# 
PMBUS_ALERT# 
PCIE_CLK_100M_DN 
J4 
PCIE_CLK_100M_DP 
GND14 
FAN_PWM0 
FAN_TACH1 
MATED_IN# 
FAN_TACH0 
FAN_TACH2 
FAN_TACH3 
MB_ON# 
COM_RX 
GND11 
COM_TX 
PCIE_RX_DN7 
GND4 
PCIE_RX_DP7 
PCIE_RX_DN6 
PCIE_RX_DP6 
J2 
PCIE_RX_DN5 
PCIE_RX_DN4 
PCIE_RX_DP5 
GND13 
GND7 
PCIE_RX_DP4 
PCIE_RX_DN3 
GND1 
PCIE_RX_DP3 
GND17 
PCIE_RX_DN2 
PCIE_RX_DP2 
GND10 
PCIE_RX_DP1 
PCIE_RX_DN1 
GND3 
PCIE_RX_DN0 
PCIE_RX_DP0 
J8 
PCIE_TX_DN2 
PCIE_TX_DP2 
GND16 
PCIE_TX_DN1 
GND9 
PCIE_TX_DP1 
PCIE_TX_DN0 
GND2 
PCIE_TX_DP0 
PCIE_TX_DN5 
GND18 
GND12 
PCIE_TX_DP5 
PCIE_TX_DN4 
GND6 
PCIE_TX_DP4 
PCIE_TX_DN3 
PCIE_TX_DP3 
PCIE_TX_DN7 
J6 
PCIE_TX_DP7 
GND15 
PCIE_TX_DN6 
GND8 
PCIE_TX_DP6 
PMBUS_CLK 
PMBUS_DATA 
MNG_RX_DP 
MNG_RX_DN 
GND5 
MNG_TX_DN 
MNG_TX_DP 
MB_SLOT_ID0 
Notice:20.82092.076 
SMB_PEHPCPU1_STBY_LVC3_SDA 
SMB_LAN_STBY_LVC3_SDA 
IRQ_BOARD_BMC_ALERT_N 
R1C11 
1/16W 0.0 
1
5% 
2 G21497-005 
EMPTY 0402 
14 
15 
13 
12 
12 
11 
9
8
9
8
0.22UF 
1 2
C9N2 
16V 0402 
A36096-155 
X7R 10% 
0.22UF 
1
16V X7R 10% 0402 
2
C9N12 A36096-155 0.22UF 
1 2
16V X7R 0402 10% 
C9N17 A36096-155 1
10% 0402 16V X7R 
A36096-155 2
0.22UF 
C9N18 
1 2
16V X7R 10% 
A36096-155 
0402 0.22UF 
C9N1 
1
16V 10% 
A36096-155 2
C9N15 
0402 X7R 0.22UF 
2
16V 0.22UF 
1
10% 
C9N6 
X7R 
A36096-155 
0402 
0.22UF 
1 2
X7R 10% 
A36096-155 
16V 0402 
C9N14 
1 2
C9N4 
0.22UF 16V X7R 
A36096-155 
10% 0402 
1 2
10% X7R 16V 
C9N5 0.22UF 
A36096-155 
1
0.22UF 16V X7R 10% 0402 
A36096-155 C9N16 2
16V 
21
0.22UF X7R 0402 
A36096-155 
10% 
C9N3 
1
C9N7 A36096-155 
0.22UF 
2
16V X7R 0402 10% 
A36096-155 
2
C9N10 
1
0.22UF 0402 10% 16V X7R 
0402 16V X7R 10% 
A36096-155 2
C9N9 
1
0.22UF 
0.22UF 0402 10% X7R 
2
C9N8 
1 A36096-155 
16V 
10 
R1C31 
1/16W 0.0 
1
5% 
2 G21497-005 
EMPTY 0402 
9
8
10 
9
8
13 
12 
11 
15 
14 
1/16W 
R1F9 
0.0 5% EMPTY 0402 
1 2 G21497-005 
13 
12 
11 
15 
14 
11 
DM-FCI-CONN76-8R-GP-U-01 
J1C1 
G21497-005 R1C9 
1/16W 0.0 
1
5% 
2
EMPTY 0402 
1/16W 
R1C10 
0.0 5% 
1 2 G21497-005 
EMPTY 0402 
P3E_CPU1_PE3_MP_TXN<15:8> 
P3E_CPU1_PE3_MP_RXN<15:8> 
P3E_CPU1_PE3_MP_RXP<15:8> 
P3E_CPU1_PE3_MP_TXP<15:8> 
SMB_LAN_STBY_LVC3_SCL 
FM_XRC_READY_N 
P3E_CPU1_PE3_MP_C_TXN<11> 
P3E_CPU1_PE3_MP_C_TXP<15> 
P3E_CPU1_PE3_MP_C_TXN<15> 
P3E_CPU1_PE3_MP_C_TXP<14> 
SMB_LAN_STBY_LVC3_SDA 
IRQ_BOARD_BMC_ALERT_N 
FM_BMC_READY_N 
FM_XRC_READY_N 
SMB_LAN_STBY_LVC3_SCL 
FAN_TACH2_R 
FAN_PWM_OUT_SYS0_R1 
FAN_TACH0_R 
FAN_TACH1_R 
FAN_TACH3_R 
P3E_CPU1_PE3_MP_C_TXN<9> 
P3E_CPU1_PE3_MP_C_TXP<8> 
P3E_CPU1_PE3_MP_C_TXN<8> 
P3E_CPU1_PE3_MP_C_TXP<13> 
P3E_CPU1_PE3_MP_C_TXN<13> 
P3E_CPU1_PE3_MP_C_TXN<12> 
P3E_CPU1_PE3_MP_C_TXN<14> 
TP_IOI4 
TP_IOG3 
TP_IOH3 
TP_FM_WAKE_N 
TP_IOH4 
TP_IOE4 
TP_IOF4 
FM_BB_BMC_MP_GPIO 
P3E_CPU1_PE3_MP_C_TXN<10> 
P3E_CPU1_PE3_MP_C_TXP<9> 
P3E_CPU1_PE3_MP_C_TXP<12> 
P3E_CPU1_PE3_MP_C_TXP<11> 
SMB_PEHPCPU1_STBY_LVC3_SCL 
FM_XRC_PRESENT_N 
TP_IOA5 
15 
14 
13 
10 
10 
0402 
P3E_CPU1_PE3_MP_C_TXP<10> 
145 163 
138 156 160 182 
120 133 145 182 66 
66 
66 
66 
138 160 156 182 
133 182 119 147 
138 156 160 
182 
120 133 145 
182 
120 133 146 
119 
133 182 119 
147 
138 160 156 
182 
181 
181 
181 
181 
181 
119 147 
145 163 
133 119 147 
DESIGN NOTE: 
A5 
B5 
A6 
C2 
F5 
C5 
E5 
D5 
B6 
C6 
E6 
D6 
F6 
G6 
H6 
J6 
I6 
B7 
D7 
C7 
E7 
G7 
F7 
I7 
H7 
B8 
A8 
C8 
E8 
D8 
F8 
H8 
I8 
J8 
A1 
B1 
C1 
E1 
D1 
F1 
G1 
H1 
I1 
B2 
A2 
E2 
D2 
G2 
H2 
F2 
I2 
J2 
A3 
B3 
D3 
C3 
E3 
G3 
F3 
H3 
I3 
A4 
B4 
D4 
E4 
C4 
F4 
G4 
H4 
J4 
I4 
I5 
H5 
G5 
A7 
G8 
DO NOT SCALE DRAWING SHEET 
B
AA
B
B
SIZE 
SCALE: 
234
1234
DEPARTMENT CODE 
1
DOCUMENT NUMBER REV 
IN 
IN 
IN 
BI 
IN 
OUT 
OUT 
BI 
IN 
IN 
BI 
IN 
IN 
OUT 
BI 
OUT 
OUT 
IN 
OUT 
OUT 
OUT 
OUT 
182 OF 270 
Wed Feb 08 16:35:19 2017 
PLACE CAPS NEAR MID-PLANE CONNECTOR 
ROOM: IO_SLOT 
CAD NOTE: 
TP FAB1 CHANGE SYMBOL TO ZZ.82092.07601 0310 
FROM AIRMAX B TO AIRMAX A FOR BULLDOG 
THESE RESISTORS 
CREEK COMPATABILITY 
THESE RESISTORS USED TO STEER SIGNALS 
WHEN USING WITH BULLDOG CREEK, POPULATE 
NEW_PN=20.82092.076 
CONFIG=H22707-001 
AIRMAX 1X8 MID-PLANE CONNECTOR B 
WIWYNN CORPORATION 



FM_UART_ALERT_N 
G21796-072 
1
R9F55 
4.75K 
0402 
CHIP 
1/16W 
1% 
2
190 119 
DO NOT SCALE DRAWING SHEET 
B
AA
B
B
SIZE 
SCALE: 
234
1234
DEPARTMENT CODE 
1
DOCUMENT NUMBER REV 
P3V3_STBY 
OUT 
183 OF 270 
Wed Feb 08 16:35:19 2017 
LEAVE PU RES FOR  GPIO 
TP FAB1 DELETE PI7C9X1172 AND RELATED COMPONENT (NO USE IE) 0118 
I2C/SPI TO UART BRIDGE CONTROLLER 
WIWYNN CORPORATION 



RM8D1 
SPI_PCH_TPM_CLK_R 
SPI_PCH_TPM_MISO_R 
IRQ_SPI_TPM_N_R 
SPI_PCH_TPM_CS_N 
SPI_PCH_CLK 
SPI_PCH_MOSI 
SPI_PCH_MISO 
SPI_PCH_TPM_MOSI_R 
SPI_PCH_TPM_CS_R_N 
RST_PLTRST_BUF_N 
SMB_SENSOR_STBY_LVC3_SDA 
IRQ_PIRQA_SPI_TPM_N 
SMB_SENSOR_STBY_LVC3_SCL 
CHIP G21497-005 0.0 0402 
1
1/16W 5% 
2
R8E1 
R8E10 
1% 
2
CHIP 
1/16W 33.2 G21796-074 
1
0402 
33.2 1% 
2
R8E13 
1
1/16W G21796-074 CHIP 0402 
1
0.0 5% 1/16W G21497-005 R8D35 
2
CHIP 0402 
R8E9 
2
1% 
G21796-074 
1
CHIP 1/16W 0402 33.2 
CONN 
MP2 
MP1 
11 
10 
9
8
7
6
5
4
3
2
1
H67026-001 
J8E1 
1
SO 
H72821-001 
121 
121 154 
111 121 125 154 
154 121 
146 191 134 145 
164 167 191 
119 157 
249 
133 119 
167 164 191 
SCONN11_H67026001 
FM_TPM_PRES_RST_N 
CAD NOTE: 
DO NOT SCALE DRAWING 
IO1 
SHEET 
B
AA
B
B
SIZE 
SCALE: 
234
1234
DEPARTMENT CODE 
1
DOCUMENT NUMBER REV 
OUT 
P3V3_STBY 
IN 
OUT 
IN 
IN 
IN 
IN 
BI 
BI 
184 OF 270 
IO7 
IO8 
IO5 
IO6 
IO4 
IO3 
IO2 
IO1 MP1 
IO9 
IO10 
IO11 
MP2 
STANDOFF 
BOM_COST=MIO_SECURITY 
ROOM=TPM 
TP FAB1 FOR BMC TPM 1120 
PLACE R8E13 NEAR TPM CONN 
PLACE R8E10 NEAR TPM CONN 
PLACE R8E9 WITHIN 200 MILS OF SPI_PCH_CLK T-POINT AND WITH 500 MILS OF TPM CONN 
SPI TPM CONNECTOR Wed Feb 08 16:35:19 2017 
WIWYNN CORPORATION 



ANODE 
CATHODE 
REF 
EN 
SDAB 
SCLB 
VCCB 
GND 
SDAA 
SCLA 
VCCA 
EN 
SDAB 
SCLB 
VCCB 
GND 
SDAA 
SCLA 
VCCA 
P3E_PCH_M2_TX_C_DN<3> 
A36096-155 
10% 
SATA6G_S0_RX_DP 
P3E_PCH_RX_0_DP 
5% 
SATA6G_S0_RX_DN 
0402 
CHIP 
1 10.0K 
R32W9 
TCA9517DGKR-GP 
U32W1 
SMB_M2_ALT_R_N 
1% 
SMB_OCP_LAN_STBY_LVC3_SCL 
SMB_OCP_LAN_STBY_LVC3_SDA 
1/16W 
C32W2 
PD_SMB_M2_EN 
0.1UF 
0402V 
10% 
X7R 
0402 
5% 0.0 
C88419-001 
VCC=P3V3_STBY;GND=GND 
1/16W 
1% 
49.9K 
0402 
G21796-048 
CHIP R32W4 
A36096-030 
SMB_M2_SCL_R 
R32W11 R32W10 
G21796-016 
CHIP 
R32W7 
P3E_PCH_TX_0_DP 
0.1UF 1
G21796-001 
SMB_M2_ALT_N 
1 R32W1 
4.02K G21796-082 
0402 
4
1/16W 
1% 
C2P9 
A36096-030 
16V 
1/16W 
G21497-005 0402 215% 
0.0 1R8F18 
C8F12 10% 21
0.22UF C8F7 2
P3E_PCH_M2_SATA6G_TX_R_DN 
P3E_PCH_M2_SATA6G_TX_R_DP 
SATA6G_S0_TX_DN 
P3E_PCH_TX_0_DN 
0402 
1/16W 
1% 
1
R8F36 
10.0K 
J8F1 
SKT-MINI67P-41-GP 
A36096-030 
X7R 
10% 
2
0402V 
1
16V 
0.1UF 
C32W4 
2
2
1
10% 
C32W3 
0.1UF 
16V 
1
2 X7R 
0402 
10% 
2 X7R 
0402V 
1 2
0402 
1/16W 
5% 
0.0 
C2T23 0.22UF 10% 1 2 X7R 16V 0402 A36096-155 
0.22UF C2T20 0402 16V X7R 2110% A36096-155 
10.22UF A36096-155 0402 X7R 210% C2T13 
0.22UF 10% 1 2 X7R 16V C2T14 0402 
110% 2 X7R 16V 0402 C2T11 0.22UF 
10% 0.22UF 16V A36096-155 0402 X7R 21
NC_M2<0> 
NC_M2<1> 
TP_LED_M2_ACT_N 
PU_M2_CLK_REQ_N 
TP_M2_32M_SUSCLK 
FM_PE_M2_WAKE_N 
SMB_M2_SDA_R 
P3E_PCH_M2_RX_DP<2> 
P3E_PCH_M2_RX_DP<1> 
P3E_PCH_M2_RX_DN<1> 
P3E_PCH_M2_TX_DN<3> 
P3E_PCH_M2_TX_C_DP<3> 
P3E_PCH_M2_RX_DP<3> 
P3E_PCH_M2_TX_DP<2> 
P3E_PCH_M2_TX_DN<2> P3E_PCH_M2_TX_C_DN<2> 
P3E_PCH_M2_SATA6G_TX_R_DN 
P3E_PCH_M2_SATA6G_TX_R_DP 
CLK_100M_M2_DP 
2
CHIP 
P3E_PCH_M2_SATA6G_RX_R_DN 
P3E_PCH_M2_SATA6G_RX_R_DP 
C2T10 
A36096-030 
C2T29 
0.1UF 
10% 
0402V 
16V 
X7R 2
1
A36096-030 
C2T2 
X7R 2
1
16V 
0402V 
10% 
0.1UF 
C2T4 
X7R 2
1
16V 
0402V 
10% 
A36096-030 
2 X7R 
16V 
0.1UF 1C2T16 
16V 
0.1UF 
10% 
1
2
C2T15 
A36096-030 
0.1UF 
10% 
0402V 
16V 
X7R 
1
2
A36096-030 
C2T24 
0.1UF 
10% 
16V 
1
X7R 2X7R 
C2T21 
16V 
0402V 
10% 
0.1UF 
2
1
A36096-030 A36096-030 
10% 
0402V 
16V 
X7R 
1
2
C2T26 
0.1UF 
C2T5 
10% 
A36096-030 
0402V 
U2P1 
IC 0402 
CHIP 2
10.0K 1
R2P16 
2
CHIP 
1
R2P14 
G21497-005 
FM_SSATA_PCIE_M2_SEL 
74LVC1G07 
2
1/16W 
R2P15 
G21796-016 
0402 
CHIP 
1
2
1% 
10.0K 
X7R 0.22UF 
P3E_PCH_M2_TX_DN<1> 
P3E_PCH_M2_TX_DP<1> 
FM_M2_SSD_PEDET 
CHIP 
1% 
2 1/16W 
R32W2 
2
1% 
1/16W 
CHIP 1
0402 
1.5K G21796-003 
G21796-001 
2.0K 
0402 
R32W5 
1/16W 
1% 
2.0K 
1% 
1/16W 
CHIP 
0402 
1% 
SMB_M2_SCL 
SMB_M2_SDA 
16V 
IRQ_MEZZ_LAN_ALERT_N 
U32W2 
0402V 
TCA9517DGKR-GP 
G21497-005 
CHIP 
5% 
0402V 
G21497-005 
1/16W 
2
A36096-030 
X7R 
0402V 
SMB_M2_ALT_N 
0.0 
1
R32W12 
1
CHIP 
5% 
1/16W 
G21497-005 
SMB_M2_SCL 
SMB_M2_SDA 
P3E_PCH_M2_RX_DN<3> 
0.1UF 
A36096-030 
P3E_PCH_M2_RX_DN<2> 
A36096-155 
16V 
P3E_PCH_M2_TX_C_DN<1> 
P3E_PCH_M2_TX_C_DP<1> 
RST_PCIE_M2_DEV_IC_N 
TP_M2_DEVSLP 
G21796-016 
A36096-155 
A36096-155 
1/16W P3E_PCH_RX_0_DN R8F21 0.0 
CHIP 
0402 
1
0.0 
10% 
X7R 2
FM_M2_DET_LVC3 
0402V 
R32W6 
2.0K 
1/16W 
CHIP 
G21796-001 
0402 
10% 
16V 
1.0UF 
X6S 
0402 
C32W5 
D97712-011 
A36096-030 
2
16V 
0.1UF 
C32W1 
P3E_PCH_M2_TX_C_DP<2> 
P3E_PCH_M2_TX_DP<3> 
CLK_100M_M2_DN 
0402 1
SATA6G_S0_TX_DP 
16V 
X7R 16V 
0402 
CHIP 
G21497-005 
P3E_PCH_M2_SATA6G_RX_R_DP 
2 CHIP 
P3E_PCH_M2_SATA6G_RX_R_DN 
0402 1/16W 
POP_M2_SATA 
POP_M2_PCIE 
POP_M2_PCIE 
POP_M2_SATA 
POP_M2_PCIE 
POP_M2_SATA 
POP_M2_PCIE 
TP FAB3 ADD M2 I2C CIRCUIT 0831 
TP FAB1 DEL NETS 0309 
POP_M2_SATA 
116 
116 
116 
159 186 
159 186 
116 
185 
185 
116 
116 
142 
116 
116 
116 
116 
116 
116 
116 
185 
185 
114 
185 
185 
120 
116 
116 
157 186 119
145 
116 
116 
248 
116 
116 
114 
116 
185 
185 
GROUP=M2_SATA 
A36096-045 
X7R 
GROUP=M2_PCIE 
GROUP=M2_SATA 
GROUP=M2_PCIE 
GROUP=M2_SATA 
GROUP=M2_PCIE 
0402V 
GROUP=M2_PCIE 
C8F13 
A36096-045 C8F15 
25V 
NOPOP 
NOPOP NOPOP 
SMB_M2_SDA 
SMB_M2_ALT_N 
C8F6 
X7R 10% 25V 
X7R 
10% 0.01UF 
C8F11 
25V 
CHIP 
SMB_M2_SCL 
0.01UF 
VREF_LMV431_1V42 
G21497-013 
5% 
R32W3 
3.3K 
0402 
1/16W 
X7R 0402V 0.01UF 10% 25V 
A36096-045 
GROUP=M2_SATA 
A36096-045 
0402V 
0.01UF 10% 0402V 
185 
185 
185 
185 
185 
185 
185 
185 
185 
185 
185 
185 
185 
G21796-016 
VR32W1 
LMV431AIMFX-GP 
74.MV431.031 
DESIGN NOTE: 
CAD NOTE: CAD NOTE: CAD NOTE: 
CAD NOTE: 
2
2
46 
44 
42 
40 
30 
36 
48 
14 
3
1
21
1
1 2
41 
35 
21 
19 
15 
13 
16 
20 
18 
8
10 
51 
9
38 
26 
28 
39 
55 
12 
5
1
69 
74 
23 
25 
27 
29 
37 
77 
75 
73 
71 
67 
49 
57 
NP1 
76 
70 
68 
58 
56 
54 
52 
50 
6
4
2
47 
45 
43 
17 
11 
7
53 
NP2 
72 
31 
33 
4
6
7
5
81
3
2
81
4
2
1
2
1
2
1
5
6
7
3
3
24 
22 
34 
32 
1
2
1
2
1
2
1
2
2
DO NOT SCALE DRAWING SHEET 
B
AA
B
B
SIZE 
SCALE: 
234
1234
DEPARTMENT CODE 
1
DOCUMENT NUMBER REV 
IN 
IN 
OUT 
OUT 
P3V3 
P3V3_STBY 
OUT 
IN 
BI 
P3V3_STBY 
OUT 
OUT 
IN 
IN 
OUT 
OUT 
IN 
IN 
OUT 
OUT 
IN 
IN 
OUT 
OUT 
IN 
IN 
IN 
IN 
OUT 
IN 
P3V3 
P3V3 
P3V3 
P3V3 P3V3 P3V3 
P3V3_STBY 
OUT 
P3V3_STBY 
P3V3 
OUT 
OUT 
OUT 
OUT 
IN 
IN 
IN 
IN 
TTL1G07_A 
185 OF 270 
Wed Feb 08 16:35:20 2017 
M.2 PCIE POP: C8F7, C8F12, R8F18 AND R8F21 ROOM=M_2 
TP FAB1 CHANGE RESET SIGNAL FROM RESET IC 1204 
0 M.2 SATA SSD 
BOM_COST=ST_FLASH 
1 M.2 PCIE SSD 
TP FAB3 ADD M2 I2C CIRCUIT 0831 
TP FAB1 CHANGE CONN PN TO 062.10003.0B21 
TP FAB1 DEL NET 0309 
M.2 SATA POP: C8F6, C8F11, C8F13 AND C8F15 
TP FAB3 ADD M2 I2C CIRCUIT 0831 
P1V8_M2 
P1V8_M2 
P1V8_M2 
PLACE CLOSE TO PINS 12,14,16,18 PLACE CLOSE TO PINS 2&4 PLACE CLOSE TO PINS 70,72,74 
P1V8_M2 
74LVC1G07 POWER PIN 
PLACE CAP NEAR 
M.2 CONNECTOR 
PCH M.2 CONNECTOR 
WIWYNN CORPORATION 



106 
98 
96 
94 
116 
118 117 
RMII_BMC_OCP_TXEN 
0.1UF 
J9B3 
37 
0.1UF 
RMII_BMC_OCP_CRSDV_R 
R9W1 
C9B9 
C9B10 
X7R 
A36096-030 
0402V 
2
10% 
16V 
2 C95333-007 
0805 
1
887R2F-L-GP 
R1M15 
SMB_OCP_LAN_STBY_LVC3_SDA 
2
2 X7R 
A36096-030 
1
16V 
0402V 
10% 
C1M24 
0402 1% 
CHIP 1/16W 
200.0 
G21796-004 
1
R1M14 
2
X7R 
A36096-030 
0402V 
C1M20 
16V 
10% 
0.1UF 
12 
11 
10 
X6S 
16V 
10% 
10UF 
1 C1M27 
8
14 
15 
15 
13 
12 
14 
13 
11 
10 
9
9
8
12 
13 
14 
15 
15 
14 
13 
11 
11 
12 
10 
9
9
10 
8
8
0402V 
D97712-004 
C1M21 1
2 X6S 
6.3V 
10% 
1.0UF 
0402V 
D97712-004 2
1
X6S 
6.3V 
10% 
1.0UF 
C1M25 
33 
76 
83 
8
27 
23 
25 
15 
54 53 
82 
120 
61 62 
A28699-018 
SCONN 
1
3
2
4
5 6
7
9 10 
11 12 
13 14 
16 
17 18 
19 20 
21 22 
24 
26 
28 
29 30 
31 32 
34 
35 36 
38 
39 40 
41 42 
43 44 
45 46 
47 48 
49 50 
51 52 
55 56 
57 58 
59 60 
63 64 
65 66 
67 68 
69 70 
71 72 
73 74 
75 
77 78 
79 
81 
85 86 
87 
89 90 
91 
93 
95 
97 
99 100 
103 
105 
107 
109 110 
111 112 
113 114 
115 
119 
101 
80 
84 
88 
92 
102 
104 
108 
0402 CHIP 1/16W 
0.0 
R1M16 
2
5% G21497-005 
10402 CHIP 1/16W 
R1M17 
2
0.0 
G21497-005 1
5% 
0402 
CHIP 1/16W 
1
5% 0.0 
G21497-005 
1/16W CHIP 0402 0.0 5% G21497-005 
21
R1M18 
0.1UF 10UF 
C1M26 
2
1
X6S 
0805 
C95333-007 
10% 
16V 
10% 
A36096-030 
X7R 2
C1M23 
0.1UF 
1
16V 
0402V 
2
1
X7R 
16V 
10% 
C1M22 
A36096-030 
0402V 
P3E_CPU0_PE3_OCP_RXP<15:8> 
P3E_CPU0_PE3_OCP_RXN<15:8> P3E_OCP_CPU0_PE3_C_TXP<15:8> 
P3E_OCP_CPU0_PE3_C_TXN<15:8> 
RMII_BMC_OCP_TXD0 
RMII_BMC_OCP_TXD1 
CLK_100M_MEZZ1_DP 
CLK_100M_MEZZ1_DN 
RMII_BMC_OCP_RXER_R 
CLK_100M_MEZZ2_DN 
RMII_BMC_OCP_CRSDV IRQ_MEZZ_LAN_ALERT_N 
SMB_OCP_FRU_STBY_LVC3_SCL 
SMB_OCP_FRU_STBY_LVC3_SDA 
FM_PE_OCP_WAKE_N 
FM_OCP_MEZZA_PRES_N 
SMB_OCP_LAN_STBY_LVC3_SCL RMII_BMC_OCP_RXER 
CLK_50M_CKMNG_OCP 
RST_PCIE_CPU_DEV0_R_N RST_PCIE_CPU_DEV0_N 
RMII_BMC_OCP_RXD0 
RMII_BMC_OCP_RXD1 
RMII_BMC_OCP_RXD0_R 
RMII_BMC_OCP_RXD1_R 
CLK_100M_MEZZ2_DP 
10.0K 
1% 
1/16W 
CHIP 
0402 
R9B7 
FM_MEZZA_PRSNT1_N 
147 150 
159 185 
32 
32 106 
106 
147 
147 
114 
114 
114 
147 157 185 119 145 
138 159 91 188 
91 138 159 188 
142 
250 
159 185 147 
101 
191 
147 
147 
114 
GROUP=NO_KR 
0402 
1UF 
10% 
10V 
887OHM 
1% 
1/16W 
0402 
SC1U10V2KX-4-GP 
G21796-016 CAD NOTE: 
DESIGN NOTE: 
TP FAB1 CHANGE PN 0310 
2
1
2
1
DO NOT SCALE DRAWING SHEET 
B
AA
B
B
SIZE 
SCALE: 
234
1234
DEPARTMENT CODE 
1
DOCUMENT NUMBER REV 
OUT 
P3V3_STBY 
P5V_STBY 
OUT 
OUT 
OUT 
OUT 
IN 
IN 
OUT 
OUT 
P3V3_STBY 
P12V_STBY P12V_STBY 
P5V_STBY 
P3V3_STBY 
P3V3_STBY 
P3V3 
IN 
IN 
IN 
IN 
OUT 
OUT 
IN 
BI 
P3V3 
IN 
IN 
IN 
IN 
IN 
IN 
BI 
P3V3 
1 2
1 2
186 OF 270 
Wed Feb 08 16:35:20 2017 
IO101 
IO103 
IO105 
IO107 
IO109 
IO111 
IO113 
IO115 
IO117 
IO119 
IO7 
IO9 
IO11 
IO15 
IO17 
IO19 
IO13 
IO21 
IO27 
IO29 
IO25 IO23 
IO31 
IO33 
IO35 
IO37 
IO39 
IO41 
IO47 
IO49 
IO45 IO43 
IO51 
IO53 
IO55 
IO57 
IO59 
IO61 
IO69 
IO71 
IO67 IO65 IO63 
IO73 
IO75 
IO77 
IO79 
IO81 
IO83 
IO87 
IO89 
IO91 
IO85 
IO93 
IO95 
IO97 
IO99 
IO2 
IO4 
IO6 
IO8 IO10 
IO12 
IO14 
IO16 
IO18 
IO20 
IO22 
IO28 
IO30 
IO26 IO24 
IO32 
IO34 
IO36 
IO38 
IO40 
IO42 
IO48 
IO50 
IO46 IO44 
IO52 
IO54 
IO56 
IO58 
IO60 
IO62 
IO70 
IO72 
IO68 IO66 IO64 
IO74 
IO76 
IO78 
IO80 
IO82 
IO84 
IO96 
IO98 
IO94 
IO86 
IO88 
IO90 
IO92 
IO100 
IO102 
IO104 
IO106 
IO108 
IO110 
IO112 
IO114 
IO116 
IO118 
IO120 
IO5 
IO1 
IO3 
FCI PLUG # ON OCP MEZZ 
TP FAB1  ADD R9W1  10K OHM AND CHANGE R9B7 TO 887 OHM1210 
61082-081402LF 
CONN 
E67482-008 B (80P) 
FCI RECPT IPN ON CC 
(5/8MM STACK) 
61082-121402LF 
61082-081402LF 
FCI RECPT # ON CC 
10135583-642402LF 
MATED HT CONNECTOR P/NS 
H87568-002 
E67482-006 
FCI RECPT IPN ON CC FCI RECPT # ON CC 
(12MM STACK) 
61082-122402LF 
TO CPU0 
C (64P) 
61083-124402LF 
(8/12 MM STACK) 
FCI PLUG # ON OCP MEZZ 
61082-082402LF 
10135584-644402LF 
A28699-010 A28699-020 
(12 MM STACK) 
10135583-641402LF 10135584-641402LF 
A (120P) 
(5/8MM STACK) 
FROM CPU0 
0.26V~0.27V 
H87568-001 
61083-084402LF 
61083-121402LF 
(5MM STACK) 
NETS WITHIN 2 INCHES OF THE OCP CONNECTOR: 
13MM HT CONNECTOR IN SCHEMATIC 
PLACE SERIES RESISTORS ON THE FOLLOWING 
12MM HT CONNECTOR IN BOM 
RMII_BMC_OCP_RXD1_R 
RMII_BMC_OCP_RXER_R 
RMII_BMC_OCP_RXD0_R 
RMII_BMC_OCP_CRSDV_R 
OCP MODULE CONN A 
SCONN120_A28699018 
WIWYNN CORPORATION ROOM=IO_SLOT 



RST_PCIE_CPU_DEV1_R_N 
61 
R2R8 
887R2F-L-GP 
P3E_CPU0_PE3_OCP_RXP<7:0> 
P3E_CPU0_PE3_OCP_RXN<7:0> 
CLK_100M_MEZZ3_DN 
FM_MEZZB_PRSNT1_N 
CLK_100M_MEZZ4_DP 
CLK_100M_MEZZ4_DN 
FM_OCP_MEZZB_PRES_N 
RST_PCIE_CPU_DEV1_N 
RST_PCIE_CPU_DEV2_N 
CLK_100M_MEZZ3_DP 
TP_RSVD_B1 
RST_PCIE_CPU_DEV3_R_N 
RST_PCIE_CPU_DEV2_R_N 
RST_PCIE_CPU_DEV3_N 
P3E_OCP_CPU0_PE3_C_TXP<7:0> 
P3E_OCP_CPU0_PE3_C_TXN<7:0> 
4
5
6
7
4
5
6
7
3
3
7
7
CHIP 
0402 
1/16W 
R2W1 
10.0K 
1% 
0
3
2
1
0
2
1
3
R9E12 
200.0 
1/16W 
21
0402 G21796-004 
1% 
CHIP 
R9E11 
G21796-004 
200.0 1% 0402 
CHIP 1/16W 
21
0
0
1
R9E10 
G21796-004 
200.0 1% 0402 
CHIP 1/16W 
21
2
2
1
E67482-007 
56 
58 
45 
57 
80 
32 
41 
28 
J8E3 
CONN 
79 
78 77 
76 75 
74 73 
72 71 
70 69 
68 67 
66 65 
64 63 
62 
60 59 
55 
54 53 
52 51 
50 49 
48 47 
46 
44 43 
42 
40 39 
38 37 
36 35 
34 
31 
30 29 
27 
26 25 
24 23 
22 21 
20 19 
18 17 
16 15 
14 13 
12 11 
10 9
8 7
6 5
4 3
2 1
33 
6
6
5
5
4
4
32 
32 
114 
114 
114 
250 
190 
190 
114 
190 
106 
106 
GROUP=NO_KR 
0402 
887OHM 
1% 
1/16W 
G21796-016 
DESIGN NOTE: 
DESIGN NOTE: 
2
1
DO NOT SCALE DRAWING SHEET 
B
AA
B
B
SIZE 
SCALE: 
234
1234
DEPARTMENT CODE 
1
DOCUMENT NUMBER REV 
IN 
P12V_STBY 
OUT 
OUT 
P3V3_STBY 
OUT 
IN 
IN 
IN 
IN 
IN 
IN 
IN 
IN 
2 1
187 OF 270 
Wed Feb 08 16:35:20 2017 
SCONN80_E67482007 
IO79 
IO63 
IO65 
IO67 
IO69 IO71 
IO75 IO73 
IO77 
IO61 IO59 
IO43 
IO45 
IO47 
IO49 IO51 
IO55 IO53 
IO57 
IO41 
IO39 
IO21 IO19 
IO27 
IO23 
IO25 
IO29 
IO35 IO33 IO31 
IO37 
IO13 
IO15 
IO1 IO3 
IO5 
IO7 
IO11 
IO17 
IO9 
IO78 
IO80 
IO76 
IO72 
IO74 
IO68 
IO70 
IO66 
IO62 
IO64 
IO60 IO58 IO56 
IO52 
IO54 
IO50 IO48 IO46 
IO42 
IO44 
IO40 
IO36 
IO38 
IO32 IO30 
IO34 
IO28 IO26 
IO20 
IO24 IO22 
IO18 IO16 
IO14 
IO10 
IO12 
IO8 IO6 IO4 IO2 
FCI PLUG # ON OCP MEZZ 
A28699-020 TP FAB1  ADD R2W1 10K OHM AND CHANGE R2B8 TO 887 OHM1210 
10135584-644402LF 
0.26V~0.27V 
B (80P) 
(5/8MM STACK) 
A (120P) 
MATED HT CONNECTOR P/NS 
FROM CPU0 
CONN 
(8/12 MM STACK) 
FCI PLUG # ON OCP MEZZ 
61083-124402LF 
61082-081402LF 
(5/8MM STACK) 
E67482-006 
A28699-010 
FCI RECPT IPN ON CC FCI RECPT # ON CC 
10135583-641402LF 
(12MM STACK) 
61082-122402LF 
FCI RECPT # ON CC 
61082-082402LF 
10135583-642402LF H87568-002 
(12 MM STACK) 
FCI RECPT IPN ON CC 
E67482-008 
TP FAB1 RENAME 1218 
TP FAB1 RENAME 1218 61083-121402LF 61082-121402LF 
TO CPU0 
10135584-641402LF 
61082-081402LF 
H87568-001 
61083-084402LF 
C (64P) 
(5MM STACK) 
13MM HT CONNECTOR IN SCHEMATIC 
12MM HT CONNECTOR IN BOM 
TO ELIMINATE ROUTING CROSSOVER. 
SWAPPED 15:8 WITH 7:0 ON 120-PIN CONNECTOR 
OCP MODULE CONN B 
WIWYNN CORPORATION 



TP FAB1 DELETE CONNECTION TO PCH 1230 
LED_GBE_P0_1 
KR_P0_OCP_TX_DP 
SMB_PCH_MEZZ_LOM3_SDA 
1/16W 
LED_GBE_P3_1 
LED_GBE_P3_0 
KR_P1_OCP_RX_DP 
KR_P1_OCP_RX_DN 
SMB_PCH_MEZZ_LOM2_SCL 
FM_OCP_MEZZC_PRES_N 
KR_P0_OCP_RX_DP 
0.1UF 
10% X7R 
FM_GBE2_LVC3_MOD_ABS CHIP 
FM_GBE1_LVC3_MOD_ABS G21796-072 
G21796-072 FM_GBE0_LVC3_MOD_ABS 
G21796-072 
1/16W 
G21796-072 CHIP EXT_MDIO_I2C_SEL 
CHIP 
1/16W 
FM_GBE3_LVC3_MOD_ABS 
G21796-072 
G21796-112 
SMB_PCH_MEZZ_LOM0_SDA 
CHIP 1/16W 1% 
SMB_PCH_MEZZ_LOM3_SDA 
SMB_PCH_MEZZ_LOM3_SCL 
30 
4.75K 
2.21K R1R22 
2
2
2.21K R1R17 
2
2.21K R1R16 
2
2
R1R21 2.21K 
2
R1R20 2.21K 
2.21K R1R19 
2
2.21K R1R18 
2
SMB_PCH_MEZZ_LOM2_SCL 
SMB_PCH_MEZZ_LOM1_SDA 
SMB_PCH_MEZZ_LOM0_SCL 
1/16W CHIP 
1
1/16W 0402 G21796-112 
1
1/16W CHIP 1% 0402 G21796-112 
1
CHIP 1/16W 1% 0402 
1
G21796-112 
1
G21796-112 1% CHIP 
1
G21796-112 1% CHIP 
1% 0402 1/16W CHIP 
1
0402 1% 1/16W CHIP 
1
A36096-030 A36096-030 
X7R 
16V 
10.1UF 
C2P16 C2R16 
0.1UF 
10% 
2 A36096-030 
PLACE NEAR THE IO SLOT. 
X7R 
C2P10 
0402V 
10% X7R 
0402V 
A36096-030 
2
16V 0.1UF 
A36096-030 
KR_P1_OCP_RX_DN 21
0.1UF 
10% 
C8C13 
0402V 
X7R 
16V 
C8C12 
1
2 A36096-030 
X7R 
10% 
16V 
0.1UF 
C2R15 
0402V 
1
2
1
16V 
0.1UF 
C2P11 
10% 
0402V 
A36096-030 
X7R 2
1 C2P12 
16V 
10% 
X7R 
A36096-030 
0402V 
0.1UF 
2
1
0402V 
X7R 
10% 
16V 
0.1UF 
C2R17 
A36096-030 2
1 0.1UF 
16V 
10% 
0402V 
A36096-030 
1
16V 
10% 
X7R 
0402V 
2 A36096-030 2
22UF 
10% 
D38464-005 
1206LF 
2
1
16V 
10% 
0402V 
A36096-030 2
1 C2P15 
0.1UF 
16V 
10% 
1 C2P14 
2
10% 
16V 
1
X7R 
0402V 
C8C15 
0402V 16V 
21
16V 
X7R 
1 2
0402V 
10% 
0.1UF 
A36096-030 
C8C14 
KR_P1_OCP_RX_C_DN 
KR_P1_OCP_RX_DP 
KR_P0_OCP_RX_C_DN 
KR_P1_OCP_RX_C_DP 
X7R 
C2R18 
X6S 
C2P13 
0.1UF 
X7R 
0402V 
16V 
0.1UF 
2
4.75K R1W40 
1
1
R1W41 
1/16W 
2.21K R1R23 
1% 
2
1
1% 
R1W43 
21
4.75K 
21
R1W44 
4.75K 1% 
21
R1W45 CHIP 
CHIP 
1% 
4.75K 1/16W 
1% 
SMB_PCH_MEZZ_LOM3_SCL 
0402 
0402 
0402 
1% 0402 
4.75K 
KR_P0_OCP_RX_C_DP 
A36096-030 
KR_P0_OCP_RX_DN 
FM_GBE2_LVC3_MOD_ABS 
SMB_OCP_FRU_STBY_LVC3_SDA 
EXT_MDIO_I2C_SEL 
SMB_OCP_FRU_STBY_LVC3_SCL 
LED_GBE_P2_1 
SMB_PCH_MEZZ_LOM0_SCL 
SMB_PCH_MEZZ_LOM1_SCL 
SMB_PCH_MEZZ_LOM1_SDA 
FM_GBE3_LVC3_MOD_ABS 
TP_RSVD<0> 
FM_GBE0_LVC3_MOD_ABS 
FM_GBE1_LVC3_MOD_ABS 
KR_P0_OCP_TX_DN 
LED_GBE_P0_0 
KR_P1_OCP_TX_DP 
KR_P1_OCP_TX_DN 
KR_P0_OCP_RX_DP 
KR_P0_OCP_RX_DN 
LED_GBE_P1_0 
LED_GBE_P1_1 
CONN 
44 
43 
51 
33 
34 
35 
59 
22 
55 23 
19 
60 
45 
54 
7
11 
20 
62 
61 
58 
56 
52 
42 
32 
31 
29 
25 
21 
12 
10 
9
8
5
64 
49 
37 
36 
38 
39 
41 
63 
46 
47 
28 
4
3
2
53 
50 
40 
14 
15 
16 
17 
18 
24 
57 
27 
26 
13 
6
1
J8E4 
48 
CHIP 
SMB_PCH_MEZZ_LOM2_SDA 
1/16W 0402 
SMB_PCH_MEZZ_LOM1_SCL 
0402 
SMB_PCH_MEZZ_LOM0_SDA 
G21796-112 
G21796-112 
LED_GBE_P2_0 
TP_SHARED_KR_MDC_0 
TP_SHARED_KR_MDIO_0 
SMB_PCH_MEZZ_LOM2_SDA 
H87568-002 
0402 
1% 
2
R1W42 0402 
0402 
1/16W 
G21796-072 
TP FAB1 DELETE TEST POINT 0121 
TP FAB3-DVT ADD 4.75KOHM RES R1W40, R1W41 20161205 
TP FAB3-DVT ADD 4.75KOHM RES R1W42-45 20161206 
120 
118 
120 188 
120 
120 
188 
188 
120 188 
250 
188 
120 188 
120 188 
120 188 
120 188 
120 188 
120 188 
188 118 
188 
118 
118 
120 188 
118 
188 
120 188 
91 138 159 186 
138 159 91 186 
120 
120 188 
120 188 
120 188 
120 188 
120 188 
120 188 
118 
120 
118 
118 
188 
188 
120 
120 
120 188 
120 188 
120 188 
120 
120 188 
GROUP=KR 
GROUP=KR 
NOPOP 
GROUP=KR 
188 120 
188 120 
188 120 
188 
188 120 
188 
CAD NOTE: 
CAD NOTE: 
ROOM = IO_MODULE 
TP FAB1 PUT KR1 BACK 0322 
TP FAB1 DELETE CONNECTION TO PCH 1230 
DO NOT SCALE DRAWING SHEET 
B
AA
B
B
SIZE 
SCALE: 
234
1234
DEPARTMENT CODE 
1
DOCUMENT NUMBER REV 
OUT 
OUT 
OUT 
OUT 
IN 
IN 
IN 
IN 
OUT 
OUT 
IN 
P12V_STBY P12V_STBY P12V_STBY P12V_STBY 
IN 
P12V_STBY 
IN 
IN 
IN 
IN 
BI 
IN 
IN 
IN 
OUT 
OUT 
OUT 
OUT 
IN 
IN 
IN 
IN 
OUT 
OUT 
OUT 
P3V3_STBY 
OUT 
OUT 
OUT 
OUT 
IN 
BI 
BI 
IN 
IN 
BI 
IN 
BI 
BI 
BI 
BI 
BI 
188 OF 270 
Wed Feb 08 16:35:20 2017 
IO10 
IO11 
IO12 
IO13 
IO14 
IO15 
IO16 
IO17 
IO18 
IO19 
IO20 
IO21 
IO22 
IO24 
IO4 
IO5 
IO51 
IO54 
IO55 
IO56 
IO57 
IO58 
IO59 
IO6 
IO60 IO61 IO62 
IO63 
IO64 
IO7 
IO8 
IO9 
IO3 IO2 
IO32 IO31 IO30 IO29 IO28 IO27 IO26 IO25 
IO23 
IO53 
IO52 
IO50 IO49 IO48 IO47 IO46 IO45 IO44 IO43 IO42 IO41 IO40 
IO39 IO38 IO37 IO36 IO35 IO34 IO33 IO1 
SCONN64_H87568002_A 
FCI PLUG # ON OCP MEZZ 
TP FAB1 DELETE CAPS 0106 
61082-081402LF 
10135584-641402LF 
61082-121402LF 
B (80P) 
H87568-002 
E67482-008 
(5/8MM STACK) 
A (120P) 
(5MM STACK) 
10135583-642402LF 
61082-082402LF 
61082-122402LF 
(12MM STACK) 
FCI RECPT IPN ON CC 
MATED HT CONNECTOR P/NS 
FCI RECPT IPN ON CC 
(12 MM STACK) 
FCI RECPT # ON CC 
A28699-010 
E67482-006 
H87568-001 
FCI RECPT # ON CC CONN 
61083-121402LF 
(5/8MM STACK) 
61082-081402LF 
TP FAB1 ADD CAPS 0322 
10135583-641402LF 
61083-124402LF 
(8/12 MM STACK) 
FCI PLUG # ON OCP MEZZ 
10135584-644402LF 
TP FAB1 DELETE TEST POINT 0121 
TP FAB1 RENAME 1218 
A28699-020 
61083-084402LF 
C (64P) 
PLEASE PLACE CAPS WITHIN 1 INCH OF PCH 
OCP MODULE CONN C 
WIWYNN CORPORATION 



0402 
JTAG_TMS 
R25W186 
0.0 
1/16W 
G21796-016 
0402 
JTAG_TCK 
CHIP 1/16W 
JTAG_PLD_TCK_MUX 
0.0 
0402 
C1L119 
1.0UF 
JTAG_TMS 
JTAG_PLD_TDO_MUX_R 
5% 0.0 
G21497-005 
1
R7G14 
0402 
JTAG_PLD_TDO_MUX 
CHIP 1/16W 
2
R8G18 G21497-005 
0402 CHIP 
JTAG_PLD_TMS_MUX 
G21497-005 
1/16W 
5% 1
R8G13 
G21497-005 
JTAG_PLD_TMS 0.0 2
JTAG_PLD_TCK 
G21796-072 
JTAG_TDO_R 
0402 
1/16W 
1% 
10.0K 
JTAG_BMC_TRST_N 
EMPTY 1/16W 
5% 
G21497-005 
FM_JTAG_PLD_EN_DEBUG 
1/16W 
EMPTY 
0402 
1/16W 
CHIP 
1.00K 
G21796-026 
0402 
2
1
1% 
R3R15 
G21497-005 
R7G17 
2
CHIP 0402 
15% 
1/16W 
0.0 
0.0 
R8G7 
G21497-005 
JTAG_PLD_TDI_MUX 
1 2
JTAG_PLD_TDI 
1/16W 
5% 2
G21497-005 
0402 
U1L10 
IC 
74CBTLV3126 
10% 
16V 
JTAG_TMS 
1/16W 
5% 0.0 
0402 
JTAG_BMC_TDO 
JTAG_PCH_PLD_TDO 
JTAG_PCH_GBE_TDO 
JTAG_BMC_TCK 
JTAG_PCH_PLD_TCK 
JTAG_PCH_GBE_CLK 
JTAG_BMC_TMS 
JTAG_PCH_GBE_TMS 
JTAG_BMC_TDI 
JTAG_PCH_PLD_TDI 
JTAG_PCH_GBE_TDI 
JTAG_TRST_N 
JTAG_PCH_GBE_TRST_N 
0.0 
1/16W 
5% 1
EMPTY 
2
R7G15 
0.0 
1/16W 
5% 1
R7G16 
EMPTY 
2
0402 
0.0 
1/16W 
5% 
CHIP 0402 
1 2
R8G17 
0.0 
1/16W 
5% 1
R8G16 
EMPTY 
2
0402 
G21497-005 
1/16W 
5% 1
R8G15 
EMPTY 
2
0.0 
1/16W 
1
0.0 5% 1
EMPTY 
2
0.0 
1/16W 
5% 
EMPTY 
1 2 G21497-005 
0.0 
1/16W 
5% 1
CHIP 
R8G8 
2
1/16W 
5% 1
CHIP 
R8G10 
20.0 
0402 
G21497-005 
1/16W EMPTY 
0.0 5% 1
R7G18 
2 G21497-005 
0.0 5% 21
R8G9 
0.0 
1/16W 
5% 1
EMPTY 
2
0402 
G21497-005 
0.0 
0402 
G21497-005 
R7G19 
G21497-005 
5% 
1/16W 
JTAG_PCH_PLD_TMS 
2
R8G14 
0402 
R8G11 
R8G12 
G21497-005 
CHIP 0402 
J7G2 
C77962-004 
CONN 
1
2
3
4
5
6
7
8
2 1
CR3U1 
IC 
1% 
R8G20 
10.0K 
1/16W 
CHIP 
G21796-016 
1
CHIP 
0402 
R8G23 
2
R7G23 
0402 
10.0K 
G21796-016 
CHIP 
0402 
G21796-016 
CHIP 
1/16W 
R7G22 
1% 
1
0402 
25% 0.0 
2
0402 
G21497-005 
R8G19 
10.0 5% 
1/16W 
15% 
CHIP 
R8G21 
2
0402 
0402 CHIP 
1
R7G21 
2
JTAG_TCK_R 
P3V3_STBY_PLD_D 
D55839-001 
1N5819HW 
SMLF 
JTAG_TDI_R 
JTAG_TMS_R 
G21497-005 
G21497-005 
G21497-005 
0402 
0402 
G21497-005 CHIP 
G21497-005 
R8G22 
1/16W 
0.0 
1/16W 
JTAG_TDI 
JTAG_TCK 
JTAG_TDO 
JTAG_TDI 
CHIP 
D97712-011 
X6S 
0402 
G21497-005 
JTAG_TDO 
JTAG_TDI 
JTAG_TRST_N 
PWRGD_P3V3_STBY 
JTAG_TCK 
G21497-005 
D18317-001 
0402 CHIP 
1
1/16W 
5% 0.0 
5% 
VCC=P3V3_STBY;GND=GND CHIP 
R7G114 
JTAG_TDO 
2
1
0402 
1 2
CHIP 
1% 
10.0K 
R3R11 
1/16W 
4.75K 
1% 
TP FAB3 ADD RES 1014 
189 
148 189 
254 255 
189 
245 
148 
189 
254 
255 
189 
245 
245 
191 
191 
144 245 254 
191 
191 
189 
144 255 
120 
120 
144 254 
120 
120 
144 255 
120 
144 255 
120 
120 
189 
120 
120 
189 
189 
189 
189 
189 
189 
189 
240 101 191 196 237 239 
189 
189 
BMC_JTAG_SEL_N_MUX 
BMC_JTAG_SEL_N 
BMC_JTAG_SEL_N 
B
B
OE 
OE 
OE 
B
OE 
B
A
A
A
A
DESIGN NOTE: 
DESIGN NOTE: 
BOM NOTE: 
BOM NOTE: 
1
4
10 
13 
2
5
12 
9
3
6
8
11 
1N5819HW USED TO PREVENT LEAKAGE ONTO P3V3_STBY RAIL 
FROM JTAG DEBUG DEVICES PLUGGED INTO THE BOARD 
DO NOT SCALE DRAWING SHEET 
B
AA
B
B
SIZE 
SCALE: 
234
1234
DEPARTMENT CODE 
1
DOCUMENT NUMBER REV 
IN 
IN 
IN 
OUT 
OUT 
IN 
OUT 
IN 
P3V3_STBY 
IN 
IN 
IN 
OUT 
IN 
IN 
OUT 
P3V3_STBY 
OUT 
P3V3_STBY 
P3V3_STBY 
OUT 
OUT 
OUT 
IN 
OUT 
IN 
IN 
OUT 
IN 
IN 
IN 
IN 
IN 
IN 
IN 
IN 
OUT 
OUT 
IN 
IN 
IN 
IN 
189 OF 270 
Wed Feb 08 16:35:21 2017 
IO1 
IO2 
IO3 
IO4 
IO5 
IO6 
IO7 
IO8 
CONN8_C77962004 
ROOM=BMC_DEBUG_HEADER 
PCH GBE 
PCH PLD 
CPLD 
BMC 
DEBUG FOR: 
TP FAB3 ADD BMC REMOTE CIRCUIT 1003 
TP FAB4 CHANGE A SIDE CONNECTION 20170111 
UNSTUFF 0-OHM RESISTORS FOR 
BMC TO CPLD COMMUNICATION 
UNSTUFF CPLD AND BMC RES FOR PCH OR PCH GBE CPLD JTAG ENABLED WHEN HIGH (DEFAULT) 
CPLD JTAG DISABLED WHEN LOW 
BMC JTAG HEADER 
WIWYNN CORPORATION 



FM_PVCCIO_CPU0_EN 
0.0 
D2 
TP_CPLD1_PL1B_L_GPLLC_FB 
TP_CPLD1_PB16B_PCLKC2_1 
RST_CD_CPU0_POR_N 
PWRGD_PVPP_GHJ 
FM_GLOBAL_RST_WARN_N 
PWRGD_PVPP_KLM 
PWRGD_PVCCIN_CPU1 
RST_PCIE_RISER1_PERST_N 
PWRGD_PVCCMCP_CPU1 
PWRGD_PVCCIN_CPU0 
RST_RSMRST_DLY 
CLK_25M_CPLD 
PWRGD_CPU0_LVC3 
SGPIO_BMC_LD_N 
TP_CPLD1_PL11A 
PWRGD_PVSA_CPU0 
SGPIO_BMC_CLK 
TP_CPLD1_PL7D_PCLKT4_0 
SGPIO_BMC_DOUT 
FM_PVCCIOMCP_CPU0_EN 
SP1_BMC_HOST_UART_RX 
UART_BMC_TXD5 
SP1_BMC_HOST_UART_TX 
FM_BMC_CPLD_GPO 
FM_UART_ALERT_N 
FM_CPU1_PKGID1 
FM_CPU_MSMI_LVT3_N 
UART_BMC_RXD5 
RST_PCIE_CPU_DEV3_N 
RST_PCIE_CPU_DEV2_N 
FM_CPU1_PKGID2 
RST_CPU1_LVC3_R1_N 
RST_CPU0_LVC3_R1_N 
FM_CPLD_UART_CH_LOCK_N 
FM_PVCCMCP_CPU1_EN 
TP_CPLD1_PB16A_PCLKT2_1 
FM_UARTSW_MSB_N 
FM_SOL_UART_CH_SEL 
RST_CD_CPU1_POR_N 
XDP_SYSPWROK 
PWRGD_CPU1_LVC3 
XDP_PWRGD_RST_N 
FM_CPU_CATERR_LVT3_N 
PWRGD_DRAMPWRGD 
FM_CPU1_PKGID0 
FM_CPU0_SKTOCC_LVT3_N 
FM_CPU0_VRM_OSC_EN 
FM_CPU1_SKTOCC_LVT3_N 
FM_DB1200ZL_BCLKS_EN_N 
FM_CPLD_BMC_PWRDN_N 
TP_CPLD1_PB25B_SI_SISPI 
FM_156M_CPU0_BRD_OSC_EN 
FM_UARTSW_LSB_N 
RST_CPU0_LVC3_N 
TP_CPLD1_PB8A_MCLK_CCLK 
TP_CPLD1_PB8B_SO_SPISO 
FM_IE_DISABLE_N 
FM_156M_CPU1_BRD_OSC_EN 
FM_CPLD_DBG_PWR_EN_N 
PWRGD_PVNN_P1V05_PCH 
PWRGD_PVCCIO_CPU0 
PWRGD_PVPP_DEF 
RST_PCIE_M2_DEV_N 
FM_CPU1_RC_EN 
FM_CPU0_PKGID2 
PWRGD_P5V 
FM_MP_PS_FAIL_N 
FM_PVCCMCP_CPU0_EN 
FM_SLPS3_N 
PWRGD_P3V3 
FM_CPU0_FIVR_FAULT_LVT3_N 
FM_CPU0_PKGID1 
FM_CPU0_PROC_ID1 
FM_CPU0_PROC_ID0 
RST_CPU1_LVC3_N 
FM_CPLD_USB_P0_EN_N 
FM_PVCCIO_CPU1_EN 
PWRGD_PVPP_ABC 
FM_PVCCIOMCP_CPU1_EN 
PWRGD_PVTT_CPU1 
FM_OC0_USB_N 
PWRGD_PVCCIOMCP_CPU0 
FM_BMC_CPLD_MP_RST_N 
FM_DIS_ADR_DLY 
PWRGD_PVCCIOMCP_CPU1 
PWRGD_PVCCMCP_CPU0 
TP_CPLD1_PB5A_CSSPIN 
FM_CPU0_RC_EN 
FM_ADR_MODE_SEL 
PWRGD_PVSA_CPU1 TP_CPLD1_PL1A_L_GPLLT_FB 
RST_CPU0_LVC3_R1_N 
RST_PCIE_PCH_PERST_N 
FM_PCH_PLD_DATA 
FM_CPU_CATERR_DLY_LVT3_N 
RST_RSMRST_R_N 
FM_DEBUG_RST_BTN_N 
CLK_32K_SUSCLK_PLD 
RST_PCIE_CPU_DEV1_N 
TP_CPLD1_PL2B_L_GPLLC_IN 
FM_CPU0_PKGID0 
PU_RST_PERST_BIT0 
FM_PWR_BTN_N FM_PWR_BTN_R2_N 
RST_CPU1_LVC3_R1_N 
5% 0.0 R1W27 
CHIP G21497-005 
21
G21796-016 
10.0K 
R1W26 
1
1% 
1/16W 
EMPTY 2
0402 
FM_MEM_EVENT_FUNC 
RST_RSMRST_R_N 
1/16W 
1% 
G21796-074 
0402 33.2 
R2R2 
CHIP 
RST_RSMRST_N 
C1 
G5 
T7 
M7 
E1 
R5 
U8D7 
B1 
G1 
H3 
H4 
G3 
G2 
J4 
P6 
T6 
T14 
K5 
R11 
J6 
J1 
P10 
L10 
M9 
H6 
P4 
R6 
T3 
R4 
L7 
P7 
N7 
R8 
M6 
L8 
P8 
T8 
N8 
L9 
T9 
P9 
M8 
N9 
R9 
T10 
R10 
N10 
M11 
T11 
P11 
M10 
N11 
T12 
R13 
P12 
T13 
R12 
P13 
T15 
R14 
D1 
C2 
E2 
E3 
F2 
G4 
F5 
H2 
H1 
K1 
H5 
K3 
K2 
J5 
K6 
L1 
L3 
K4 
L5 
L2 
M1 
L4 
M3 
N1 
P1 
P2 
IC 
P5 
R7 
J3 
M2 
R1 
H63395-001 
N2 
J2 
N3 
D3 
N6 
T5 
T4 
T2 
R3 
G6 
F4 
F3 
F1 
CHIP 0402 5% 
G21497-005 
R3P35 1
1/16W 
2
1/16W CHIP 
0402 5% 0.0 
G21497-005 
1R3P34 2
211 
192 29 
233 
119 147 
234 
206 
108 
193 
201 112 
126 
101 
96 
144 
201 
144 
144 
194 
158 145 
145 150 158 
145 158 
119 146 157 
183 119 
55 113 
92 147 120 247 
158 145 
187 
187 
55 
190 
190 
135 
193 
120 144 158 
168 120 145 
192 63 
111 144 
96 
111 
92 144 247 
96 
55 
21 118 144 
104 
55 112 118 146 
102 
119 145 157 
104 
120 144 158 
96 
135 120 
104 
155 
235 
211 118 
232 
248 
119 133 
21 
196 
157 181 120 144 
194 
118 148 247 
196 175 248 
144 
21 113 
21 
21 
96 
176 
213 
231 91 
193 
229 230 
176 
120 
194 
118 147 157 
135 
193 
194 
120 133 
119 
206 
190 
121 
119 133 
119 
190 
111 155 247 175 
101 
187 
21 
192 
175 119 145 
190 
192 
190 192 111 118 147 
0402 1/16W 
DO NOT SCALE DRAWING SHEET 
B
AA
B
B
SIZE 
SCALE: 
234
1234
DEPARTMENT CODE 
1
DOCUMENT NUMBER REV 
IN 
OUT 
IN 
OUT 
IN 
IN 
IN 
IN 
IN 
OUT 
BI BI 
OUT 
OUT 
IN 
OUT 
IN 
IN 
IN 
IN 
IN 
IN 
IN 
IN 
IN 
IN 
IN 
IN 
IN 
OUT 
IN 
IN 
IN 
OUT 
OUT 
IN 
IN 
OUT 
OUT 
OUT 
OUT 
OUT 
IN 
IN 
OUT 
OUT 
IN 
IN 
IN 
IN 
IN 
IN 
BI 
IN 
OUT 
IN 
IN 
OUT 
IN 
OUT 
IN 
IN 
OUT 
OUT 
IN 
OUT 
IN 
IN 
IN 
IN 
IN 
OUT 
OUT 
OUT 
OUT 
OUT 
IN 
IN 
IN 
IN 
OUT 
IN 
IN 
IN 
OUT 
OUT 
IN 
OUT 
OUT 
IN 
IN 
OUT 
IN 
OUT 
OUT IN 
IN 
190 OF 270 
Wed Feb 08 16:35:21 2017 
LCMXO2_A 
1/3 
PL7C_PCLKT4_0 
PB19A 
PB18D 
PB18C 
PL5D 
PB3A PB3B PB3C 
PB3D 
PB5A_CSSPIN PB5B 
PB6A PB6B PB6C 
PB6D 
PB8A_MCLK_CCLK PB8B_SO_SPISO PB8C 
PB8D 
PB9A PB9B PB9C 
PB9D 
PB11A_PCLKT2_0 PB11B_PCLKC2_0 PB11C 
PB11D 
PB12A 
PB12B PB12C 
PB12D 
PB16A_PCLKT2_1 PB16B_PCLKC2_1 PB16C 
PB16D 
PB18A PB18B 
PB19B PB19C 
PB19D 
PB21A PB21B PB21C 
PB21D 
PB22A 
PB22B PB22C 
PB22D 
PB24A PB24B 
PB25A_SN PB25B_SI_SISPI PB25C 
PB25D 
PL1A_L_GPLLT_FB 
PL1B_L_GPLLC_FB 
PL1C 
PL1D 
PL2A_L_GPLLT_IN 
PL2B_L_GPLLC_IN 
PL2C 
PL2D 
PL3A_PCLKT5_0 
PL3B_PCLKC5_0 
PL3C 
PL3D 
PL4A 
PL4B 
PL4C 
PL4D 
PL5A 
PL5B 
PL5C 
PL6A 
PL6B 
PL6C 
PL6D 
PL7A 
PL7B 
PL7D_PCLKC4_0 
PL9A 
PL9B 
PL9C 
PL9D 
PL10A 
PL10B 
PL10C 
PL10D 
PL11A 
PL11B 
PL11C 
PL11D 
PL12A_PCLKT3_0 
PL12B_PCLKC3_0 
PL12C 
PL12D 
PL13A 
PL13B 
PL13C 
PL13D 
PL14A 
PL14B 
PL14C 
PL14D 
BOM_COST=CPLD ROOM=CPLD 
TP FAB1 NC (NO USE IE) 0118 
TP FAB1 ADD RES 0217 
TP FAB1 ADD RES 0226 TP FAB1 CONNECT TO USB3.0 OC IC 1221 
CPLD (1 OF 3) 
WIWYNN CORPORATION 



PWRGD_P1V8MCP_CPU0 
FM_SINT_PRSNT_N 
TP_CPLD1_PT24B 
TP_CPLD1_PT24C_INITN 
TP_CPLD1_PT24D_DONE 
FM_CPU0_AND_CPU1_MCP_PRES 
PWRGD_DSW_PWROK 
PU_THERMTRIP_FORCE_N 
FM_PCH_PWRBTN_N 
FM_SLPS4_N 
JTAG_PLD_TMS 
TP_CPLD1_PT11A 
FM_BMC_ONCTL_N 
FM_ADR_COMPLETE 
FM_PVDDQ_ABC_EN 
PWRGD_P3V3_STBY 
FM_ADR_SMI_GPIO_N 
TP_CPLD1_PT13A 
FM_CPU1_FIVR_FAULT_LVT3_N 
JTAG_PLD_TCK 
FM_PLD_DEBUG_MODE_N 
FM_PVPP_CPU1_EN 
FM_CPU0_THERMTRIP_LVT3_N 
FM_PVDDQ_DEF_EN 
FM_FAST_PROCHOT_THROTTLE_DLY_N 
FM_MEM_THERM_EVENT_PCH_N 
FM_PVDDQ_GHJ_EN 
PWRGD_PVCCIO_CPU1 
FM_PVCCIN_PVCCSA_CPU1_EN_LVC1 
FM_CPU1_VRM_OSC_EN 
FM_PVPP_CPU0_EN 
FM_P12V_MAIN_SW_EN 
FM_CPU1_PROC_ID1 
FM_CPU0_FIVR_FAULT_LVT3 
RST_PLTRST_BUF_N 
FM_THERMTRIP_DLY 
FM_CPU1_PROC_ID0 
TP_CPLD1_PR12D 
TP_CPLD1_PR11B 
TP_CPLD1_PR10C 
TP_CPLD1_PR9D 
TP_CPLD1_PR9C 
TP_CPLD1_PR9A 
TP_CPLD1_PR7D 
TP_CPLD1_PR7C 
TP_CPLD1_PR7B_PCLKC1_0 
TP_CPLD1_PR7A_PCLKT1_0 
TP_CPLD1_PT17C 
TP_CPLD1_PT17B_PCLKC0_1 
TP_CPLD1_PT16B 
FM_MEM_THERM_EVENT_LVT3_N 
TP_CPLD1_PT19D 
TP_CPLD1_PT20A 
TP_CPLD1_PT20B 
TP_CPLD1_PT22D 
FM_PCH_PWRBTN_R1_N 
FM_JTAG_PLD_EN_DEBUG 
FM_CPU0_OR_CPU1_MCP_PRES 
FM_CPU0_CD_PRES 
FM_CPU1_CD_PRES_N 
TP_CPLD1_PT22C 
FM_WBG_PRSNT_N 
FM_CPU1_MCP_CLK_EN_N 
FM_CPU1_FIVR_FAULT_LVT3 
FM_P1V8MCP_CPU1_EN 
FM_ADR_SMI_GPIO_R_N 
JTAG_PLD_TDI 
JTAG_PLD_TDO 
RST_PCIE_CPU_DEV0_N 
FM_PCH_PRSNT_N 
TP_CPLD1_PT11B 
FM_CPU1_THERMTRIP_LATCH_LVT3_N 
FM_P3V3_CPLD_EN 
PU_FAB2_MARKER_CPLD 
RST_BMC_SYSRST_BTN_OUT_B_N RST_BMC_SYSRST_BTN_OUT_B_ R1_N 
FM_PVDDQ_KLM_EN 
FM_FAST_PROCHOT_THROTTLE_IN_N 
FM_UV_ADR_TRIGGER_EN 
FM_CPU1_THERMTRIP_LVT3_N 
FM_UV_ADR_TRIGGER_N 
PWRGD_CPUPWRGD 
FM_CPU0_THERMTRIP_LATCH_LVT3_N 
FM_CPU0_MCP_CLK_EN_N 
FM_P1V8MCP_CPU0_EN 
PWRGD_PCH_PWROK 
FM_CPLD_ADR_TRIGGER_N 
PWRGD_P1V8MCP_CPU1 
FM_ADR_COMPLETE_DLY 
FM_DB1200_PWRGD 
RST_PLTRST_N 
PWRGD_SYS_PWROK 
SMB_SENSOR_STBY_LVC3_SDA 
SMB_SENSOR_STBY_LVC3_SCL 
RST_PCIE_MIDPLANE_N 
SGPIO_BMC_DIN_R 
PU_RST_PERST_BIT1 
FM_PS_EN 
FM_PVCCIN_PVCCSA_CPU0_EN_LVC1 
FM_SLP_SUS_N 
FM_FORCE_ADR_N 
PWRGD_PVTT_CPU0 
FM_CTNR_PS_ON 
PWRGD_P1V15_BMC_STBY 
E16 
F15 
E10 
D10 
A9 
G12 
C16 
F13 
B12 
C15 
B16 
D16 
E14 
D15 
F16 
F12 
G14 
G11 
H12 
H15 
H13 
J12 
H14 
H16 
J16 
J14 
J15 
K16 
H11 
J13 
K14 
K15 
J11 
L12 
L14 
K13 
K12 
L15 
M16 
K11 
L13 
M14 
M15 
N15 
P16 
N16 
N14 
P15 
R16 
C4 
B5 
B3 
A4 
C5 
A5 
B6 
A3 
B4 
D6 
B7 
E6 
D7 
F7 
E8 
A7 
B8 
C8 
A8 
D8 
E9 
D9 
C9 
A10 
F9 
C11 
F10 
D11 
B11 
B14 
A15 
A13 
C13 
B9 
E11 
C12 
D14 
E15 
E7 
C6 
A6 
C7 
IC 
H63395-001 
U8D7 
L16 
A11 
A14 
B13 
A12 
B10 
C10 
F8 
G16 
F14 
G15 
G13 
CHIP G21497-005 5% 0.0 R1W29 
1 2
1 2
CHIP 0.0 5% G21497-005 R1W28 
R4W1 
2
4.75K 1
1% 
1/16W 
CHIP 
G21796-072 
0402 
1/16W 
4.75K 
R7D42 
G21796-072 
0402 
CHIP 2
1% 
1
PWRGD_P12V_MAIN 
CHIP G21497-005 
2
R2R4 
0.0 
1
0402 
4.75K 
1% 
1/16W 
0402 
CHIP 
G21796-072 
R2R7 
SGPIO_BMC_DIN 
CHIP 0402 
51 G21497-048 
R2R6 
5.0% 1/16W 
TP FAB1 CHANGE NET NAME TO LOW ACTIVE 
194 
121 133 
113 
196 200 118 157 247 
192 
156 118 
118 148 
189 
145 
120 89 
215 
240 101 189 196 237 239 
89 156 157 120 
144 
189 
192 
233 234 
92 
218 
170 
120 145 
223 
213 
206 
104 
231 232 
198 
55 
92 
146 134 145 184 
134 
55 
94 156 
189 
113 
113 
113 
121 133 
102 
92 
193 
189 
245 
186 
121 133 
120 145 
198 
156 118 
226 
170 
119 125 144 
92 
200 
92 
145 119 
102 
194 
133 118 144 
120 
193 
89 
102 
119 136 139 247 
133 118 144 247 
164 167 
184 
167 164 184 
181 
192 
181 
201 
118 
120 144 
221 222 
181 161 198 
238 
196 
144 
0402 
PU_CPLD1_PT20D_PROGRAMN 
1/16W 
0402 1/16W 
1/16W 5% 
CAD NOTE: 
DESIGN NOTE: 
1
2
21
DO NOT SCALE DRAWING SHEET 
B
AA
B
B
SIZE 
SCALE: 
234
1234
DEPARTMENT CODE 
1
DOCUMENT NUMBER REV 
IN 
OUT 
OUT 
IN 
IN 
OUT 
OUT 
IN 
IN 
IN 
OUT 
IN 
IN 
IN 
IN 
OUT 
OUT 
OUT 
P3V3_STBY 
P3V3_STBY 
OUT 
OUT 
OUT 
IN 
OUT 
OUT 
OUT 
OUT 
IN 
OUT 
OUT 
IN 
IN 
OUT 
OUT 
IN 
OUT 
OUT 
OUT 
OUT 
OUT 
P3V3_STBY 
IN 
IN 
IN 
IN 
OUT 
IN 
OUT 
IN 
OUT 
OUT 
OUT 
OUT 
IN 
OUT 
OUT 
IN 
IN 
OUT 
IN 
IN 
IN 
BI 
IN 
IN 
OUT 
IN 
IN 
IN 
OUT 
OUT 
OUT 
IN 
IN 
OUT 
OUT 
IN 
IN 
IN 
Wed Feb 08 16:35:21 2017 
191 OF 270 
LCMXO2_A 
2/3 
PR1C 
PR1D 
PR2A 
PR2B 
PR2C 
PR2D 
PR3A 
PR3B 
PR3C 
PR3D 
PR4A 
PR4B 
PR4C 
PR5A 
PR5B 
PR5C 
PR5D 
PR6A 
PR6B 
PR6C 
PR6D 
PR7A_PCLKT1_0 
PR7B_PCLKC1_0 
PR7C 
PR7D 
PR9A 
PR9B 
PR9C 
PR9D 
PR10A 
PR10B 
PR10C 
PR10D 
PR11A 
PR11B 
PR11C 
PR11D 
PR12A 
PR12B 
PR12C 
PR12D 
PR13A 
PR13B 
PR13C 
PR13D 
PR14A 
PR14B 
PR14C 
PR14D 
PT9A PT9B PT9C 
PT10A PT10B 
PT11A PT11B 
PT11C 
PT11D 
PT12A 
PT13A 
PT13C 
PT13D 
PT16A PT16B PT16C_TCK PT16D_TMS 
PT17A_PCLKT0_1 PT17B_PCLKC0_1 PT17C 
PT17D 
PT18A 
PT18B PT18C_SCL_PCLKT0_0 PT18D_SDA_PCLKC0_0 
PT19B PT19C 
PT20A PT20B 
PT21A PT21B PT21C 
PT21D 
PT22A PT22B PT22C 
PT22D 
PT23B 
PT24A PT24B PT24C_INITN PT24D_DONE 
PT19A 
PT19D 
PT20C_JTAGENB PT20D_PROGRAMN 
PT23A 
PR1A 
PR1B 
PT12B PT12C_TDO PT12D_TDI 
PT13B PR4D 
TP FAB1 ADD RES 0226 
TP FAB1 ADD RES 0226 
TP FAB1 ADD A PU RES 0203 
SMBUS ADDRESSES:  0X80-0X86 
PLACE THIS RESISTOR NEAR CPLD 
CPLD (2 OF 3) 
WIWYNN CORPORATION BOM_COST CPLD 
ROOM CPLD 



0402 
EMPTY 
10.0K 
G21796-016 
0402 
1
G21796-026 
K10 
PU_RST_PERST_BIT1 
FM_PLD_DEBUG_MODE_N 
CHIP 
1% 
G21796-016 
0402 
1/16W 
CHIP 
G21796-016 
0402 
1/16W 
CHIP 
R7E19 
1.00K 
1% 
R7E5 
2
1% 
2
1
X7R 
16V 
0402V 
10% 
0.1UF 
A36096-030 
C2P2 
2
1
X7R 
16V 
0402V 
10% 
0.1UF 
A36096-030 
C2R1 
2
1
X7R 
16V 
0402V 
10% 
0.1UF 
A36096-030 
C3R3 
FM_MEM_EVENT_FUNC 
2
1
X7R 
16V 
0402V 
10% 
0.1UF 
A36096-030 
C3P43 
0402 
1/16W 
CHIP 
G21796-026 
1% 
1.00K 
R7E20 
1/16W 
RST_RSMRST_N 
RST_CD_CPU1_POR_N 
RST_CD_CPU0_POR_N 
2
1
1/16W 
CHIP 
0402 
1% 
4.75K 
G21796-072 
R6M9 
CHIP 2
1
1/16W 
0402 
1% 
4.75K 
G21796-072 
R3R16 
1
PU_THERMTRIP_FORCE_N 
2
1
X7R 
16V 
0402V 
10% 
0.1UF 
A36096-030 
C3R1 
PU_RST_PERST_BIT0 
R2R1 
1/16W 
0402 
CHIP 
1% 
10.0K 
0402 
1/16W 
CHIP 
G21796-016 
1% 
10.0K 
2
1
X7R 
16V 
0402V 
10% 
0.1UF 
A36096-030 
C2P5 
2
1
X7R 
16V 
0402V 
10% 
0.1UF 
A36096-030 
C2R2 
2
1
X7R 
16V 
0402V 
10% 
0.1UF 
A36096-030 
C3P48 1
2 X7R 
16V 
0402V 
10% 
0.1UF 
A36096-030 
C3P44 
2
1
X7R 
16V 
0402V 
10% 
0.1UF 
A36096-030 
C2P3 
2
1
X7R 
16V 
0402V 
10% 
0.1UF 
A36096-030 
C2R4 
2
1
X7R 
16V 
0402V 
10% 
0.1UF 
A36096-030 
C2P7 
2
1
X7R 
16V 
0402V 
10% 
0.1UF 
A36096-030 
C2R3 
2
1
X7R 
16V 
0402V 
10% 
0.1UF 
A36096-030 
C2P6 
2
1
X7R 
16V 
0402V 
10% 
0.1UF 
A36096-030 
C3P52 
2
1
X7R 
16V 
0402V 
10% 
0.1UF 
A36096-030 
C2P4 
2
1
X7R 
16V 
0402V 
10% 
0.1UF 
A36096-030 
C2R5 
J10 
A2 
R15 
H63395-001 
B2 
T16 
T1 
A16 
A1 
L6 
B15 
C3 
C14 
D4 
D13 
E5 
E12 
F6 
F11 
H8 
H9 
J8 
J9 
L11 
M5 
M12 
N4 
N13 
P3 
P14 
R2 G7 
G10 
K7 
G8 
D12 
G9 
E13 
H10 
M13 
K9 
N12 
K8 
N5 
J7 
H7 
E4 
D5 
M4 
IC 
U8D7 
0402V 
2
1
X7R 
16V 
10% 
0.1UF 
A36096-030 
C3P47 
2
1
X7R 
16V 
0402V 
10% 
0.1UF 
A36096-030 
C3P51 
2
1
X7R 
16V 
0402V 
10% 
0.1UF 
A36096-030 
C3R2 
2
1
X7R 
25V 
0402V 
10% 
0.01UF 
A36096-045 
C2P8 
1/16W 
R2R3 
2
G21796-072 
1% 
10.0K 
R7E6 
4.75K 
R7E18 
191 
191 
190 
190 111 118 147 
190 63 
190 29 
191 
190 
NOPOP 
1 1
2
1
2 2 2
1
2
1
DO NOT SCALE DRAWING 
FM_MEM_EVENT_FUNC STATE: 
HIGH: MEM_EVENT ASSERTION ASSERTS THERMTRIP TO PCH THROUGH CPLD 
LOW: MEM_EVENT ASSERTION DOES NOT DRIVE THERMTRIP (NVDIMM M ODE) 
SHEET 
B
AA
B
B
SIZE 
SCALE: 
234
1234
DEPARTMENT CODE 
1
DOCUMENT NUMBER REV 
PVPP_KLM 
OUT 
P3V3_STBY P3V3_STBY 
OUT 
PVPP_ABC 
OUT 
OUT 
OUT 
P3V3_STBY 
OUT 
P3V3_STBY 
OUT 
OUT 
P3V3_STBY P3V3_STBY 
P3V3_STBY 
P3V3_STBY 
P3V3_STBY 
192 OF 270 
Wed Feb 08 16:35:21 2017 
LCMXO2_A 
3/3 
VCC<3> 
VCC<2> 
VCC<1> 
VCC<0> 
GND<14> 
GND<23> 
NC<0> 
GND<0> 
GND<1> GND<2> GND<3> GND<4> GND<5> GND<6> GND<7> GND<8> GND<9> GND<10> GND<11> GND<12> 
GND<13> 
GND<15> GND<16> GND<17> GND<18> GND<19> GND<20> GND<21> GND<22> VCC<4> VCC<5> VCC<6> VCC<7> 
VCCIO0<0> VCCIO0<1> VCCIO0<2> 
VCCIO1<0> VCCIO1<1> VCCIO1<2> VCCIO1<3> VCCIO2<0> VCCIO2<1> VCCIO2<2> VCCIO2<3> 
VCCIO4<0> VCCIO4<1> VCCIO5<0> 
VCCIO0<3> 
VCCIO3<0> 
TP FAB1 DEL NET 0309 
TP FAB1 NOPOP R7E18 0523 
CPLD (3 OF 3) 
WIWYNN CORPORATION 
ROOM CPLD 
BOM_COST CPLD 



FM_CPU1_VRM_322M_156M_OSC_EN 
VSENSE_P1V8MCP_CPU1_SKT_VRTN 
PVCCIOMCP_CPU1 
P1V8_MCP_CPU1 
P1V8_MCP_CPU1 
PVCCMCP_CPU1 
PVCCIOMCP_CPU1 
PVCCMCP_CPU1 
PVCCMCP_CPU1 
PVCCIOMCP_CPU1 
P1V8_MCP_CPU1 
PVCCMCP_CPU1 
C4E29 
20% 
470UF 
699013-049 699013-049 
3018 
0402V 
D97712-004 
699013-049 
ALUM ALUM 
3018 
20% 
470UF 
C4E24 1
2
C6R16 
1.0UF 
C4F2 
47UF 
4V 
C3C1 
1.0UF 
6.3V 
X6S 
D97712-004 
0402V 
3018 
FM_P1V8MCP_CPU1_EN 
H61426-002 
B10 
SVID_CLK0_CPU1_R 
SMB_VR_STBY_LVC3_SCL 
SMB_VR_STBY_LVC3_SDA 
PWRGD_PVCCMCP_CPU1 
SVID_DIO1_CPU1_R 
SVID_CLK1_CPU1_R 
VSENSE_PVCCIOMCP_CPU1_SKT_VRTN 
VSENSE_PVCCIOMCP_CPU1_SKT_VSEN 
CLK_322M_156M_CPU1_OSC_VRM_DP 
FM_PVCCMCP_CPU1_EN 
SVID_DIO0_CPU1_R 
SVID_ALERT0_CPU1_R_N 
VSENSE_P1V8MCP_CPU1_SKT_VSEN 
SVID_ALERT1_CPU1_R_N 
PWRGD_P1V8MCP_CPU1 
FM_PVCCIOMCP_CPU1_EN 
PWRGD_PVCCIOMCP_CPU1 
CLK_322M_156M_CPU1_OSC_VRM_DN 
VSENSE_PVCCMCP_CPU1_SKT_VRTN 
VSENSE_PVCCMCP_CPU1_SKT_VSEN 
VR_PVCCIOMCP_CPU1_XADDR1 
VR_PVCCMCP_CPU1_XADDR2 
2
1
X6S 
10% 
1.0UF 
C4F3 
2
1
6.3V 
C4F1 
2
1
470UF 
20% 
ALUM 
B16 
D15 
E15 
F15 
A16 
D16 
E16 
C16 
C14 
B14 
B12 
E13 
A14 
D19 
E19 
A8 
E14 
J4B2 
CONN 
F20 
F19 
F17 
F16 
F14 
F13 
F12 
F11 
F10 
F9 
F8 
F7 
F6 
F5 
F4 
F3 
F2 
F1 
E20 
E18 
E17 
E12 
E11 
E10 
E9 
E8 
E7 
E6 
E5 
E4 
E3 
E2 
E1 
D20 
D18 
D17 
D14 
D13 
D12 
D11 
D10 
D9 
D8 
D7 
D6 
D5 
D4 
D3 
D2 
D1 
C20 
C19 
C18 
C17 
C15 
C13 
C12 
C11 
C10 
C9 
C8 
C7 
C6 
C5 
C4 
C3 
C2 
C1 
B20 
B19 
B18 
B17 
B15 
B13 
B11 
B9 
B8 
B7 
B6 
B5 
B4 
B3 
B2 
B1 
A20 
A19 
A18 
A17 
A15 
A13 
A12 
A10 
A9 
A7 
A6 
A5 
A4 
A3 
A2 
A1 
F18 
A11 
E19 
H61426-002 
J4E1 
CONN 
F20 
F19 
F18 
F17 
F16 
F15 
F14 
F12 
F10 
F8 
F7 
F6 
F5 
F4 
F3 
F2 
E20 
E17 
E16 
E15 
E14 
E13 
E12 
E10 
E8 
E7 
E6 
E5 
E4 
E3 
E2 
E1 
D20 
D19 
D18 
D17 
D16 
D15 
D14 
D13 
D12 
D11 
D10 
D9 
D8 
D7 
D6 
D5 
D4 
D2 
D1 
C20 
C19 
C18 
C17 
C16 
C15 
C14 
C13 
C11 
C10 
C9 
C7 
C6 
C5 
C4 
C2 
B20 
B19 
B18 
B17 
B16 
B15 
B14 
B13 
B12 
B11 
B10 
B9 
B8 
B7 
B6 
B5 
B4 
B3 
B2 
B1 
A20 
A19 
A18 
A17 
A16 
A15 
A14 
A13 
A11 
A10 
A9 
A8 
A7 
A6 
A4 
A2 
A1 
E18 
C8 
A5 
F9 
E9 
C12 
F13 
D3 
C3 
A3 
F1 
C1 
A12 
F11 
E11 
10% 
1
2
C3C2 
1.0UF 
6.3V 
1
X6S 
10% 
2
C4C1 
699013-049 
470UF 
20% 
3018 
2.5V 
ALUM 
2
1
1
2
1/16W 
CHIP 
0402 
1% 
3.16K 
G21796-043 
R4C11 R4C12 
G21796-078 
8.06K 
1% 
0402 
CHIP 
1/16W 
2
1
20% 
X5R 
1
2 602433-106 
0603V 
C3F1 
602433-106 
47UF 
20% 
0603V 
4V 
X5R 
1
2
0402V 
10% 
6.3V 
D97712-004 
0402V 
D97712-004 
X6S 
56 
191 
55 206 213 
138 159 211 213 235 194 201 206 
215 218 223 226 
138 159 194 201 206 211 213 215 
218 223 226 235 
190 
55 223 226 
55 223 226 
73 
73 
104 
104 
190 
55 206 213 
206 213 55 
56 
223 226 55 
191 
190 
190 
104 
73 
73 
2.5V 2.5V 2.5V 
DESIGN NOTE: 
DO NOT SCALE DRAWING 
IMPROVE CPU1_VMCP TRANSIENT PERFORMANCE ADD C4E29 1003 
SHEET 
B
AA
B
B
SIZE 
SCALE: 
234
1234
DEPARTMENT CODE 
1
DOCUMENT NUMBER REV 
IN 
P5V_STBY 
P3V3_STBY 
P12V_STBY 
IN 
IN 
IN 
IN 
IN 
BI 
BI 
IN 
P3V3 
OUT 
OUT 
IN 
BI 
IN 
IN 
IN 
OUT 
OUT 
PVCCIO_CPU1 
OUT 
OUT 
IN 
OUT 
IN 
ROOM=PVCCP_MCP_CPU1 
193 OF 270 
Wed Feb 08 16:35:22 2017 
SMBUS ADDRESS 
IOF19 
IOA20 
IOB20 IOC20 
IOD20 
IOE20 IOF20 
IOE19 
IOD19 IOC19 
IOB19 
IOA19 
IOF18 
IOE18 IOD18 
IOC18 
IOB18 IOA18 
IOF17 IOE17 
IOD17 
IOC17 IOB17 
IOA17 
IOF16 
IOE16 
IOA14 
IOB14 IOC14 
IOD14 
IOE14 IOF14 
IOA15 
IOB15 
IOC15 
IOD15 IOE15 
IOF15 
IOA16 
IOB16 
IOC16 
IOD16 
IOF13 
IOE13 
IOD13 IOC13 
IOB13 
IOA13 
IOF12 
IOE12 IOD12 
IOC12 
IOB12 IOA12 
IOF11 IOE11 
IOD11 
IOC11 IOB11 
IOA11 
IOF10 
IOF9 
IOE9 
IOD9 
IOE10 
IOD10 
IOC10 IOB10 
IOA10 
IOC9 
IOB9 
IOA9 
IOF8 
IOE8 IOD8 
IOC8 
IOB8 IOA8 
IOE7 
IOD7 
IOC7 IOB7 
IOA7 
IOF6 
IOE6 
IOD6 
IOF7 
IOC6 
IOB6 
IOA6 
IOF5 
IOE5 IOD5 
IOC5 
IOB5 IOA5 
IOC4 IOB4 
IOA4 
IOD4 
IOF4 IOE4 
IOF3 
IOE3 
IOD3 IOC3 
IOB3 
IOA3 
IOF2 
IOE2 IOD2 
IOC2 
IOB2 IOA2 
IOF1 IOE1 
IOD1 
IOC1 IOB1 
IOA1 
IOF19 
IOA20 
IOB20 IOC20 
IOD20 
IOE20 IOF20 
IOE19 
IOD19 IOC19 
IOB19 
IOA19 
IOF18 
IOE18 IOD18 
IOC18 
IOB18 IOA18 
IOF17 IOE17 
IOD17 
IOC17 IOB17 
IOA17 
IOF16 
IOE16 
IOA14 
IOB14 IOC14 
IOD14 
IOE14 IOF14 
IOA15 
IOB15 
IOC15 
IOD15 IOE15 
IOF15 
IOA16 
IOB16 
IOC16 
IOD16 
IOF13 
IOE13 
IOD13 IOC13 
IOB13 
IOA13 
IOF12 
IOE12 IOD12 
IOC12 
IOB12 IOA12 
IOF11 IOE11 
IOD11 
IOC11 IOB11 
IOA11 
IOF10 
IOF9 
IOE9 
IOD9 
IOE10 
IOD10 
IOC10 IOB10 
IOA10 
IOC9 
IOB9 
IOA9 
IOF8 
IOE8 IOD8 
IOC8 
IOB8 IOA8 
IOE7 
IOD7 
IOC7 IOB7 
IOA7 
IOF6 
IOE6 
IOD6 
IOF7 
IOC6 
IOB6 
IOA6 
IOF5 
IOE5 IOD5 
IOC5 
IOB5 IOA5 
IOC4 IOB4 
IOA4 
IOD4 
IOF4 IOE4 
IOF3 
IOE3 
IOD3 IOC3 
IOB3 
IOA3 
IOF2 
IOE2 IOD2 
IOC2 
IOB2 IOA2 
IOF1 IOE1 
IOD1 
IOC1 IOB1 
IOA1 
TP FAB1 CHANGE CONNECTION 0318 
TP FAB1 CHANGE CONNECTION 0318 
TP FAB1 CHANGE CONNECTION 0318 
PVCCIOMCP_CPU1 & P1V8_MCP_CPU1: 0XC8 
PVCCMCP_CPU1: 0X03(BUS #1) 
PVCCIOMCP_CPU1:0X04(BUS #2) 
P1V8_MCP_CPU1: 0X05(BUS #2) 
PVCCMCP_CPU1: 0XB8 
SVID ADDRESS 
MCP CPU1 VRM 
SCONN120_H61426002 SCONN120_H61426002 
WIWYNN CORPORATION 
DEBUG ONLY 



FM_CPU0_VRM_322M_156M_OSC_EN 
PVCCIOMCP_CPU0 
PVCCMCP_CPU0 
PVCCMCP_CPU0 
PVCCMCP_CPU0 PVCCIOMCP_CPU0 
P1V8_MCP_CPU0 
P1V8_MCP_CPU0 
P1V8_MCP_CPU0 
PVCCMCP_CPU0 
PVCCIOMCP_CPU0 
ALUM CLK_322M_156M_CPU0_OSC_VRM_DN 
VSENSE_P1V8MCP_CPU0_SKT_VSEN 
0402 
G21796-082 
VR_PVCCIOMCP_CPU0_XADDR1 E10 
F10 
H61426-002 
VR_PVCCMCP_CPU0_XADDR2 
B10 
CHIP 
0402 
FM_P1V8MCP_CPU0_EN 
PWRGD_P1V8MCP_CPU0 
VSENSE_PVCCMCP_CPU0_SKT_VRTN 
PWRGD_PVCCIOMCP_CPU0 
FM_PVCCIOMCP_CPU0_EN 
SVID_ALERT0_CPU0_R_N 
CLK_322M_156M_CPU0_OSC_VRM_DP 
VSENSE_PVCCMCP_CPU0_SKT_VSEN 
VSENSE_P1V8MCP_CPU0_SKT_VRTN 
SMB_VR_STBY_LVC3_SDA 
SVID_CLK0_CPU0_R 
SVID_DIO0_CPU0_R 
VSENSE_PVCCIOMCP_CPU0_SKT_VSEN 
VSENSE_PVCCIOMCP_CPU0_SKT_VRTN 
SMB_VR_STBY_LVC3_SCL 
PWRGD_PVCCMCP_CPU0 
FM_PVCCMCP_CPU0_EN 
SVID_DIO1_CPU0_R 
SVID_CLK1_CPU0_R 
SVID_ALERT1_CPU0_R_N 
10% 
X6S 
1
2
C3M46 
1.0UF 
6.3V 
0402V 
D97712-004 
C4T2 
D97712-004 
1.0UF 
10% 
0402V 
6.3V 
X6S 
1
2
C3N40 
1.0UF 
6.3V 
1
2
10% 
X6S 
D97712-004 
0402V 
J6B1 
CONN 
F20 
F19 
F18 
F17 
F16 
F15 
F12 
F11 
F9 
F8 
F7 
F6 
F5 
F4 
F3 
F2 
F1 
E20 
E19 
E18 
E17 
E12 
E11 
E9 
E8 
E7 
E6 
E5 
E4 
E3 
E2 
E1 
D20 
D19 
D18 
D17 
D13 
D12 
D11 
D10 
D9 
D8 
D7 
D6 
D5 
D4 
D3 
D2 
D1 
C20 
C19 
C18 
C17 
C13 
C12 
C11 
C10 
C9 
C8 
C7 
C6 
C5 
C4 
C3 
C2 
C1 
B20 
B19 
B18 
B17 
B13 
B12 
B11 
B9 
B8 
B7 
B6 
B5 
B4 
B3 
B2 
B1 
A20 
A19 
A18 
A17 
A12 
A11 
A10 
A9 
A8 
A7 
A6 
A5 
A4 
A3 
A2 
A1 
MCP VRM CPU0 
A13 
E13 
F13 
E14 
F14 
A15 
B15 
C15 
A16 
B16 
C16 
D16 
E16 
B14 
C14 
D14 
E15 
D15 
A14 
H61426-002 
F20 
F19 
F18 
F17 
F16 
F14 
F13 
F12 
F11 
F10 
F9 
F8 
F7 
F4 
F2 
F1 
E20 
E19 
E18 
E17 
E16 
E15 
E14 
E13 
E11 
E10 
E9 
E8 
E4 
E1 
D19 
D18 
D16 
D13 
D10 
D9 
D8 
D7 
D4 
D3 
D2 
D1 
C20 
C19 
C18 
C17 
C16 
C15 
C14 
C13 
C12 
C11 
C10 
C9 
C8 
C7 
C4 
C3 
C2 
B20 
B19 
B17 
B16 
B15 
B13 
B12 
B11 
B10 
B9 
B8 
B7 
B4 
B2 
A20 
A19 
A17 
A16 
A15 
A14 
A13 
A12 
A11 
A10 
A9 
A8 
A4 
A2 
A1 
E7 
D17 
A7 
B6 
C6 
D6 
E6 
F6 
A5 
B5 
C5 
D5 
E5 
F5 
A6 
D20 
D12 
F3 
B1 
MCP VRM CPU0 
A3 
E2 
D11 
B3 
C1 
CONN 
J6E1 
E12 
E3 
D15 
F15 
B18 
A18 
D14 
B14 
C3R4 
470UF 
20% 
699013-049 
3018 
2
1 C4R1 
2
1
699013-049 
3018 
ALUM 
20% 
470UF 
C4T1 
D97712-004 
1.0UF 
10% 
0402V 
6.3V 
X6S 
1
2
R3N29 
G21796-317 
16K 
1.0% 
1/16W 
2
1
R7C24 
4.02K 
1% 
CHIP 
1/16W 
2
1
C3T2 
602433-106 
47UF 
20% 
0603V 
4V 
X5R 
1
2
C3T1 
47UF 
20% 
4V 
X5R 
1
2 602433-106 
0603V 
C3N14 
699013-049 
470UF 
ALUM 
2
1
20% 
3018 
104 
104 
22 
191 
191 
39 
190 
190 
201 211 21 
39 
22 
138 
159 193 201 206 211 213 215 218 223 
226 235 
21 201 211 
21 201 211 
39 
39 
138 159 211 213 235 193 201 206 215 
218 223 226 
190 
190 
21 215 218 
21 215 218 
215 218 21 
2.5V 
2.5V 2.5V 
DESIGN NOTE: 
DO NOT SCALE DRAWING SHEET 
B
AA
B
B
SIZE 
SCALE: 
234
1234
DEPARTMENT CODE 
1
DOCUMENT NUMBER REV 
IN 
IN 
IN 
P3V3 
OUT 
OUT 
IN 
IN 
OUT 
BI 
IN 
BI 
IN 
OUT 
PVCCIO_CPU0 
OUT 
IN 
OUT 
OUT 
IN 
IN 
IN 
BI 
P5V_STBY 
P3V3_STBY 
P12V_STBY 
IN 
IN 
194 OF 270 
SMBUS ADDRESS 
IOF19 
IOA20 
IOB20 IOC20 
IOD20 IOE20 IOF20 
IOE19 IOD19 IOC19 IOB19 IOA19 
IOF18 IOE18 IOD18 IOC18 IOB18 IOA18 
IOF17 IOE17 IOD17 IOC17 IOB17 IOA17 
IOF16 IOE16 
IOA14 
IOB14 
IOC14 
IOD14 IOE14 IOF14 
IOA15 
IOB15 IOC15 
IOD15 IOE15 IOF15 
IOA16 
IOB16 IOC16 
IOD16 
IOF13 IOE13 IOD13 IOC13 IOB13 IOA13 
IOF12 IOE12 
IOD12 IOC12 IOB12 IOA12 
IOF11 IOE11 IOD11 IOC11 IOB11 IOA11 
IOF10 
IOF9 IOE9 IOD9 
IOE10 IOD10 IOC10 IOB10 IOA10 
IOC9 IOB9 IOA9 
IOF8 IOE8 IOD8 IOC8 IOB8 IOA8 
IOE7 IOD7 IOC7 IOB7 IOA7 
IOF6 IOE6 IOD6 
IOF7 
IOC6 IOB6 
IOA6 
IOF5 IOE5 IOD5 IOC5 IOB5 IOA5 
IOC4 
IOB4 IOA4 
IOD4 
IOF4 IOE4 
IOF3 IOE3 IOD3 IOC3 IOB3 IOA3 
IOF2 IOE2 
IOD2 IOC2 IOB2 IOA2 
IOF1 IOE1 IOD1 IOC1 IOB1 IOA1 
IOF19 
IOA20 
IOB20 IOC20 
IOD20 IOE20 IOF20 
IOE19 IOD19 IOC19 IOB19 IOA19 
IOF18 IOE18 IOD18 IOC18 IOB18 
IOA18 
IOF17 IOE17 IOD17 IOC17 IOB17 IOA17 
IOF16 IOE16 
IOA14 
IOB14 IOC14 
IOD14 IOE14 IOF14 
IOA15 
IOB15 IOC15 
IOD15 IOE15 IOF15 
IOA16 
IOB16 
IOC16 
IOD16 
IOF13 IOE13 IOD13 IOC13 IOB13 IOA13 
IOF12 IOE12 
IOD12 IOC12 IOB12 IOA12 
IOF11 IOE11 IOD11 IOC11 IOB11 IOA11 
IOF10 
IOF9 IOE9 IOD9 
IOE10 IOD10 IOC10 IOB10 IOA10 
IOC9 IOB9 IOA9 
IOF8 IOE8 IOD8 IOC8 IOB8 
IOA8 
IOE7 IOD7 IOC7 IOB7 IOA7 
IOF6 IOE6 IOD6 
IOF7 
IOC6 
IOB6 IOA6 
IOF5 IOE5 IOD5 IOC5 IOB5 IOA5 
IOC4 IOB4 IOA4 
IOD4 
IOF4 IOE4 
IOF3 IOE3 IOD3 IOC3 IOB3 IOA3 
IOF2 IOE2 
IOD2 IOC2 IOB2 IOA2 
IOF1 IOE1 IOD1 IOC1 IOB1 IOA1 
TP FAB1 CHANGE CONNECTION 0318 
TP FAB1 CHANGE CONNECTION 0318 
TP FAB1 CHANGE CONNECTION 0318 
PVCCIOMCP_CPU0 & P1V8_MCP_CPU0: 0XC4 
PVCCMCP_CPU0: 0X98 
SVID ADDRESS 
PVCCMCP_CPU0: 0X03(BUS #1) 
PVCCIOMCP_CPU0:0X04(BUS #2) 
P1V8_MCP_CPU0: 0X05(BUS #2) 
MCP CPU0 VRM Wed Feb 08 16:35:22 2017 
SCONN120_H61426002 SCONN120_H61426002 
WIWYNN CORPORATION 
DEBUG ONLY



4_3 
4_2 
4_1 
1_3 
1_2 
1_1 
NP1 
3_3 
3_2 
3_1 
2_3 
2_2 
2_1 
4_3 
4_2 
4_1 
1_3 
1_2 
1_1 
NP1 
3_3 
3_2 
3_1 
2_3 
2_2 
2_1 
MTG_KEYHOLE MTG_KEYHOLE MTG_KEYHOLE 
MTG_KEYHOLE MTG_KEYHOLE 
MTG_KEYHOLE 
MTG_KEYHOLE 
TH4A1 
4040LF 
C9M3 
68UF 
20% 
16V 724613-112 
3018 
TANT 
C3T6 
68UF 
724613-112 
TANT 
20% 
3018 
16V 
724613-112 
20% 
C4B14 
68UF 
TANT 
16V 
3018 
C4F5 
68UF 
20% 
724613-112 
TANT 
16V 
3018 
ALUM 
4040LF 
20% 
470UF 
A93539-036 
C1F7 
2
1
16V ALUM 
A93539-036 
C1B14 
470UF 
20% 
4040LF 
16V 
2
1
C4B13 
A93539-036 
470UF 
20% 
4040LF 
16V 
ALUM 
2
1C4F6 
A93539-036 
470UF 
20% 
16V 
ALUM 
2
1
TH7G1 
EMPTY 
1
NA 
TH7A1 
1
NA 
EMPTY 
1
NA 
EMPTY 
1
TH1A1 
EMPTY 
NA 
EMPTY 
TH9A1 
1
NA 
TH9G1 
1
NA 
EMPTY 
NA 
EMPTY 
1
TH4G1 
0402V 
C1E16 
0.1UF 
10% 
16V 
X7R 
1
2 A36096-030 
0402V 
2 X7R 
1
10% 
0.1UF 
C1E17 
A36096-030 
16V 
X7R 2
1 C9R6 
10% 
16V 
0.1UF 
0402V 
A36096-030 2
1
0402V 
A36096-030 
X7R 
10% 
16V 
0.1UF 
C9R12 
C95333-007 
0805 
2 X6S 
16V 
10% 
10UF 
1 C1E15 
16V 
2 X6S 
1 C1E12 
10UF 
10% 
0805 
C95333-007 
C9R5 
X6S 
0805 
2
1 10UF 
10% 
C95333-007 
16V 
1
2
3
RM1E1 
CONN 
G98259-001 
STFT363B238R224H453-GP 
RM1G1 
J1D1 
FCI-CONN12-2R-GP 
J1E1 
FCI-CONN12-2R-GP 
C3T3 
724613-112 
TANT 
16V 
20% 
68UF 
3018 
C4F4 
68UF 
724613-112 
TANT 
16V 
20% 
3018 
C9T3 
68UF 
20% 
16V 
TANT 
3018 
724613-112 
C6N5 
68UF 
20% 
TANT 
16V 
3018 
724613-112 
C7M6 
68UF 
724613-112 
20% 
3018 
16V 
TANT 16V 
20% 
TANT 
68UF 
724613-112 
C3T15 
3018 
C4M7 
20% 
68UF 
724613-112 
TANT 
16V 
3018 
20% 
16V 
TANT 
724613-112 
3018 
C3T13 
68UF 
C1M5 
68UF 
20% 
16V 724613-112 
TANT 
3018 
724613-112 
C4M6 
68UF 
20% 
TANT 
3018 
16V 
C1R23 
68UF 
20% 
16V 
TANT 
3018 
724613-112 
C3B6 
68UF 
20% 
16V 724613-112 
TANT 
3018 
NOPOP NOPOP NOPOP NOPOP NOPOP NOPOP NOPOP 
1
2
1
2
1
2
1
2
1
2_1 
2_2 
2_3 
3_1 
3_2 
1_1 
1_2 
1_3 
4_1 
4_2 
4_3 3_3 
NP1 NP1 
3_3 4_3 
4_2 
4_1 
1_3 
1_2 
1_1 
3_2 
3_1 
2_3 
2_2 
2_1 
2
1
2
1
2
1
2
1 1
2 2
1
2
1
2
1
2
1
2
1
2
1
2
1
DO NOT SCALE DRAWING SHEET 
B
AA
B
B
SIZE 
SCALE: 
234
1234
DEPARTMENT CODE 
1
DOCUMENT NUMBER REV 
P12V_STBY 
P12V_STBY 
P12V_PSU P12V_PSU 
P12V_PSU 
P12V_PSU P12V_PSU 
P12V_STBY 
111
1 1
1
1
195 OF 270 
Wed Feb 08 16:35:22 2017 
CONN3 
IO3 
IO2 
IO1 
TP FAB1 CHANGE SYMBOL 0302 
ROOM: HOT_SWAP 
BOM_COST=TEST_MFG 
POP J1E1 (AIR MAX CONNECTOR) 1218 
ROOM=MOUNTING_HOLES 
NOPOP J1D1 (PRESSFIT CABLE) 1218 
ROOM: HOT_SWAP 
TP FAB1 NOPOP CAPS 0412 
TP FAB1 CHANGE SYMBOL 0316 
NOPOP 
MOUNTING HOLES + POWER INPUT CONNECTOR 
BULK CAPS TO SUPPORT FAST PROCHOT 
GUIDE PIN 
POWER CONN: 40A MAX POWER CONN: 40AMAX 
WIWYNN CORPORATION 



COIN TYPE BATTERY 
BATTERY 
R2U43 
1% 
PWRGD_P3V3_STBY 
CHIP 
A_PG_P12V_MAIN 
PWRGD_P12V_HSC 
1/16W 
R8D38 
1% 
1
0402 
2
R8D40 
G21796-040 
0402 
1
1/16W 
CHIP 2
4
1/16W 
0402V 
R8D39 
49.9K 
1% 
2
0402 A_PG_P5V 
A36096-030 
G21796-016 
1% 
10.0K 
1
R2P21 
R2P18 
PWRGD_P12V_MAIN_R 
CHIP 
D97712-004 
X6S 
H46130-001 
25V 
PWRGD_P3V3_R1 
PWRGD_P5V_N 
PWRGD_P12V_HSC_DLY_R 
PWRGD_P5V_R 
A_ADM1085_CEXT 
A_P3V_BAT_R 
P3V_BAT_SOURCE 
VSENSE_P12V_ADM1085 
PLACE 1UF CLOSE TO DIODE 
NEAR BATTERY HOLDER 
A36096-030 
C8E3 
0.1UF 
10% 
0402V 
16V 
X7R 2
1 PWRGD_P12V_HSC_DLY 
0402 1/16W 
1
R8E7 
22.1 
CHIP 
1.0% 
2
G21796-250 
U8E2 
IC 
3
2
D23047-001 
GND=GND; 
PWRGD_DSW_PWROK 
0402V 
A36096-030 
C1L16 
0.1UF 
10% 
16V 
X7R 
U1L3 
IC 
D23047-001 
2
GND=GND; 
3
0402 
G21796-146 
1/16W 
1% 
6.34K 
R3P51 
1
2
G21796-058 
R3P48 
90.9K 
1% 
CHIP 
1/16W 
0402 
1
2
A36096-030 
C3P46 
0.1UF 
10% 
16V 
X7R 
1
2
0402V 
G21796-016 
R3P50 
EMPTY 
10.0K 
1/16W 
1% 
0402 
1
2
1 4
5
2
U7D3 
IC 
6
3
G21796-047 
0402 
1% 
CHIP 
2
R1L16 
1
49.9 
1/16W 
CHIP 
1% 
G21796-017 
R2P20 
0402 
2
100.0 
1/16W 
1
PWRGD_P3V3 
PWRGD_P5V 
A36096-090 
C3P45 
0.047UF 1
10% 
0402 
X7R 2
G21796-072 
1/16W 
4.75K 
1% 
R3P44 
1
2 CHIP 
0402 
3
C90169-001 
BAS70-05 
SMLF 
DIO 
CR2U1 
1
2
XBT8G1 
3PVERT 
1
2
C68619-005 
3
BT8G1 
202168-001 
0402 
G21796-026 
CHIP 
2
1.00K 1% 
1/16W 
1
C79254-001 
2N7002 
Q1P2 
FET 
C73510-001 
2
IC 
SMLF 
BAT54WS 
CR8E1 
1
G21796-016 
10.0K 
CHIP 
1/16W 
2
0402 
1
0402 
CHIP 
1/16W 
2
1/16W 
CHIP 
1% 
10.0K 
R8D41 
1
2
G21796-016 
0402 
1/16W 
0402 
G21796-072 
R8D37 
4.75K 1
CHIP 
1% 
2
G21796-048 
1
CHIP 
PWRGD_P12V_MAIN 
0402 
G21796-017 
R8D42 
2
1% 
CHIP 
100.0 
1/16W 
1
0.1UF 
10% 
C8D4 
16V 
X7R 
H69492-001 
U8D8 
6
1
5
IC 
2
3
C73510-001 
2
CR7E1 
1
IC 
BAT54WS 
SMLF 
C2U26 
1.0UF 
0402V 
6.3V 
10% 
1
2
20.0K 
1% 
TP FAB3-DVT CHANGE R8D40 FROM 3.74K TO 20K 20161208
TP FAB3-DVT CHANGE R3D38 FROM 100K TO 511K 20161208
240 101 189 191 237 
239 
169 
181 241 248
200 118 157 
191 247 
175 190 248 
190 
191 
CONFIG=64.51135.6DL 
NEW_VALUE=511K 
S
D
G
TPS3700 
DESIGN NOTE: 
CAD NOTE: 
DESIGN NOTE: 
RESET_N 
RESET_N 
1
2
DO NOT SCALE DRAWING SHEET 
B
AA
B
B
SIZE 
SCALE: 
234
1234
DEPARTMENT CODE 
1
DOCUMENT NUMBER REV 
IN 
P3V3_RTC_STBY 
IN 
OUT 
ADM809 
VCC 
OUT 
P3V3 ADM809 
VCC 
P3V3_STBY 
OUT 
OUT 
P3V3_STBY 
P12V_STBY P3V3_STBY P3V3_STBY 
OUT 
P3V3_STBY 
P3V3_STBY 
P3V3_STBY 
P12V 
P5V 
P3V3_STBY 
OUT 
196 OF 270 
Wed Feb 08 16:35:22 2017 
1
ENIN ENOUT 
GND CEXT 
VIN VCC 
VDD 
OUTB 
OUTA 
INBN 
INAP 
GND P12V < 10.47 PWRGD_P12V_MAIN DEASSERT P12V >= 10.62 PWRGD_P12V_MAIN ASSERT 
P5V >= 4.539V (4.687V~4.372V): PWRGD_5V ASSERT 
ROOM = V_SUPER 
ADM809S (2.93V TYPICAL) USED IN THESE 2 LOCATIONS. 
TARGET POWER ON DELAY IS 225MS 
NOMINAL TRIP POINT IS 8.972V (8.204V~9.767V) 
FOR ADM1085: 
BATTERY CIRCUIT/VOLTAGE SUPERVISORS 
ADM1085 
WIWYNN CORPORATION 



CHIP 
PWRGD_PVDDQ_ABC_N 
1% 1W CHIP 1206 
G52199-004 
2
R4B12 
COG 
A36095-025 
0402LF 
G52199-004 
CHIP 
R12W13 
4D02R2F-GP 
R12W6 R12W7 
R12W12 R12W11 
BSL308C-H6327-GP 
4D02R2F-GP 
R12W1 
VR_PVDDQ_ABC_AIINSEN 
VR_PVDDQ_ABC_VINSEN 
R12W5 
665KR2B-GP 1
C12W1 
47.0PF 
50V 0402LF 
COG 
A36095-025 
R12W10 
665KR2B-GP 
1
2
Q12W2 
BSL308C-H6327-GP 
COG 
A36095-025 
2
0402LF 
C12W2 
47.0PF 
50V 
5% 
1
PWRGD_PVDDQ_DEF_N 
5% 
G22026-050 
0603 
PWRGD_PVDDQ_KLM_N 
10UF 
C9U11 
10% 
R12W4 
1
100.0K 1
G22026-050 
CHIP 2 CHIP 
VR_PVDDQ_DEF_VINSEN 
VR_PVDDQ_DEF_AIINSEN VR_PVDDQ_KLM_AIINSEN 
0805 
G10601-001 
C4A17 
10UF 
10% 
16V 
X7R 
2
1
10% 
0805 
16V 
2
1 10UF 
C6U10 
X7R 
C4A4 
10UF 
0805 
G10601-001 
10% 
16V 
X7R 2
1
X7R 
C4B11 
10UF 
16V 
1
2
0805 
G10601-001 
1
X7R 
16V 
10UF 
C1A16 
G10601-001 
0805 
2
G10601-001 
1 10UF 
16V 
C1B7 
2
0805 
10% 
X7R 
C6T2 
16V 
X7R 2
1 10UF 
0805 
10% 
16V 
X7R 
0805 
C6U18 
2
10UF 1
G10601-001 
C9U8 
10UF 
16V 
X7R 
G10601-001 
0805 
2
1
16V 
X7R 2
10% 
1
0805 
G10601-001 
C1A4 
2 X7R 
1
16V 
10% 
10UF 
0805 
G10601-001 
16V 
2
1 C9T8 
10UF 
10% 
X7R 
G10601-001 
0805 
1% 
1/10W 
R12W14 
1
2
1% 
100.0K 
1/10W 
CHIP 
G22026-050 
0603 
1
2
R12W19 
1% 
BSL308C-H6327-GP 
2
PWRGD_PVDDQ_GHJ_N 
BSL308C-H6327-GP 
PWRGD_PVDDQ_GHJ 
1
CHIP 2
1/10W 
R12W9 
10% 
PWRGD_PVDDQ_DEF 
1/10W 
2
4D02R2F-GP 
1% 
100.0K 
21
5% 
C12W3 
Q12W3 
0603 
G10601-001 
100.0K 
VR_PVDDQ_KLM_VINSEN 
PWRGD_PVDDQ_KLM 
COG 
A36095-025 
0402LF 
47.0PF 
50V 
5% 
1 2
R12W20 
665KR2B-GP 
C12W4 
Q12W4 
R12W3 
R12W8 
4D02R2F-GP 
VR_PVDDQ_GHJ_VINSEN 
R12W16 R12W17 
10% 
G10601-001 
10% 
VR_PVDDQ_GHJ_AIINSEN 
R12W15 
R4F2 
R12W2 
50V 
47.0PF 
0603 
G22026-050 Q12W1 
2
G52199-004 
1206 1% 1W 
R1F3 
1
1206 1W 1% 
665KR2B-GP 
1
R12W18 
G52199-004 
R9M4 
1206 CHIP 1W 1% 
D
S
D
G
S
G
D
S
D
G
S
G
D
S
D
G
S
G
D
S
D
G
S
G
TP FAB3-DVT CHANGE R9M4 TO 0.004OHM RES 20161121 TP FAB3-DVT CHANGE R4B12 TO 0.004OHM RES 20161121 
TP FAB3-DVT CHANGE R1F3 TO 0.004OHM RES 20161121 TP FAB3-DVT CHANGE R4F2 TO 0.004OHM RES 20161121 
TP FAB1 CHANGE RES TO 064.6653F.M001 0318 
TP FAB1 CHANGE PACKAGE SIZE TO 0805 
TP FAB3 CHANGE RES TO 100K OHM 0901 
TP FAB1 CHANGE RES TO 064.6653F.M001 0318 
TP FAB1 CHANGE PACKAGE SIZE TO 0805 
TP FAB3 CHANGE RES TO 100K OHM 0901 
TP FAB1 CHANGE RES TO 064.6653F.M001 0318 
TP FAB1 CHANGE PACKAGE SIZE TO 0805 
TP FAB3 CHANGE RES TO 100K OHM 0901 
TP FAB1 CHANGE PACKAGE SIZE TO 0805 
TP FAB3 CHANGE RES TO 100K OHM 0901 
TP FAB1 CHANGE RES TO 064.6653F.M001 0318 
215 
215 
215 
218 
218 226 
223 
218 
226 
226 
223 
223 
NEW_VALUE=0.004 OHM 
1% 
0402 
NEW_VALUE=0.004 OHM 
CONFIG=064.1003F.M001 
PWRGD_PVDDQ_ABC 
CONFIG=064.R0045.0711 CONFIG=064.R0045.0711 
NEW_VALUE=0.004 OHM 
AT0805 
0.1% 
1/16W 
CONFIG=064.R0045.0711 
NEW_VALUE=0.004 OHM 
4.02OHM 
1/16W 
CONFIG=064.1003F.M001 
NEW_VALUE=100K OHMNEW_VALUE=100K OHM 
CONFIG=064.1003F.M001 
CONFIG=064.R0045.0711 
1/8W 
AT0805 AT0805 
1/8W 
0.1% 0.1% 
AT0805 
1/8W 
0.1% 
CONFIG=064.1003F.M001 
NEW_VALUE=100K OHM 
1/8W 
0.1% 
NEW_VALUE=100K OHM 
CONFIG=064.1003F.M001 
AT0805 
1/8W 
0.1% 
AT0805 
1/8W 
0.1% 0.1% 
1/8W 
AT0805 
NOPOP 
665KOHM 
P12V_NVDIMM_DEF_D 
1/16W 
NOPOP 
665KOHM 1/16W 
0402 
0.1% 
0402 
1/16W 
NOPOP 
P12V_NVDIMM_GHJ_D 
0402 
0.1% 
1/16W 
NOPOP 
665KOHM 
4.02OHM 1% 
0402 
0.1% 
1/16W 
1% 
NEW_VALUE=100K OHM 
CONFIG=064.1003F.M001 
NEW_VALUE=100K OHM 
CONFIG=064.1003F.M001 
P12V_NVDIMM_KLM_D 
NEW_VALUE=100K OHM 
CONFIG=064.1003F.M001 
1% 
0402 
0.1% 
1/8W 
AT0805 
NEW_VALUE=100K OHM 
1/16W 
4.02OHM 
P12V_NVDIMM_ABC_D 
4.02OHM 
0402 
665KOHM 
0402 
CAD NOTE: 
OTHERWISE PICK A VALUE > R1 
R12W20: 
DNP IF LIN < 19A 
OTHERWISE PICK A VALUE > R1 
BASED ON IIN LEVEL, 1%, 0402 BASED ON IIN LEVEL, 1%, 0402 
DNP IF LIN < 19A 
R12W10: 
BASED ON IIN LEVEL, 1%, 0402 
OTHERWISE PICK A VALUE > R1 
DNP IF LIN < 19A 
R12W5: 
DNP IF LIN < 19A 
R12W15: 
BASED ON IIN LEVEL, 1%, 0402 
OTHERWISE PICK A VALUE > R1 
1
2
2
21
4
2
21
1
43
2
1
1
5
3 4
6
5
43
6
5
1 2
2
2
1
5
6
1
21
1
2 1
6
3
2
DO NOT SCALE DRAWING 
PLACE AT THE CENTER OF EACH DIMM CHANNEL. CLOSE TO THE 12V PINS OF NVDIMM CONNECTOR 
SHEET 
B
AA
B
B
SIZE 
SCALE: 
234
1234
DEPARTMENT CODE 
1
DOCUMENT NUMBER REV 
P12V_NVDIMM_ABC 
P12V_NVDIMM_ABC P12V_STBY 
P12V_NVDIMM_DEF 
P12V_NVDIMM_DEF 
P12V_NVDIMM_ABC 
P12V_NVDIMM_ABC 
P12V_NVDIMM_DEF 
P12V_NVDIMM_KLM 
P12V_NVDIMM_KLM 
P12V_NVDIMM_GHJ 
P12V_NVDIMM_GHJ 
P12V_NVDIMM_KLM P12V_NVDIMM_GHJ 
P12V_NVDIMM_GHJ P12V_STBY 
OUT 
IN 
OUT 
P12V_NVDIMM_KLM 
IN 
OUT 
OUT 
P12V_STBY 
OUT 
IN 
P12V_NVDIMM_DEF 
OUT 
P12V_STBY 
IN 
OUT 
OUT 
2 1
2 1
2 1
2 1
2 1
2 1
2 1
2 1
197 OF 270 
Wed Feb 08 16:35:23 2017 
TP FAB1 CHANGE TO INFX RECOMMENDED CIRCUIT 0122 
POWER MISC: RAPL RESISTOR 
BOM_COST=PVDDQ_KLM_VR 
ROOM=PVDDQ_KLM_PWR_VR 
BOM_COST=PVDDQ_DEF_VR 
ROOM=PVDDQ_DEF_PWR_VR 
ROOM=PVDDQ_GHJ_PWR_VR 
BOM_COST=PVDDQ_GHJ_VR 
ROOM=PVDDQ_ABC_PWR_VR 
BOM_COST=PVDDQ_ABC_VR 
RAPL RESISTOR CH ABC 
RAPL RESISTOR CH KLM 
RAPL RESISTOR CH GHJ 
RAPL RESISTOR CH DEF 
WIWYNN CORPORATION 



G56246-001 
C95333-007 
A36096-030 
0.1UF 
A36096-030 C95333-007 
FM_P3V3_CPLD_EN 
TP_SLG55021_P3V3_8 
P3V3_SWITCH_G 
FM_ENABLE_FAN_POWER 
TP_SLG55021_P12V_FAN_8 
P12V_FAN_SWITCH_G 
P5V_SWITCH_G 
P12V_SWITCH_G 
TP_SLG55021_P12V_MAIN_8 
FM_P12V_MAIN_SW_EN 
FM_CTNR_PS_ON 
TP_SLG55021_P5V_8 
BSZ019N03LS 
Q7E7 
5
G26762-001 
NFET 
1
4
BSZ019N03LS 
NFET 
G26762-001 
1
Q8B1 
5
4
5
G26762-001 
BSZ019N03LS 
Q1B1 
NFET 
1
4
G26762-001 
BSZ019N03LS 
5
Q8G1 
NFET 
4
1
G21796-010 
2
0402 
100.0K 
1/16W 
1% 
R8B4 
1
CHIP 
0402 
4.75K 
R8E12 
1% 
G21796-072 
EMPTY 
1/16W 
0.1UF 
16V 
10% 
X7R 
A36096-030 
C9M9 1
2
0402V 
C95333-007 
X6S 2
C9M10 
0805 
10UF 
10% 
16V 
1
EU9M1 
IC 
5
7
8
6
9
4
G56246-001 
2
1
3
C9M6 
0.1UF 
X7R 
16V 
10% 
1
2 A36096-030 
0402V 
C1B19 1 0.1UF 
10% 
0402V 
16V 
X7R 2
C1B18 
C95333-007 
10UF 
0805 
1
10% 
16V 
X6S 2
C95333-007 
C7E6 1 10UF 
0805 
10% 
16V 
X6S 2 A36096-030 
0.1UF 
0402V 
C7E5 1
10% 
16V 
X7R 2
C95333-007 
C7E8 1 10UF 
10% 
0805 
16V 
X6S 
2
C7E9 
A36096-030 
0.1UF 
10% 
16V 
X7R 
1
2
0402V 
C2U2 
10UF 
10% 
16V 
X6S 
1
2
0805 
C2U19 
0.1UF 
10% 
16V 
X7R 
1
2
0402V 
10% 
X6S 
C95333-007 
1 C2U1 
16V 
10UF 
2
0805 
X7R 
A36096-030 
0.1UF 
C2T36 1
16V 
10% 
2
0402V 
C8B7 
A36096-030 
0.1UF 
10% 
16V 
X7R 
1
2
0402V 
1 C8B6 
10UF 
10% 
0805 
16V 
X6S 
2
C95333-007 
X6S 
0805 
C8B12 
10UF 
10% 
16V 
1
2
C8B5 
A36096-030 
0.1UF 
10% 
0402V 
16V 
X7R 
1
2
C8E19 
0.1UF 
A36096-030 
X7R 
16V 
10% 
1
2
0402V 
C8B8 
0402V 
16V 
10% 
A36096-030 
1
X7R 2
C8F17 
0.1UF 
10% 
16V 
X7R 
1
2
A36096-030 
0402V 
2
G56246-001 
EU7E1 
IC 
9
6
8
4
7
5
1
3
8
EU8B1 
IC 
5
9
7
6
4
2
1
3
EU2T1 
IC 
5
8
7
4
9
6
G56246-001 
2
3
1
191 
161 181 191 
181 161 191 
G
S
D
G
S
D
G
S
D
G
S
D
2
1
DO NOT SCALE DRAWING SHEET 
B
AA
B
B
SIZE 
SCALE: 
234
1234
DEPARTMENT CODE 
1
DOCUMENT NUMBER REV 
P5V_STBY 
P3V3_STBY 
P12V_FAN 
P12V_STBY 
P3V3 
P5V_STBY 
IN 
P3V3_STBY 
IN 
IN 
IN 
P12V_STBY 
P12V 
P5V 
P5V_STBY 
P5V_STBY 
P5V_STBY 
198 OF 270 
Wed Feb 08 16:35:23 2017 
SLG55021 
PG 
GS
D
SHDN_N 
ON 
VCC 
THPAD GND 
SLG55021 
PG 
GS
D
SHDN_N 
ON 
VCC 
THPAD GND 
SLG55021 
PG 
GS
D
SHDN_N 
ON 
VCC 
THPAD GND 
SLG55021 
PG 
GS
D
SHDN_N 
ON 
VCC 
THPAD GND 
ROOM=P5V_PWR_SWITCH 
ROOM=P12V_FAN_PWR_SWITCH 
ROOM=P3V3_PWR_SWITCH 
BOM_COST=PWR_SWITCH 
ROOM=P12V_PWR_SWITCH 
POWER SWITCHES WIWYNN CORPORATION 



IC 
1/16W 
1% 
1
2
G21796-010 
0402 
R1D39 
100.0K 
1/16W 
1% 
1100.0K 1
0402 
R1D32 
X7R 
0402 
G21796-317 
1/16W 
40.2K 
R1D40 
3
Q1D1 
2 CHIP 
AGND_HSC 
R1D34 
16K 
A_HSC_LOW_EN 
A_HSC_HIGH_EN 
0402 
D24280-001 
2N7002DW 
FET 
1
CHIP 
1.0% 
2
G21796-007 
CHIP 
D24280-001 
FET 
2N7002DW 
CLX-CONN3A-1-GP 
2
J1B4 
1
1% 
G21796-089 
0402 
CHIP 
AGND_HSC 
0.0 
R1D24 
A_HSC_TIMER 
1.0UF 
R1D25 
R9P16 
A36096-030 0402 
1/16W 
EMPTY 
X7R G21796-220 
0402V 
C1D11 
0.1UF 
AGND_HSC 
1
X7R 2
0402V 
A36096-030 
1/16W 
1% 
1
0402 
G21796-072 
CHIP 
16V 
R9P24 
0402 
0603LF 
A_HSC_TEMP 
1% 
1
603269-064 
C9P14 
50V 
2 X7R 
0.033UF 
10% 
0402 
G21796-017 
0402 
15.0K 
G21497-005 
TP_HSC_MDAT 
TP_HSC_MCLK 
IRQ_SML1_PMBUS_ALERT_N 
A_HSC_HIGH_EN 
IRQ_HSC_FAULT_N 
A_HSC_GATE 
PWRGD_P12V_HSC 
A_HSC_LOW_GATE 
A_HSC_VOUT 
A_HSC_CSOUT 
IRQ_SML1_PMBUS_ALERT_R_N 
TP_HSC_ALERT2_N 
A_HSC_MON 
A_HSC_MOP 
A_HSC_HSN 
IRQ_SML1_PMBUS_ALERT_R_N 
SMB_3V3SB_HSC_SDA_R 
SMB_3V3SB_HSC_SCL_R 
PD_HSC_RETRY_N 
PWRGD_P12V_R 
IRQ_HSC_FAULT_R_N 
A_HSC_ISTART 
2
CHIP 2
R1D43 
1
0402 
G21796-010 
CHIP 
1/16W 
1% 
100.0K 1
R1D11 
1/16W 
CHIP 
G21796-010 
R1D18 
1
0402 
2
1% 
100.0K 
2
2
5
4
1
2X7R 
C1D27 
0402V 
A36096-030
EMPTY 
10% 
0.1UF 
C9P12 
2
1
0402 
G21796-026
CHIP 
1/16W 
1% 
1.00K 
2
1
C52245-001
IC 
MMBT3904
Q1D3 
2
1
3
SM 
12.1K 
1/16W 
1
2
0402 
CHIP 
1% 
2
0402 
CHIP 
1/16W 
1% 
6.19K R1D31 
G21796-161 
2
1
G21796-107 
2CHIP 
1/16W 
R9P18 
1
0402 
2
1
2
1
1.0UF 1
10% 
16V 
2
1/16W CHIP 5% 
1 2
0.0 
1 2
1% 
100.0 
R1D28 
EMPTY 
1/16W 
2
1
1% 
10.0 1
R9P30 
CHIP 
1/10W 
2
0.0 
1/8W 
0805 
5% 
CHIP 
1
G22179-004 
R1D41 
2
1% 
G21796-058 
0402 
R9P28 
2
1
CHIP 
90.9K 
21
0402 5% 0.0 
R1W21 
G21497-005 
0402 
R1W20 
0.0 
1 2
5% 
X7R 
10% 
A36096-046 2
1C1W16 
0402LF 
50V 
1000PF 
2N7002 
Q1W5 
1
3
FET 
2 C79254-001 
R1D42 
CHIP 
1/16W 
2
1% 
1
A36096-030 
0402V 
X7R 
10% 
16V 
0.1UF 
2
1
G21796-010 
CHIP 
1/16W 
R9P29 
100.0K 
1% 
1
2
D97712-011 
C1D19 
X6S 
10% 
0402 
16V 
1
2
0402 1/16W 
1
1% 
G21796-074 
2
33.2 
CHIP 
R1D30 
CHIP 1/16W 
33.2 
1
R1D26 
1% 
2
G21796-074 
0402 
G21796-074 
1/16W CHIP 
1% 
2
0402 
R1D33 
1
33.2 
C1D26 1
1 1% 
1
2
12 
5
30 
28 
G99251-001 
29 
26 
25 
21 
9
6
8
15 
16 
17 
4
1
32 
31 
2
IC 
33 
24 
22 
19 
11 
20 
13 
14 
10 
AGND_HSC 
AGND_HSC 
AGND_HSC 
AGND_HSC 
AGND_HSC 
AGND_HSC 
AGND_HSC 
AGND_HSC 
1
0402 
2
1
FM_P12V_HSC_ADR2 
2
2
1% 
G21796-177 X6S 10% 
16V 
0.1UF 1/16W 
1% 
7.5K 
R1D29 
1% 
150.0K 
0402 
CHIP 
4.75K 
16V 
7FM_P12V_HSC_ADR1 
10% 
16V 
R1D36 
27 
R1D27 
4.75K 
10% 
CHIP 
AGND_HSC 
0402 A36096-030 
0402V 
G21796-072 
1/16W 
5% 
0.0 
G21497-005 
SMB_BMC_PMBUS_STBY_LVC3_SCL 
SMB_BMC_PMBUS_STBY_LVC3_SDA 
A_HSC_PWGIN 
G21796-010 
1/16W 
100.0K 
R9P23 
FM_P12V_HOTSWAP0_EN 
1/16W 
1% 
0402 
A_HSC_HSP 
AGND_HSC 
23 
18 
100.0K 
G21796-010 
G21796-010 
CHIP 1/16W 0402 1/16W 
R1D16 
69.8K 
1% 
1/16W 
0402V 
Q1D1 
AGND_HSC 
C1D21 
G21796-133 
6
10% 
16V 
0.1UF 
C9P15 
R1D15 
AGND_HSC 
100.0K 
R1D37 
1
0402 
2 CHIP 
1% 
1/16W 
G21796-010 CHIP 2 CHIP 
0.1UF 
AGND_HSC 
G21796-109 
1/16W 
R9P17 
A36096-030 
11K 
AGND_HSC 
TP_HSC_SPISSN 
0402 
G21497-005 
CHIP 
C1D25 
0603 
SM 
EU1D2 
AGND_HSC 
0402 
D97712-011 
3
G22026-041 
1
VR1D1 
A_HSC_VCAP 
A_HSC_ISET 
A_HSC_PSET 
A_HSC_OV 
A_HSC_UV 
P12V_HSC_VCC 
TP FAB3 CHANGE RES FOR DOUBLE SIDE 1006 
TP FAB1 CHANGE RES 0429 
TP FAB3 CHANGE RES FOR DOUBLE SIDE 1006 
TP FAB3 NOPOP R1D29 AND POP R9P17 ON BOTH SS AND DS 0901 
TP FAB3 NOPOP R9P16 ON DS BOM 0901 
TP FAB3 NOPOP R1D29 ON SINGLE SIDE MB AND POP IT ON DOUBLE SIDE MB 0803 
TP FAB3 POP R9P17 ON SINGLE SIDE MB AND NOPOP IT ON DOUBLE SIDE MB 0803 
TP FAB3-DVT CHANGE ZENER DIODE'S REVERSE STAND-OFF VOLTAGE TO 14V. 
200 
120 146 170 
133 119 146 
200 
196 
200 
200 
181 199 
200 
200 
200 
181 199 
138 159 181 247 
138 159 181 247 
181 
200 
NEW_PN=083.01514.00AD 
NOPOP 
TEMP_SENSOR_E 
TEMP_SENSOR_B 
0402 1/16W 5% 
CHIP 
1/16W 
CHIP 
1/16W 
CONFIG=064.7501D.06DD 
BOM_DS=64.68125.6DL BOM_DS=64.57625.6DL 
BOM_DS=NOPOP 
G21497-005 
NEW_VALUE=14V 
199 
S
D
G
S
D
G
S
D
G
CHIP 
0402 
A_HSC_OCP_SEL 
1/16W 
2
A_HSC_ISET_S2 
R1D13 
G21796-058 
A_HSC_ISET_S 
90.9K 1
1% 
DESIGN NOTE: 
DESIGN NOTE: 
DEFAULT 
DEFAULT 47.9A 
40.6A 
77.3A 
70A 
DOUBLE SIDE 
71.5A 
41.4A 
SINGLE SIDE 
PIN 1-2 
PIN 1-2 
PIN 2-3 
78.9A 
FPH OCP 
48.8A 
FPH OCP 
PIN 2-3 
TP FAB1  ADD J1B4 AND DELETE J1B3 0113 
TO BE USED WHEN USING TYCO 
2
D53458-001 EMPTY LOCATION 
3
POWER CONNECTOR 
1
1
2
DO NOT SCALE DRAWING SHEET 
B
AA
B
B
SIZE 
SCALE: 
234
1234
DEPARTMENT CODE 
1
DOCUMENT NUMBER REV 
OUT 
P12V_PSU 
P12V_PSU 
P12V_STBY 
P12V_STBY 
P12V_STBY 
OUT 
OUT 
OUT 
OUT 
OUT 
OUT 
OUT 
IN 
OUT 
OUT 
BI 
IN 
OUT 
IN 
OUT 
199 OF 270 
Wed Feb 08 16:35:23 2017 
VCAP 
UV 
VCC 
OV 
TIMER 
SDA SCL RETRY_N 
PSET ISTART 
ISET 
ADR1 
HSP 
TEMP 
PWRGD 
FAULT_N 
ENABLE 
ADR2 
HSN 
MOP 
MON 
MCLK 
MDAT 
CSOUT 
VOUT 
GATE 
GND 
GPO2_ALERT2_N GPO1_ALERT1_N_CONV 
PGND 
EP 
PWGIN SPISS_N 
PSET: 78W 
ISTART: 9.92A 
THRESHOLD 9.26V 
DS: 0X45 (7 BIT), 0X8A (8BIT) 
STUFF = RETRY MODE 
TIMER: 620US 
EMPTY = LATCH-OFF MODE (DEFAULT) 
TP FAB1 ADD MOS 1231 
LAYOUT NOTE: CLOSE TO Q1D3 
TP FAB1 ADD C1W16, R1W20 AND R1W21 0115 
TP FAB1 CHANGE RES 0422 
SS: 0X11 (7 BIT), 0X22 (8BIT) 
PMBUS ADDRESS : 
UV: P12V_PSU <= 10.091V (9.812V~10.377V) 
OV: P12V_PSU >= 13.12V (12.857V~13.386V) 
HOT SWAP CONTROLLER (1/2) 
ADM1278 
ROOM: HOT_SWAP WIWYNN CORPORATION 



G21796-099 
0.068UF 
A_HSC_CSOUT 
H69492-001 
PWRGD_DSW_PWROK 
2.7K 1
A_P12V_STBY_FP_TRIGGER 
SC22P50V2JN-4GP 
C73510-001 2.7K 
R9P4 
BAT54WS 
2
CR9P2 
G21796-016 
16V 
G21796-010 
A_P12V_STBY_ADR_TRIGGER 
R9P9 
1
G21796-344 
1% 
1
2
0.1UF 
AGND_HSC 
A36096-030 
G21796-016 
0402 
AGND_HSC 
SC22P50V2JN-4GP 
5
AGND_HSC 
C9W2 
1
CHIP 
20% 
IC SMLF 
FM_DISABLE_FAN_N 
1/16W 2
A36096-030 
105.0K 
R1D14 
G21796-016 
0402 
G21796-072 
A79322-001 
AGND_HSC 
0402V 
U1D2 
A_HSC_LOW_GATE 
A_HSC_HSN 
4
3
C9W1 
AGND_HSC 
H69492-001 
A_P12V_STBY_FP_TRIGGER 
R6W3 
FM_OC_DETECT_N 
1/16W 
1% 
IRQ_OC_DETECT_N 
R1D22 
AGND_HSC 0402V 
0402 
6
0402 
G21796-016 
2N7002DW 
FET 
1% 
10.0K 
50V 
CHIP 
AGND_HSC 
AGND_HSC 
AGND_HSC AGND_HSC 
AGND_HSC 
IC SMLF 
1
C73510-001 
CHIP 
A_HSC_GATE1_R 
A_HSC_TIMER_R 
A_HSC_GATE3_R 
A_HSC_TIMER 
A_HSC_GATE2_R 
A_HSC_MOP 
A_HSC_HSP 
UV_HIGH_SET 
IRQ_UV_DETECT_N 
A_HSC_MON 
P12V_MB0_SW 
A_HSC_GATE 
FM_UV_ADR_TRIGGER_N 
A_HSC_C 
A_HSC_LOW 
FM_OC_DETECT_EN_N 
FM_HSC_TIMER_EXP_N 
FM_OC_DETECT_EN 
0402 CHIP 2
1/16W 
R9P20 
CHIP 
1/16W 
G21497-005 
5% 
R9P21 
0.0 1
2
0402 
G21796-016 
EMPTY 
R9P19 
10.0K 
1% 
1/16W 
1
2
0402 
5
3
1
2
G68777-001 
1/16W 
R9R4 
CHIP 
G21796-066 
1% 10.0 0402 
2
15
G68777-001 
3
10.0 1% 
G21796-066 
2
CHIP 
0402 
1
R1E1 
1/16W 
5
3
1
2
G68777-001 
G21796-066 
10.0 
1% 
R1D47 
0402 
CHIP 
1/16W 1/16W 
G21796-066 
0402 
CHIP 
R9P26 
1% 
10.0 
3W 
R1D49 E74391-005 
3
1
0.001 
6
4
5
2
6PAD 
1% CHIP 
3W 
E74391-005 R9R1 
2
6
1% CHIP 
4
5
3
6PAD 
1
0.001 
CHIP 
0402 
10.0 
1% 
R1D46 R9P27 
1/16W 
1% 
CHIP 
0402 
G21796-066 
10.0 
5% 
R1D44 
CHIP 
G21497-005 
0.0 1/16W 0402 
1/16W 
G21497-005 
0402 0.0 CHIP 5% 
R1D45 
0.1UF 
C1D22 
EMPTY 
0402V 
10% 
16V 
A36096-030 
0402V 
C9P16 
16V 
0.1UF 
EMPTY 
10% 
0402V 
A36096-030 2
10% 
C9P17 
16V 
EMPTY 
1 0.1UF 
0402 
2
1
1% 
1/16W G21796-016 
0402 
1% 
10.0K 
R1D10 
CHIP 2
1
1/16W 
R9P33 
1% 
G21796-010 
100.0K 
0402 
CHIP 
1/16W 
R9P12 
4.99K 
1/16W 
1% 
1
G21796-013 
0402 
CHIP 2
1/16W 
G21796-016 
R9P5 
10.0K 
1% 
CHIP 
1
2
BAT54WS 
1
CR9P1 
1% 
G21796-344 
0402 
CHIP 
1
2
1/16W 
0402 
R1D21 
4.75K 
CHIP 2
1% 
1
3
C79254-001 
2N7002 
2
FET 1
Q1D2 
X7R 
10% 
0402V 
A36096-030 
16V 
2
1C9P11 
6
1
IC 
5
H69492-001 
2
3
4
U9P2 
Q9P1 
D24280-001 
5
3
4
2N7002DW 
Q9P1 
D24280-001 
2
6
FET 
1
2
1/16W 
1
0402 
R1D23 
10.0K 
1/16W 
G21796-016 
0402 
CHIP 
1% 
2
1
C1D9 
0.1UF 
10% 
X7R 
16V 
1
2
10% 
0.1UF 
C9P6 1
2
1
R1D12 
10.0K 
1% 
1
CHIP 
1/16W 
2
1
5
2
IC 
4
6
3
U9P1 
IC 
2
10.0K 1
2 CHIP 
X7R 
C1E2 
2
1
1206 
0402 
1/16W 
R1D51 
G21796-066 
2
1% 
1
10.0 
CHIP 
10.0K 
R9P6 
1/16W 
1% 
1
2
1 10.0K 
R9P11 
2
1/16W 
1% 
CHIP 
74HC1G126 
VCC=P3V3_STBY 
GND=GND 
U1D1 
4
1
IC 
X7R 2
0402 
R9P10 
108427-047 
1/16W 
CHIP 
0402 10.0 
1
1% 
R1D48 
2
G21796-066 
G21796-016 
FET 
2N7002 
Q6W1 
A36096-030 
G21796-066 
1/16W 
232KR2F-2-GP 
2
0402 
1/16W 
100.0K 
C79254-001 
0402 
R9P7 
1% 
CHIP 
3.74K 
1% 
1/16W 
CHIP 
G21796-059 
2
270KR2F-GP 
R9P13 
A_HSC_HIGH 
R1D19 
10.0K 
1% 
CHIP 
AGND_HSC 
G21796-016 
0402 
1/16W 
G21796-080 
0402 
CHIP 2
1 200.0K 
R1D20 
1% 
1/16W 
TP FAB3-DVT CHANGE R9P9 FROM 10K TO 3.74K 20161208 
TP FAB3-DVT CHANGE R9P7 FROM 249K TO 100K 20161208 
TP FAB1 CHANGE RES 0422 
TP FAB3 NOPOP CR9P1 1021 
TP FAB1 CHANGE RES 0422 
TP FAB3 CHANGE R1D20 AND R1D14 RES FOR DOUBLE SIDE 1006 
199 
196 118 157 191 247 
161 
199 170 
120 145 
199 
199 
199 
137 146 
120 145
170 
199 
199 
191 
120 126 145 
120 145 170 
BOM_DS=64.15435.6DL 
BOM_DS=64.16935.6DL 
5% 
1% 
270KOHM 
CONFIG=64.1002D.6DL 
22PF 
NOPOP 
BOM_SS=64.16535.6DL 
NOPOP 
0402 
50V 
22PF 
NPO 
NPO 
0402 
NOPOP 
50V 
5% 
0402 
232KOHM 
1/16W 
1% 
BOM_DS=064.0U505.0C71 
BOM_DS=064.0U505.0C71 
G21497-005 
CHIP 
0402 
5% 
1/16W 
R9P15 
0.0 
CONFIG=64.1002D.6DL 
0402 
1/16W 
CONFIG=64.1002D.6DL 
200 
200 
TP FAB1 R9P13 NEED TO CHANGE TO 270K OHM 
UV_HIGH_SET_N 
S
D
G
S
D
G
S
D
G
S
D
G
A_P12V_STBY_FPH_GATE 
A_HSC_INAP 
P12V_HSC_SENP1 
P12V_HSC_SENN1 
P12V_HSC_SENP0 
A_HSC_LOW_DRAIN 
P12V_HSC_SENN0 
IC 
4
EU1E1 
EU9R1 
4
IC IC 
4
EU1E3 
C81983-002 
EMPTY
MBRS340T3G 
SM
1
CR1F5 
2
TPS3700 
TPS3700 
TPS3700 
INAP (LOW OC): 40.6A 
UV_HIGH_SET=0: TRIP = 11V (10.721V~11.319V) 
TP FAB1 ADD ATTRIBUTES 0307 
INBN (HIGH OC): 47.9A (DEFAULT) 
SINGLE SIDE: 
INAP (LOW OC): 70A (DEFAULT) 
DOUBLE SIDE: 
INBN (HIGH OC): 77.3A 
TRIP = 10.218V (9.832V~10.561V) 
INAP (ADR LOW VOLTAGE) 
INBN (FPH LOW VOLTAGE) 
NOTE: GATE VOLTAGE: 24V PK 
OCP LOW TRIP: 41.4A P12V_STBY (12V  STBY TO  THE BOARD) 
P12V_PSU (12V INPUT POWER  FROM EXTERNAL PSU) 
UV_HIGH_SET=1: TRIP = 11.5V (11.158V~11.789V) (DEFAULT) 
1 2
21
DO NOT SCALE DRAWING SHEET 
B
AA
B
B
SIZE 
SCALE: 
234
1234
DEPARTMENT CODE 
1
DOCUMENT NUMBER REV 
IN 
OUT 
P3V3_STBY 
IN 
P12V_STBY 
IN 
P12V_PSU 
IN 
IN 
IN 
IN 
IN 
IN 
OUT 
P12V_STBY 
P3V3_STBY 
P3V3_STBY 
IN 
P3V3_STBY 
P3V3_STBY 
P3V3_STBY 
P12V_STBY 
P3V3_STBY OUT 
P3V3_STBY 
P12V_STBY 
OUT 
OUT 
OUT 
OUT 
P12V_STBY 
2
1 2
1
1 2
200 OF 270 
Wed Feb 08 16:35:23 2017 
VDD 
OUTB 
OUTA 
INBN 
INAP 
GND 
VDD 
OUTB 
OUTA 
INBN 
INAP 
GND 
VDD 
OUTB 
OUTA 
INBN 
INAP 
GND 
GS
D
GS
D
GS
D
TP FAB1 MOVE R6W1 AND R6W2 TO PAGE 137 0308 
LOW VOLTAGE TIGGER CIRCUIT: ADR TRIGGGER 
8.3V (7.989V~8.578V) NOMINAL ON P12V_STBY FAILING 
DSW_PWROK FIRST TRIP POINT 
TP FAB1 CONNECT FROM HOT SWAP 1231 
U1D2 
TP FAB1 ADD UV FPH VOLTAGE THRESHOLD SELECTION 1117
TP FAB1 R6W3 CHANGE TO 232K 1119 
U9P1: 
ROOM: HOT_SWAP 
TP FAB1 POP 0 OHM 1231 
TP FAB1 ADD CAP 1117 
HOT SWAP CONTROLLER (2/2) 
IOUT FAST PROCHOT CIRCUIT 
TRIP: 10.9V 
LOW VOLTAGE TIGGER CIRCUIT: FAST PROCHOT 
WIWYNN CORPORATION 
HSC TIMER 



TP FAB1 CO-LAY WITH FAIRCHILD PARTS 1203 
1/16W 
A36096-030 
SVID_CLK0_CPU0_R 
ISENSE_PVSA_CPU0_IMON 
1/16W R4E6 
0402 
0.1% 
0402 
CHIP 
0.1UF 
0402V 
A36096-030 
X7R 
35 
0.1% 1.0K 
G85996-004 
CHIP 1/16W 
G85996-004 
0.1% RF3 
1/16W CHIP 1/16W 
1.0K RF2 
0402 
CHIP 
VR_PVCCIN_CPU0_AIREF1 
VR_PVCCIN_CPU0_AIREF2 
SC22P50V2JN-4GP SC22P50V2JN-4GP 
CF1 CF4 
SC22P50V2JN-4GP 
CF5 
SC22P50V2JN-4GP 
2
G21796-009 
1/16W 
1/16W 
ISENSE_PVCCIN_CPU0_PH5_IMON 
A36096-050 
31 
23 
1.0K 
G85996-004 
SVID_VCLK_PVCCIN_CPU0 
0402 
0402 
EU4D4 
R4D67 
10402 
2IRQ_PVCCIN_CPU0_VRHOT_LVC3_R_N 
R6P45 
PU_VR_PVCCIN_CPU0_IMON 39 
26 
16 
PWRGD_PVSA_CPU0_R 
SVID_VDIO_PVCCIN_CPU0 
SVID_VALERT_VCCIN_CPU0 
18 
G21497-005 G21796-074 R4D65 
VR_PVCCIN_CPU0_PWM1 
VR_PVCCIN_CPU0_PWM2 
VR_PVSA_CPU0_PWM 
1 1/16W CHIP 
33.2 0402 CHIP 
X6S 
D97712-004 A36096-030 
0402V 
20 
IC 
27 
29 
13 
PU_VR_PVCCIN_CPU0_FLT1_SMBALT_N_IMON 
1
R4D31 
G21796-026 2
1/16W 
11 
VR_PVCCIN_CPU0_VD12 
0.1UF 
G21796-047 
VR_PVCCIN_CPU0_AVINSEN 
SC22P50V2JN-4GP 
C4D17 
H79206-001 
0402 
C4D20 
0402V 
X7R 
10% 
16V 
R4D27 
100.0K 1
1
2
G21796-003 
0402 
1% 
1/16W 
CHIP 
G21796-160 
0402 
R4D32 
1.5K 
1% 
1/16W 
CHIP 
R4E9 
1
47 
1/16W 
G85996-004 
RF1 1.0K 0.1% 
G21796-001 
EMPTY 
0402 
1/16W 
1% 
2.0K 
R6P32 
1/16W 
0402 
G21796-001 
EMPTY 
1% 
R6P37 
2.0K 
R4E8 
10.0 1% 
CHIP 
2
1/16W 
0402 
1
G21796-066 
R4D39 
1/16W CHIP 
2
1% 10.0 
0402 
1
G21796-066 
2CHIP 
1/16W 
1% 
1.00K 
R4E3 
G21796-026 
0402 
1
2.26K 1
R4E20 
2
0402 
1.0% 
G21796-311 
0402 
4.02K 1
2
CHIP 
1.0% 0402 22.1 
R4D63 
A36096-046 
0402LF 
X7R 
10% 
1000PF 
C4D42 1
2
50V 
1% 
21
1
1/16W 
33.2 
CHIP 
0402 
G21497-005 
1
1/16W 
5% 
2
R6P18 
0.0 
R6P16 
1/16W 
CHIP 
1.00K 
1% 
0402 
G21796-026 
38 
41 
44 
19 
7
40 
48 
8
2
5
6
9
49 
43 
15 
14 
3
4
25 
30 
28 
33 
34 
32 
24 
21 
45 
12 
36 
22 
46 
10 
37 
42 
0402 
1.00K 
R4E4 
1% 1
EMPTY 2
1% 
49.9 
1
PIN-CON3-27-GP 
J8D4 
2
1
2
R4D58 
1.00K 
1% 
CHIP 
G21796-026 
0402 
2
1/16W 
0.0 
1
1% 
1.00K 
G21796-026 
CHIP 
1/16W 
0402 
R4E5 
2
D97712-004 
0402V 
X6S 
10% 
6.3V 
1.0UF 
C4D25 1
2
10% 
C4D26 1
2
16V 
6.3V 
10% 
C4D15 
1.0UF 1
22
0.1UF 
C4D19 
10% 
0402V 
16V 
X7R 
1
1
R4D26 
G21497-005 
0402 
CHIP 
0.0 
5% 2
VR_FET_SW_P12V_STBY_PVCCIN_CPU0 
2
1
20402LF 50V X7R 
220PF 
A36096-050 
10% 
C4D29 1
X7R 
A36096-050 
10% 2
1C4D18 
1
2
10% 
0402LF 
50V 
C4D45 
220PF 
X7R 
A36096-050 
R4D66 1 2
0.0 
VR_VRRDY_PVCCIN_CPU0 
SMB_VR_STBY_LVC3_SCL 
SMB_VR_STBY_LVC3_SDA 
VR_PVCCIN_CPU0_AIREF4 
VR_PVCCIN_CPU0_VD12 
VR_PVCCIN_CPU0_PWM5 
VR_PVSA_CPU0_BIREF1 
A_TSENSE_PVSA_CPU0 
VR_PVCCIN_CPU0_AVINSEN 
FM_PVCCIN_PVCCSA_CPU0_EN_LVC1 
VSENSE_PVSA_CPU0_N 
VSENSE_PVSA_CPU0_BVSP 
VSENSE_PVCCIN_CPU0_N 
VSENSE_PVCCIN_CPU0_AVSP 
VR_PVCCIN_CPU0_VREN 
VR_PVCCIN_CPU0_AIREF3 
VR_PVCCIN_CPU0_AIREF5 
ISENSE_PVCCIN_CPU0_PH4_IMON 
ISENSE_PVCCIN_CPU0_PH3_IMON 
SVID_DIO0_CPU0_R 
VR_PVCCIN_CPU0_PWM3 
VR_PVCCIN_CPU0_PWM4 
VSENSE_PVSA_CPU0_P 
VR_PVCCIN_CPU0_VDD 
PWRGD_PVSA_CPU0 
PWRGD_PVCCIN_CPU0 
VSENSE_PVCCIN_CPU0_P 
R6P28 
CHIP 
REMOVE VR DONGLE HEADER IN MASS PRODUCTION 
0402 
R6P27 
1/16W 
2
G21796-082 G21796-082 
CHIP 
1% 
1/16W 
1
1% 
4.02K 
0402 
SVID_ALERT0_CPU0_R_N 
G21796-250 
1/16W 
CHIP 
5% 
G21497-005 
CHIP 
IRQ_PVCCIN_CPU0_VRHOT_LVC3_N 
FM_PVCCIN_CPU0_PWR_IN_ALERT_N 
2
1% 
100.0 
R4E10 
1/16W 
0402 
G21796-017 
EMPTY 
1/16W 
2.26K 
1.0% 
G21796-311 
0402 
G21796-074 
1% 
CHIP 
5% 
ISENSE_PVCCIN_CPU0_PH2_IMON 
1% 
CHIP 
150.0 
RF5 
ISENSE_PVCCIN_CPU0_PH1_IMON 
0.1% 
0402 
17 
RF6 1.0K 0.1% 
G85996-004 0402 1/16W 
CHIP 
2
1
X7R 
0402LF 
220PF 
50V 
10% 
A_TSENSE_PVCCIN_CPU0 
CF6 
0402LF 
50V 
220PF 
1/16W 
CF2 
1/16W 
G85996-004 
1.0K 
SC22P50V2JN-4GP 
CF3 
CHIP 
0402 
RF4 
TP FAB4 CHANGE RF1-5 TO 953OHM FOR VR FAILCHILD, SINGLE SIDE BOM 20170123 
TP FAB3 CHANGE CAP 0912 
21 194 211 
205 
202 
202 
204 
202 
202 
205 
201 
201 
138 159 211
213 235 193
194 206 215
218 223 226
138 159 193
194 206 211
213 215 218
223 226 235
203 
201 
204 
205 
205 
201 
191 
205 
204 
203 
204 
203 
203 
21 194 211 
203 
203 
205 
190 
112
190
204 
194 211 21 
95 145 
95 
202 
202 
202 203 204 
GROUP=POWER_FAIR 
FAIR_SS=064.9530D.M001 
NPO 
GROUP=POWER_FAIR GROUP=POWER_FAIR GROUP=POWER_FAIR 
GROUP=POWER_FAIR 
22PF 0402 
GROUP=POWER_FAIR GROUP=POWER_FAIR 
5% 
50V 
5% 
50V 
NPO 
22PF 0402 
50V 
NPO 
0402 
5% 
50V 
22PF 0402 
5% 
50V 
NPO 
0402 22PF 
GROUP=POWER_FAIR 
GROUP=POWER_FAIR 
GROUP=POWER_FAIR 
50V 22PF 5% 
NPO 0402 
NPO 
5% 
22PF 
GROUP=POWER_FAIR 
GROUP=POWER_FAIR 
FAIR_SS=064.9530D.M001FAIR_SS=064.9530D.M001FAIR_SS=064.9530D.M001 FAIR_SS=064.9530D.M001 
1/16W 
EMPTY 
VR_PVCCIN_CPU0_XADDR1 
EMPTY 
VR_PVCCIN_CPU0_XADDR2 
DESIGN NOTE: 
DESIGN NOTE: 
DESIGN NOTE: 
21
2121212121
2
212 21
1
2
1
1
2 2
1
2
2
1
3
2
1
1
2121
1
DO NOT SCALE DRAWING SHEET 
B
AA
B
B
SIZE 
SCALE: 
234
1234
DEPARTMENT CODE 
1
DOCUMENT NUMBER REV 
IN 
IN 
IN 
IN 
IN 
IN 
IN 
OUT 
IN 
IN 
IN 
IN 
IN 
IN 
IN 
IN 
OUT 
IN 
IN 
IN 
IN 
IN 
IN 
OUT 
OUT 
OUT 
PVCCIO_CPU0 
BI 
OUT 
OUT 
OUT 
PVCCIO_CPU0 
IN 
IN 
BI 
OUT 
OUT 
P3V3_STBY 
P3V3_STBY 
P3V3_STBY 
OUT 
OUT 
OUT 
VR DONGLE HEADER FOR DIGITAL CONTROLLERS 
201 OF 270 
Wed Feb 08 16:35:24 2017 
1
1
1
SVID ADDRESS 
PXE1610C 
VRHOT_N 
THPAD 
BPWM1 
APWM1 APWM2 
APWM3 
APWM4 
APWM5 
APWM6 
SDA 
SCL 
VCLK 
VDIO 
RESET_N 
AISEN6 
AIREF6 
AISEN5 
AIREF5 
AISEN4 
AIREF4 
XADDR1 
AISEN3 
AIREF3 
XADDR2 
AISEN2 
AIREF2 
ATSEN 
AISEN1 
AIREF1 
VDD 
BTSEN 
BISEN1 BIREF1 
PINALRT_N 
VALRT_N 
AVSEN 
AVREF 
BVSEN 
BVREF 
VINSEN IINSEN 
VD12 
AVRRDY 
AVREN 
MP0 MP1 
MP2 
MP3 
MP4 
TP FAB1 DELETE RES 0203 
TP FAB1 CHANGE TO 021.60545.0103 0324 TP FAB1 ADD ATTRIBUTE 0321 
TP FAB1 NC 0321 
TP FAB1 CO-LAY WITH FAIRCHILD PARTS 1203 
TP FAB1 DELETE RES 0203 
TP FAB1 NOPOP RES 0316 
TP FAB1 DEL RES 0314 
TP FAB1 NC 0321 
TP FAB1 CHANGE TO 1K OHM 0218 
TP FAB1 NOPOP RES 0316 
TP FAB1 NC 0321 
TP FAB1 NC 0321 
TP FAB1 NC 0321 
TP FAB1 NC 0321 
SMBUS ADDRESS: 0X90 
PVSA_CPU0: 0X01(BUS #1) 
PVCCIN_CPU0: 0X00(BUS #1) 
INFINEON:NOPOP 
FAIRCHILD:POP 
RF1&RF2&RF3&RF4&RF5&RF6 
CF1&CF2&CF3&CF4&CF5&CF6 
VCCIN CPU0 (1 OF 4) 
ROOM=PVCCIN_CPU0_VR WIWYNN CORPORATION 



F S
F S
L4D3 
2
A36096-046 
VR_PVCCIN_CPU0_PHASE2 
TP_PVCCIN_CPU0_PH2_GL_0 
TP_PVCCIN_CPU0_PH2_GL_1 
VR_PVCCIN_CPU0_PH2_PHASE 
VR_PVCCIN_CPU0_PH2_VCIN 
VR_FET_SW_P12V_STBY_PVCCIN_CPU0 
1/16W 
22.0UF 1
2
2 E15431-004 
X6S 
20% 
4V 
C4E3 
C4E25 
VR_PVCCIN_CPU0_PHASE2_RC 
A36096-046 
1R3F-GP 
RT4 
1R3F-GP 
RT2 
A36096-046 
X7R 
50V 
10% 
VR_PVCCIN_CPU0_PHASE1 
40 
7
VR_PVCCIN_CPU0_PHASE1_RC 
ISENSE_PVCCIN_CPU0_PH2_IMON 
VR_PVCCIN_CPU0_PH2_OCSET 
10% 
0402LF 
50V 
1000PF 
0402LF 
1000PF 
VR_PVCCIN_CPU0_AIREF2 
CT5 32 
TP_PVCCIN_CPU0_PH1_GL_0 
VR_PVCCIN_CPU0_PH1_OCSET 
ISENSE_PVCCIN_CPU0_PH1_IMON 
VR_PVCCIN_CPU0_AIREF1 
A_TSENSE_PVCCIN_CPU0 
A_TSENSE_PVCCIN_CPU0 
VR_PVCCIN_CPU0_PH1_BOOT 
X7R 
CT3 
1
2
X7R 
10% 
50V CT4 
0402LF 
A36096-046 
X7R 
10% 
50V 
1000PF 
CT2 1
2
EMPTY 
1% 
R4E19 
0402 
1/16W 
68.1K 
1% 
R4E22 
40 
7
31 
EU4D6 
3
10 
37 
25 
41 
1
35 
4
IC 
30 
36 
38 
36 
EU4E1 
1
3
2
25 
30 
5
35 
32 
10 
6
41 
IC 
38 
37 4
31 
1 10UF 
2
0805 
C95333-007 
X6S 
10% 
16V 
10% 
2
10UF 1
X6S 
C6P22 
0805 
16V 
C95333-007 
10% 
10UF 1 C6R4 
16V 
X6S 2
1.0UF 1
16V 
C4D48 
10% 
0402 
2 2
1
X7R 
16V 
10% 
0.1UF 
C4D49 
2
1
10% 
X6S 
10% 
2
10UF 
16V C95333-007 
1 C6R13 
X6S 
VR_PVCCIN_CPU0_PWM1 
C95333-007 
C6P13 
2 X6S 
1 10UF 
0805 
16V 
10% 
0805 
2
1 C6R11 
10UF 
X6S 
C95333-007 
16V 
10% 
D97712-011 
0402 
C4E19 
1.0UF 
X6S 
1
2
16V 
0402V 
A36096-030 
X7R 
10% 
16V 
0.1UF 
C4E20 
2
1
2
D97712-011 
0402 
10% 
16V 
1.0UF 1
2X7R 
10% 
16V 
0.220UF 
C4D50 
0402 
1
A36096-104 
0402 
2
1
10% 
X7R 
A36096-155 
A36096-104 
0402 
X7R 
C4E17 1
16V 
10% 
2
0402 
A36096-155 
X7R 
10% 
16V 
2
0
5.0% G22178-002 
0 0603 
RT1 
16V 
34 
10% 
X7R 
34 
0402V 
16V 
H73688-001 
CHIP 
X7R 
10% 
0.1UF 
CT6 
A36096-030 
33 
5
6
33 
39 
CT1 
0.1UF 
H73688-001 
68.1K 
0402V 
A36096-030 
1/10W 
CHIP 
1/10W 
0603 
RT3 5.0% 
G22178-002 
VR_PVCCIN_CPU0_PH2_BOOT_R 39 
0402LF 
1000PF 
VR_PVCCIN_CPU0_PH2_BOOT 
16V 
1.0UF 
5% 
G21497-005 
1
R6R6 
2
0402 0.0 
A36096-030 
VR_PVCCIN_CPU0_PWM2 
0805 
C95333-007 
X6S 
D97712-011 
0402V 0402 
D97712-011 
C4E26 
16V 
0.22UF 
C4E27 
0402 
2
R6R2 
1
G21497-005 
5% 0.0 
0.22UF 
VR_PVCCIN_CPU0_PH1_VCIN 
C4E10 C4E6 
1 C4E5 
IND-120NH-30-GP 
L4E1 
IND-120NH-30-GP 
C6R7 
4V 
20% 
X6S 
0603V 
E15431-004 
EMPTY 
0402 
G21796-187 
0603V 
22.0UF 
G21796-187 
E15431-004 
20% 
C6P16 
22.0UF 1
0603V 
X6S 
1
2
0603V 
E15431-004 
X6S 
22.0UF 
C4E11 
4V 
20% 
4V 
X6S 
TP_PVCCIN_CPU0_PH1_GL_1 
10% 
VR_PVCCIN_CPU0_PH1_BOOT_R 
VR_PVCCIN_CPU0_PH1_PHASE 
0.220UF 
0805 
VR_FET_SW_P12V_STBY_PVCCIN_CPU0 
C6N8 
TP FAB1 CHANGE TO 0 OHM 0107 
TP FAB1 CHANGE RES TO 1 OHM 0603 0107 
TP FAB1 CHANGE RES TO 1 OHM 0603 0107 
TP FAB1 ADD NET NAME 12/04 
TP FAB1 CHANGE TO 0 OHM 0107 
201 
201 
201 
201 
202 203 204 201 
202 203 204 201 
201 
201 
CHIP 
1/16W 
0603 
1/10W 1 OHM 
1% 
NOPOP 
0603 
1/10W 
1 OHM 
1% NOPOP 
NOPOP 
10V 
0402 
CHIP 
1/16W 
1UF 
10% 
10V 
0402 
120NH 
ISAT=94A@25C 
DCR=0.17MOHM 
IRMS=66A@DELTA_T<40C 
120NH 
ISAT=94A@25C 
DCR=0.17MOHM 
IRMS=66A@DELTA_T<40C 
GROUP=PWR_MLCC_CAP GROUP=PWR_MLCC_CAP 
GROUP=PWR_MLCC_CAP 
GROUP=PWR_MLCC_CAP
10% 
1UF 
TP FAB1 ADD NET NAME 12/04 
TP FAB1 CO-LAY WITH TI PARTS 11/16 
SC1U10V2KX-4-GP SC1U10V2KX-4-GP 
2
NOPOP 
1
1
1
2
NOPOP 
2
1
1
1
2
21
2
NOPOP 
2
1 2
21
1 2
DO NOT SCALE DRAWING 
TP FAB1 CO-LAY WITH TI PARTS 11/16 
TP FAB1 CO-LAY WITH TI PARTS 11/16 
SHEET 
B
AA
B
B
SIZE 
SCALE: 
234
1234
DEPARTMENT CODE 
1
DOCUMENT NUMBER REV 
P5V_STBY 
P5V_STBY 
IN 
IN 
PVCCIN_CPU0 
OUT 
PVCCIN_CPU0 
OUT 
OUT 
OUT 
OUT 
OUT 
2
2 11 2
11 2
Wed Feb 08 16:35:24 2017 
202 OF 270 
GL<1> 
GL<0> 
PGND<1> 
PGND<0> 
PGND<2> LGND 
VOS 
EN 
VDRV 
VCC 
VIN<0> VIN<1> 
PHASE 
REFIN 
BOOST 
PWM 
SW 
NC 
IOUT 
OCSET 
TOUT_FLT 
GL<1> 
GL<0> 
PGND<1> 
PGND<0> 
PGND<2> LGND 
VOS 
EN 
VDRV 
VCC 
VIN<0> VIN<1> 
PHASE 
REFIN 
BOOST 
PWM 
SW 
NC 
IOUT 
OCSET 
TOUT_FLT 
TP FAB1 CO-LAY WITH TI PARTS 11/16 
TP FAB1 CHANGE PN 0310 
TDA21470 
TDA21470 
TP FAB1 CO-LAY WITH TI PARTS 11/16 
TP FAB1 CHANGE L4D3 PN 0122 
TP FAB1 CO-LAY WITH TI PARTS 11/16 
TP FAB1 CHANGE L4E1 PN 0122 
TP FAB1 CHANGE PN 0310 
TP FAB1 DEL NET 0309 
TP FAB1 DEL NET 0309 
NOPOP 
NOPOP 
VCCIN CPU0 (2 OF 4) 
PLACE ON TOP 
PLACE ON TOP 
SPOF 
WIWYNN CORPORATION 
SPOF 
ROOM=PVCCIN_CPU0_PWR_VR 



VR_PVCCIN_CPU0_PHASE3_RC 
VR_PVCCIN_CPU0_PHASE4_RC 
F S
F S
699013-049 
10% 
E15431-004 E15431-004 
IC 
EU4D1 
38 ISENSE_PVCCIN_CPU0_PH4_IMON 
VR_PVCCIN_CPU0_PH4_OCSET 
C4D16 
C95333-007 
ISENSE_PVCCIN_CPU0_PH3_IMON 38 
VR_PVCCIN_CPU0_PHASE3 
16V 
0402V 
0603V 
X6S 
0603V 
R4E13 
100.0 
1% 
1/10W 
CHIP 
G22026-038 
0603 
470UF 
ALUM 
699013-049 
VR_PVCCIN_CPU0_AIREF4 
G21796-187 
E15431-004 
0603V 
2
0603V 
E15431-004 
22.0UF 
20% 
4V 
1
C6P3 
22.0UF 
X6S 
20% 
4V 
C4D4 
X6S 
1
IND-120NH-30-GP 
2
34 
33 
7
36 
VR_PVCCIN_CPU0_PHASE4 
1000PF CT41 
L4D1 
R4D71 
68.1K 
1/16W 
EMPTY 
0402 
699013-049 
20% 
C6R9 
1R3F-GP 
X6S 
C6P18 
2
699013-049 
C6N9 
470UF 
20% 
699013-049 
ALUM 
IND-120NH-30-GP 
L4D2 
TP_PVCCIN_CPU0_PH4_GL_1 
TP_PVCCIN_CPU0_PH4_GL_0 
VR_PVCCIN_CPU0_PH4_BOOT_R 
A36096-155 
16V 
C4D5 
0.22UF 
C4D14 
VR_PVCCIN_CPU0_PH3_VCIN 
0.0 0402 
G21497-005 
5% 
R6P19 
21
D97712-011 
10% 0402LF 
A36096-030 
0402V 
0.1UF 
16V 
10% 
VR_PVCCIN_CPU0_PH3_BOOT_R 
CT39 
H73688-001 A36096-030 
0402V 
1/10W 
5.0% 
10% 
TP_PVCCIN_CPU0_PH3_GL_1 
TP_PVCCIN_CPU0_PH3_GL_0 
VR_PVCCIN_CPU0_PH3_PHASE 
RT28 
X7R 
32 
0.1UF 
16V 
32 
X7R 
VR_PVCCIN_CPU0_PH4_BOOT 
H73688-001 
CT40 
39 
VR_PVCCIN_CPU0_PH4_PHASE 
VR_PVCCIN_CPU0_PWM4 
A_TSENSE_PVCCIN_CPU0 
A_TSENSE_PVCCIN_CPU0 
VR_PVCCIN_CPU0_PH3_OCSET 
VR_PVCCIN_CPU0_AIREF3 
VR_PVCCIN_CPU0_PH3_BOOT 0402LF 
A36096-046 
CT37 
10% 
50V 
1000PF 
X7R 
1% 
37 
31 
5
41 
1
10 
40 
3
25 
30 
35 
6
2
4
36 
31 
39 
6
1
41 
5
7
40 
2
35 
3
4
30 
IC 
EU4D3 
37 
25 
33 10 
34 
1
VR_FET_SW_P12V_STBY_PVCCIN_CPU0 
0805 
C95333-007 
2 X6S 
10% 
1
10UF 
16V 
C6P7 C6P15 
10UF 
10% 
X6S 
C95333-007 
0805 
1
2
16V 
0805 
C95333-007 
10UF 
C6P20 
X6S 
10% 
2
1
16V 
VR_PVCCIN_CPU0_PWM3 
X6S 
C6P19 
2
0805 
C95333-007 
1
16V 
10UF 
10% 
2
0402 
10% 
X6S 
16V 
1.0UF 
D97712-011 
1 C4D10 
16V 
0.1UF 
A36096-030 
10% 
0402V 
X7R 2
1 C4D11 
16V 
1.0UF 
10% 
X6S 
0402 
2
1
D97712-011 
0402 
2
1
0402 
D97712-011 
16V 
X6S 2
C4D30 
1.0UF 
10% 
1
16V 
0.1UF 
A36096-030 2 X7R 
10% 
C4D35 1
2
0402 
X6S 
10% 
1.0UF 1
0402 
A36096-104 
X7R 
10% 
16V 
2
1
0.220UF 
C4D28 
0402 
A36096-155 
10% 
16V 
0.22UF 
C4D13 
2
1
X7R 
VR_FET_SW_P12V_STBY_PVCCIN_CPU0 
2
3018 
ALUM 
2.5V 
1
20% 
1 C6P8 
3018 
ALUM 2
3018 
1
X7R 
1
10% 
16V 
0402 
2
A36096-104 
0.220UF 
C4D9 
2
1
0805 
2
C6R6 
10UF 1
16V 
10% 
X6S 
1
2
3018 
2
20% 
470UF 
ALUM 
3018 
699013-049 
0402 
1
G21497-005 
0.0 5% 
R6P10 
2
0
0603 
G22178-002 CHIP 
1/10W 
5.0% 
CHIP 
50V 
50V 
CT38 1000PF 
A36096-046 
X7R 
0402LF 
A36096-046 
X7R 
10% 
50V 
1000PF 
CT42 
X6S 2
0805 
1
16V 
10UF 
C6P24 
20% 
C95333-007 
X7R 
10% 
RT26 
RT27 
1R3F-GP 
A36096-046 
0402LF 
0
G22178-002 
RT25 
0603 
X7R 
C4D6 
VR_PVCCIN_CPU0_PH4_VCIN 
C4D7 
10% 
470UF 
20% 
ALUM 
3018 
470UF 
C6P14 
699013-049 
470UF 
20% 
1
2
3018 
470UF 
C6P23 
ALUM 
1 C6R3 
0402 
G21796-187 
EMPTY 
1/16W 
1% 
68.1K 
R4D72 
2
1
C4D34 
20% 
2
4V 
2
1 22.0UF 
C6P21 
22.0UF 
4V 
20% 
TP FAB1 CHANGE TO 0 OHM 0107 
TP FAB1 CHANGE TO 0 OHM 0107 
TP FAB1 CO-LAY WITH TI PARTS 11/16 
TP FAB1 CHANGE RES TO 1 OHM 0603 0107 
201 
201 
201 
201 
202 203 204 201 
202 203 204 201 
201 
201 
GROUP=PWR_MLCC_CAP 
0603 
GROUP=PWR_BULK_CAP 
GROUP=PWR_BULK_CAP 
GROUP=PWR_BULK_CAP 
GROUP=PWR_BULK_CAP 
GROUP=PWR_BULK_CAP 
GROUP=PWR_BULK_CAP 
GROUP=PWR_BULK_CAP 
GROUP=PWR_MLCC_CAP
GROUP=PWR_MLCC_CAP 
GROUP=PWR_MLCC_CAP
DCR=0.17MOHM 
2.5V 
IRMS=66A@DELTA_T<40C 
ISAT=94A@25C 
120NH 
1 OHM 
2.5V 
DCR=0.17MOHM 
ISAT=94A@25C 
120NH 
10V 
10% 
1UF 
1/16W 
CHIP 
2.5V 2.5V 
CHIP 
1/16W 
NOPOP 
1% 
1/10W 
1/10W 
NOPOP 
1% 
1 OHM 
0603 
0402 
1UF 
10V 
10% 
0402 
2.5V 2.5V 
IRMS=66A@DELTA_T<40C 
TP FAB1 ADD NET NAME 12/04 
TP FAB1 ADD NET NAME 12/04 
1
SC1U10V2KX-4-GP 
SC1U10V2KX-4-GP 
TP FAB1 CHANGE RES TO 1 OHM 0603 0107 
21
1 NOPOP 
1 2
2
1
1
1
2
1
2
1
1
2
2
1
2
2
1
NOPOP 
2
21
2
DO NOT SCALE DRAWING 
TP FAB1 CO-LAY WITH TI PARTS 11/16 
TP FAB1 CO-LAY WITH TI PARTS 11/16 
TP FAB1 CO-LAY WITH TI PARTS 11/16 
SHEET 
B
AA
B
B
SIZE 
SCALE: 
234
1234
DEPARTMENT CODE 
1
DOCUMENT NUMBER REV 
OUT 
P5V_STBY 
P5V_STBY 
IN 
OUT 
IN 
OUT 
PVCCIN_CPU0 
OUT 
OUT 
OUT 
PVCCIN_CPU0 
PVCCIN_CPU0 
2
1 2
1 2 1
2 1
203 OF 270 
Wed Feb 08 16:35:24 2017 
GL<1> 
GL<0> 
PGND<1> 
PGND<0> 
PGND<2> LGND 
VOS 
EN 
VDRV 
VCC 
VIN<0> VIN<1> 
PHASE 
REFIN 
BOOST 
PWM 
SW 
NC 
IOUT 
OCSET 
TOUT_FLT 
GL<1> 
GL<0> 
PGND<1> 
PGND<0> 
PGND<2> LGND 
VOS 
EN 
VDRV 
VCC 
VIN<0> VIN<1> 
PHASE 
REFIN 
BOOST 
PWM 
SW 
NC 
IOUT 
OCSET 
TOUT_FLT 
TP FAB1 CHANGE PN L4D1 0122 
TDA21470 
TP FAB1 CO-LAY WITH TI PARTS 11/16 
TDA21470 
TP FAB1 CHANGE PN 0310 
TP FAB1 DEL NET 0309 
TP FAB1 CHANGE PN 0310 
TP FAB1 DEL NET 0309 
TP FAB1 CHANGE L4D2 PN 0122 TP FAB1 CO-LAY WITH TI PARTS 11/16 NOPOP 
NOPOP 
NOPOP 
NOPOP 
ROOM = PVCCIN_CPU0_DECAP_VR 
VCCIN CPU0 (3 OF 4) 
PLACE ON TOP 
PLACE ON TOP 
SPOF 
WIWYNN CORPORATION 
SPOF ROOM=PVCCIN_CPU0_PWR_VR 
ROOM=PVCCIN_CPU0_PWR_VR 



F S
TP FAB1 CHANGE TO 0 OHM 0107 
201 
201 
201 
202 203 201 
201 
37 
201 
37 
10% 
100.0 
VSENSE_PVCCIN_CPU0_P 
0402 
VR_PVCCIN_CPU0_PHASE5_RC 
2
120NH 
IND-120NH-30-GP 
L4C3 
IRMS=34A@DELTA_T<45C 
DCR=0.22MOHM 
ISAT=50A@25C 
L4C1 
0402 
10V 
10% 
1UF 
C4D47 
0.22UF 
16V 
C4C14 
CHIP 
1/16W 
0402 0.0 
G21497-005 
2
R6P47 
5% 
1
0402 
0603 
1
A36096-155 
10% 
2 X7R 
0402 
A36096-104 
X7R 
16V 
2
0.220UF 
16V 
1.0UF 
0402 
D97712-011 2
C4D46 
10% 
X6S 
1C4C19 1
16V 
0.1UF 
X7R 
2 A36096-030 
0402V 
10% 
16V 
1 1.0UF 
C4C18 
X6S 
0402 
2
1
X6S 
10UF 
0805 
16V 
C6N10 
2
10% 
2
1
X6S 
C95333-007 
0805 
16V 
10UF 
C6P17 
10% 
VR_PVCCIN_CPU0_PWM5 
2
1 C6N11 
10UF 
16V 
10% 
X6S 
OSCON 
2
20% 
1
16V 
C4D2 
A31228-047 
2626 
270UF 
1
2 OSCON 
2626 
A31228-047 
16V 
20% 
270UF 
C4E16 
1
G21796-017 
R4E14 
2
1% 
1/16W CHIP 
CHIP 
1
0402 
1/16W 
2
R4E16 
G21497-005 
2
CHIP 
1
0402 
0.0 
1/16W 
G21497-005 
R4E17 
5% 
G21796-026 
2
1
0402 
R4E15 
1.00K 
1% 
EMPTY 
1/16W 
R4E18 
2
100.0 
1/16W 
1
G21796-017 
1% 
0402 
CHIP 
1
2
2626 
A31228-047 
270UF 
OSCON 
16V 
20% 
C4C12 
40 
5
33 
4
35 
7
10 
36 
37 
3
30 
25 
IC 
39 
32 
41 
H73688-001 
6
34 
1
2
31 
G21796-187 
EMPTY 
1/16W 
0402 
2
R4D68 
1 68.1K 
1% 
A36096-046 
X7R 
10% 
50V 
1000PF 
CT34 
50V 
1/10W RT23 
0
VR_PVCCIN_CPU0_PH5_PHASE 
VR_PVCCIN_CPU0_AIREF5 
A_TSENSE_PVCCIN_CPU0 
VR_PVCCIN_CPU0_PH5_OCSET 
VSENSE_PVCCIN_CPU0_N 
VSENSE_PVCCIN_CPU0_SKT_VSEN 
CT36 
0.1UF 
G22178-002 
10% 
C4C17 1
TP_PVCCIN_CPU0_PH5_GL_0 
0402V 
VR_PVCCIN_CPU0_PH5_BOOT 
CHIP 
5.0% 
VR_PVCCIN_CPU0_PH5_BOOT_R 
X7R 
10% 
VR_PVCCIN_CPU0_PHASE5 
0402LF 
A36096-046 
0402LF 
CT35 
C95333-007 
10% 
1000PF X7R 
1R3F-GP 
1% 
1 OHM 
RT24 
1/10W 
0603 
2
1
22.0UF 
4V 
20% 
X6S 
E15431-004 
0603V 
20% 
4V 
22.0UF 
C4D12 
0603V 
E15431-004 
NOPOP 
DCR=0.17MOHM 
ISAT=94A@25C 
IRMS=66A@DELTA_T<40C 
X6S 
1
C6R2 
GROUP=PWR_MLCC_CAP 
GROUP=PWR_MLCC_CAP
VR_FET_SW_P12V_STBY_PVCCIN_CPU0 
A36096-030 
16V 
TP_PVCCIN_CPU0_PH5_GL_1 
38 ISENSE_PVCCIN_CPU0_PH5_IMON 
EU4C2 
VR_PVCCIN_CPU0_PH5_VCIN 
D97712-011 
VR_FET_SW_P12V_STBY_PVCCIN_CPU0 
VSENSE_PVCCIN_CPU0_SKT_VRTN 
5% 0.0 
C95333-007 
0805 
80NH 
IND-80NH-1-GP 
SC1U10V2KX-4-GP 
DESIGN NOTE: 
1
1
2
2
1
1 2
2
LL=0.9MOHM 
VBOOT=1.7V 
TP FAB1 CHANGE RES PN 0218 
VOUT=1.8V(NOM) 
RIPPLE GUIDE= +/- 5MV 
DC TOL = +/-17MV 
AC + RIPPLE TOL =  +/-22MV 
IOUT TDC=88A 
IOUT PK=228A 
IOUT DI/DT = 778 A/US 
SW FREQ=625 KHZ 
IOUT STEP=187 APP 
ROUT AS DIFF PAIR 
10MIL WIDTH 
5MIL SPACING 
1 2
1 2
NOPOP 
DO NOT SCALE DRAWING 
TP FAB1 CO-LAY WITH TI PARTS 11/16 
TP FAB1 CO-LAY WITH TI PARTS 11/16 
TP FAB1 CO-LAY WITH TI PARTS 11/16 
SHEET 
B
AA
B
B
SIZE 
SCALE: 
234
1234
DEPARTMENT CODE 
1
DOCUMENT NUMBER REV 
P5V_STBY 
P12V_STBY 
IN 
IN 
PVCCIN_CPU0 
OUT 
OUT 
IN 
PVCCIN_CPU0 
OUT 
OUT 
OUT 
1 2
1 2
KELVIN 
VR CONTROLLER SIDE 
TP FAB1 ADD NET NAME 12/04 
TP FAB1 DELETE ADM4073, CAP, RES 0321 
TDA21470 
INPUT CURRENT SENSE FOR VCCIN AND VSA 
TP FAB1 CHANGE PN 0310 
TP FAB1 CHANGE L4C1 PN 0122 
PVCCIN CPU0 VOLTAGE SENSE 
SOCKET SIDE 
TP FAB1 DEL NET 0309 
CONNECTION 
TP FAB1 CHANGE RES TO 1 OHM 0603 0107 
TP FAB1 CHANGE L4C3 PN 0122 
INPUT FILTER 
204 OF 270 
Wed Feb 08 16:35:25 2017 
1
1
1
NOPOP 
NOPOP 
GL<1> 
GL<0> 
PGND<1> 
PGND<0> 
PGND<2> LGND 
VOS 
EN 
VDRV 
VCC 
VIN<0> VIN<1> 
PHASE 
REFIN 
BOOST 
PWM 
SW 
NC 
IOUT 
OCSET 
TOUT_FLT 
VCCIN CPU0 (4 OF 4) 
PLACE ON TOP 
WIWYNN CORPORATION 
SPOF 
ROOM=PVCCIN_CPU0_PWR_VR 
ROOM = PVCCIN_CPU0_FILTER_VR ROOM = PVCCIN_CPU0_VSENSE_VR 



VR_PVSA_CPU0_PHASE_SW 
VR_PVSA_CPU0_PHASE_SW_RC 
100.0 1% 
5% 
ALUM 
3018 
VR_FET_SW_P12V_STBY_PVCCIN_CPU0 
C4C4 
RT40 
A36096-030 
35 
C4C9 
20% 
470UF 
C6N1 
699013-049 
1R3F-GP 
RT39 
A36096-046 
0402LF 1000PF 
CT59 
10% 
X7R 
0805 
50V 
VSENSE_PVSA_CPU0_SKT_VSEN 
VSENSE_PVSA_CPU0_SKT_VRTN 
TP_PVSA_CPU0_GL_1 
VR_PVSA_CPU0_BIREF1 
A_TSENSE_PVSA_CPU0 
VR_PVSA_CPU0_OCSET 
ISENSE_PVSA_CPU0_IMON 
TP_PVSA_CPU0_GL_0 
VR_PVSA_CPU0_BOOT_R 
VR_PVSA_CPU0_PWM 
VR_PVSA_CPU0_BOOT 
VR_PVSA_CPU0_PHASE 
VSENSE_PVSA_CPU0_P 
VSENSE_PVSA_CPU0_N 
CHIP 1/10W 
5.0% G22178-002 
0 0603 
16V CT60 
0402V 
A36096-030 
X7R 
10% 
0.1UF 
0402LF 
A36096-046 
X7R 
10% 
50V 
1000PF 
CT58 G21796-187 
EMPTY 
1/16W 
1% 
68.1K 
R4C13 
0402 
2
1
E15431-004 
20% 
4V 
22.0UF 
2
0603V 
X6S 
C6N7 1
32 
33 
39 
2
40 
IC 
10 
36 
37 
EU4C1 
7
H73684-001 
4
31 
38 
30 
25 
3
5
1
6
41 
34 
0402 
G21796-208
CHIP 
1/16W 
1.0% 
51.1 
R6N4 
0603V 
E15431-004 
X6S 
20% 
4V 
22.0UF 
1
2
C4C11 
G21796-026 
0402 
EMPTY 
1/16W 
1% 
1.00K 
R4C3 
1
2
0805 
C95333-007 2
1
X6S 
C6N6 
10UF 
10% 
16V 
X6S 
C95333-007 
1
2
0805 
10UF 
10% 
C6N3 
16V 
C6N2 
C95333-007 
10% 
10UF 
16V 
X6S 
2
1
10% 
16V 
1.0UF 
X6S 
1
2
0402 
D97712-011 
16V 
10% 
X7R 
2
1
0402V 
C4C10 
0.1UF 
0.0 5% 
CHIP 
R4C2 
G21497-005 
1/16W 
1
0402 
2
R4C1 
100.0 
1/16W 
1
G21796-017 
0402 
2
1% 
G21497-005 
R4C4 
0.0 
1/16W 
0402 
CHIP 
21
0402 
A36096-104 
X7R 
10% 
16V 
0.220UF 1C4C8 
2
0402 
1/16W 
2
R4C5 
G21796-017 
1
1 C4C6 
1.0UF 
2 X6S 
16V 
10% 
D97712-011 
0402 
10% 
A36096-155 
2
0402 
2
R6N3 
G21497-005 
1
16V 
0.0 5% 0402 
VR_PVSA_CPU0_VCIN 
X7R 
0.22UF 1 C4C5 
IND-300NH-20-GP 
L4C2 
20% 
3018 
C6N4 
470UF 
699013-049 
ALUM 
1
2
2.5V 
1
2
2.5V 
TP FAB1 CHANGE TO 0 OHM 0107 
39 
39 
201 
201 
201 
201 
201 
201 
CHIP 
GROUP=PWR_BULK_CAP GROUP=PWR_BULK_CAP 
0603 
1 OHM 
1/10W 
1% 
NOPOP 
CHIP 
1/16W CHIP 
1UF 
10% 
10V 
0402 
300NH 
ISAT=33A@25C 
DCR=0.17MOHM 
IRMS=66A@DELTA_T<40C 
TP FAB1 ADD NET NAME 12/04 
SC1U10V2KX-4-GP 
DESIGN NOTE: 
DESIGN NOTE: 
IOUT TDC=15A 
ROUT AS DIFF PAIR 
5MIL SPACING 
IOUT STEP=5A/US 
VBOOT=0.9V 
10MIL WIDTH 
DC TOL = +/-5MV 
SW FREQ=520 KHZ 
IOUT DI/DT =20A/US 
IOUT PK=16A 
TOTAL TOL = 0.917MAX/0.779VMIN 
VOUT=0.85V (TYP) SVID 
RIPPLE = +/- 10MV 
NOPOP 
2
1
1 2
1
2
2
1
2
1
21
DO NOT SCALE DRAWING 
TP FAB1 CO-LAY WITH TI PARTS 11/16 
TP FAB1 CO-LAY WITH TI PARTS 11/16 
TP FAB1 CO-LAY WITH TI PARTS 11/16 
SHEET 
B
AA
B
B
SIZE 
SCALE: 
234
1234
DEPARTMENT CODE 
1
DOCUMENT NUMBER REV 
P5V_STBY 
IN 
IN 
PVSA_CPU0 
IN 
OUT 
OUT 
PVSA_CPU0 
OUT 
OUT 
PVSA_CPU0 
OUT 
2 1
1 2
SOCKET SIDE VR CONTROLLER SIDE 
PVSA CPU0 VOLTAGE SENSE 
205 OF 270 
Wed Feb 08 16:35:25 2017 
PVCCSA CPU SPECIFICATIONS: 
GL<1> 
GL<0> 
PGND<1> 
PGND<0> 
PGND<2> LGND 
VOS 
EN 
VDRV 
VCC 
VIN<0> VIN<1> 
PHASE 
REFIN 
BOOST 
PWM 
SW 
NC 
IOUT 
OCSET 
TOUT_FLT 
TDA21460 
TP FAB1 CHANGE PN 0310 
TP FAB1 CHANGE L4C2 PN 0122 
TP FAB1 DEL NET 0309 
TP FAB1 CHANGE RES TO 1 OHM 0603 0107 
NOPOP 
NOPOP 
VSA CPU0 
PLACE ON TOP 
SPOF 
WIWYNN CORPORATION 
ROOM = PVSA_CPU0_VSENSE_VR 
ROOM=PVSA_CPU0_PWR_VR 
ROOM = PVSA_CPU0_DECAP_VR 



1.0UF 
0402 
A_TSENSE_PVSA_CPU1 
CHIP 1/16W 
SC22P50V2JN-4GP 
A36096-050 
H79206-001 
0402LF 
220PF 
0402LF 
1.0K 
G85996-004 
CF12 
CHIP 
SC22P50V2JN-4GP 
ISENSE_PVCCIN_CPU1_PH3_IMON 
ISENSE_PVCCIN_CPU1_PH4_IMON 
ISENSE_PVCCIN_CPU1_PH5_IMON 
R1D4 
2
CHIP 
FM_PVCCIN_PVCCSA_CPU1_EN_LVC1 
RF12 
VSENSE_PVSA_CPU1_BVSP 
30 
28 
VR_PVCCIN_CPU1_VREN 
34 
SC22P50V2JN-4GP 
CF8 
G85996-004 
1.0K 
SVID_CLK0_CPU1_R 
0402 
VSENSE_PVCCIN_CPU1_P 
VSENSE_PVCCIN_CPU1_N 
VSENSE_PVCCIN_CPU1_AVSP 
SC22P50V2JN-4GP 
CF11 
SC22P50V2JN-4GP 
1/16W 
CF9 CF10 
SC22P50V2JN-4GP 
CF7 
SVID_VCLK_PVCCIN_CPU1 CHIP 2
RF10 
0402 
1
VR_PVCCIN_CPU1_AIREF4 
VR_PVCCIN_CPU1_AIREF5 
ISENSE_PVCCIN_CPU1_PH1_IMON 
0402 
0402 
10% 
X7R 
27 
29 
0.1% 
0402 
CHIP 
0.1% 
CHIP 
1.0K 
1/16W 
25 
G85996-004 G85996-004 
1/16W 
EU1C2 
16V 
VR_PVCCIN_CPU1_AVINSEN 
A36096-050 
0402LF 
10% 
X7R 
VSENSE_PVSA_CPU1_N 
C1C13 
A36096-030 
0402V 
1/16W 
49.9 
1% G21796-160 
R1C16 
1.5K 
1% 
C1C8 
0.1UF 
16V 
10% 
X7R 
100.0K 
1% 
0402 
50V 
C1C10 
43 
10 
1% 
CHIP 
RF7 
CHIP 
0.1% 
G85996-004 
1/16W 
RF11 1.0K 
VR_PVCCIN_CPU1_AIREF3 
150.0 
G21796-009 
0402 
1
2
1/16W 
CHIP 
G21796-043 
R9N7 
3.16K 
1/16W 
R9N8 
0402 
2
1
CHIP 
G21796-082 
4.02K 
1% 
1
0402 CHIP 1/16W 
22.1 1.0% 
R1C30 
2
G21796-250 
C1C23 
A36096-046 
X7R 
0402LF 
1 1000PF 
2
10% 
50V 
33.2 
1/16W 
1% 
G21796-074 
CHIP 
1
R1D1 
2
1/16W 
1% 
CHIP 
33.2 
2
0402 
1
R9P3 
G21796-074 
CHIP 
1 2
1/16W 
0.0 5% 0402 
G21497-005 
R9N16 
1
1/16W 
0402 
G21796-026 
1% 
1.00K 
R9N14 
2 CHIP 
33 
47 
17 
23 
31 
24 
26 
49 
11 
1
39 
41 
12 
32 
IC 
9
8
2
4
3
6
5
7
40 
14 
20 
16 
15 
18 
48 
19 
13 
36 
35 
22 
21 
45 
46 
44 
38 
37 
42 
G21796-026 
R1D7 
2
1% 
CHIP 
0402 
1.00K 
1/16W 
1
0402V 
10% 
X6S 
6.3V 
D97712-004 2
10% 
16V 
1 C1C14 
0.1UF 
A36096-030 
X7R 
0402V 
2
EMPTY 
1
1.0% 
1/16W 
0402 
2.26K 
G21796-311 
R1D53 
0402 
G21796-311 
EMPTY 
1/16W 
1
2
R1C18 
2.26K 
1.0% 
R1C28 
1.00K 1
1% 
0402 
1/16W 
CHIP 2
G21796-026 
0402 
G21796-026 
2
1/16W 
R1D8 
1.00K 
1% 
CHIP 
1
G21497-005 0402 5% 
0.0 CHIP 
2
1/16W 
1
R1D3 
2
G21497-005 
0.0 
1/16W 
5% 0402 
R1D2 
1
CHIP 
100.0 
CHIP 
G21796-017 
0402 
2
1
R9P1 
1% 
1/16W 
X6S 
6.3V 
0402V 
10% 
1.0UF 
D97712-004 
C1C7 
X7R 2
1 C1C9 
0.1UF 
10% 
A36096-030 
0402V 
2
1/16W 
CHIP 
0402 
5% 
0.0 
1
R1C14 
G21497-005 
VR_FET_SW_P12V_STBY_PVCCIN_CPU1 
1
2
1/16W 
CHIP 
R1C13 
0402 
1
2
1/16W 
CHIP 
R9P2 
G21796-047 
0402 
1
R1D9 
1% 
0402 
1
2
G21796-003 
CHIP 
2
1% 
1
R1D6 
1.00K 
1/16W 
CHIP 
G21796-026 
0402 
220PF 
X7R 50V 2
1C1C16 
1
2
1
1% 
2
0402 
50V 
1 C1D1 
220PF 
0402LF 
2
10.0 1% 
0402 
1/16W 
VR_PVSA_CPU1_BIREF1 
VR_PVCCIN_CPU1_AVINSEN 
A_TSENSE_PVCCIN_CPU1 
VR_PVCCIN_CPU1_VDD 
SMB_VR_STBY_LVC3_SCL 
SMB_VR_STBY_LVC3_SDA 
PWRGD_PVSA_CPU1_R 
SVID_DIO0_CPU1_R 
IRQ_PVCCIN_CPU1_VRHOT_LVC3_R_N 
SVID_VALERT_VCCIN_CPU1 
VR_PVCCIN_CPU1_VD12 
SVID_VDIO_PVCCIN_CPU1 
VR_PVSA_CPU1_PWM 
VR_PVCCIN_CPU1_PWM1 
VR_PVCCIN_CPU1_PWM2 
VR_PVCCIN_CPU1_PWM3 
IRQ_PVCCIN_CPU1_VRHOT_LVC3_N 
VR_PVCCIN_CPU1_PWM4 
VR_PVCCIN_CPU1_PWM5 
PU_VR_PVCCIN_CPU1_IMON 
PU_VR_PVCCIN_CPU1_FLT1_SMBALT_N_IMON 
VR_VRRDY_PVCCIN_CPU1 
FM_PVCCIN_CPU1_PWR_IN_ALERT_N 
ISENSE_PVSA_CPU1_IMON 
SVID_ALERT0_CPU1_R_N 
PWRGD_PVSA_CPU1 
VSENSE_PVSA_CPU1_P 
VR_PVCCIN_CPU1_VD12 
PWRGD_PVCCIN_CPU1 
1/16W 1/16W 
0402 G85996-004 
RF9 1.0K 0.1% RF8 1.0K 0.1% 
VR_PVCCIN_CPU1_AIREF2 
VR_PVCCIN_CPU1_AIREF1 
ISENSE_PVCCIN_CPU1_PH2_IMON 
1/16W 
10.0 
G21796-066 
10% 
A36096-050 
G21796-066 
R1C21 
CHIP 
0.1% 
C1C11 
X7R 
1
A36096-050 
10% 220PF 
50V 
2
TP FAB4 CHANGE RF12 TO 1.1KOHM FOR VR FAILCHILD, SINGLE SIDE BOM 20170123 
TP FAB4 CHANGE RF7-11 TO 953OHM FOR VR FAILCHILD, SINGLE SIDE BOM 20170123 
TP FAB1 CO-LAY WITH FAIRCHILD PARTS 1203 
TP FAB3 CHANGE CAP 0912 
210 
208 
208 
209 
191 
55 193 213 
209 
209 
208 
209 
207 
206 
210 
208 
210 
206 
207 208 209 
138 159 211 213 
235 193 194 201 
215 218 223 226 
138 159 193 194 
201 211 213 215 
218 223 226 235 
55 193 213 
206 
210 
207 
207 
208 
95 145 
208 
209 
95 
210 
193 213 55 
190 
210 
206 
190 
207 
207 
207 
0402 
NPO 
GROUP=POWER_FAIR 
22PF 
5% 
50V 
GROUP=POWER_FAIR 
FAIR_SS=064.1101D.M001 
FAIR_SS=064.9530D.M001 
GROUP=POWER_FAIR GROUP=POWER_FAIR 
FAIR_SS=064.9530D.M001 
GROUP=POWER_FAIR 0402 22PF 
5% 
GROUP=POWER_FAIR GROUP=POWER_FAIR GROUP=POWER_FAIR 
NPO 
50V 
0402 
GROUP=POWER_FAIR 
FAIR_SS=064.9530D.M001 
GROUP=POWER_FAIR 
22PF 
5% 
50V 
NPO 
0402 0402 
5% 
NPO 
22PF 
5% 
0402 
5% 
NPO 
50V 
22PF 
1 2
50V 
NPO 
GROUP=POWER_FAIR GROUP=POWER_FAIR 
22PF 
50V 
FAIR_SS=064.9530D.M001 FAIR_SS=064.9530D.M001 
TP FAB1 CO-LAY WITH FAIRCHILD PARTS 1203 
VR_PVCCIN_CPU1_XADDR1 
VR_PVCCIN_CPU1_XADDR2 
DESIGN NOTE: 
DESIGN NOTE: 
21
21212121
21
22 1 2
2
1
1 1 1
1
2
2 2 1
DO NOT SCALE DRAWING 
CF7&CF8&CF9&CF10&CF11&CF12 
INFINEON:NOPOP 
FAIRCHILD:POP 
RF7&RF8&RF9&RF10&RF11&RF12 
SHEET 
B
AA
B
B
SIZE 
SCALE: 
234
1234
DEPARTMENT CODE 
1
DOCUMENT NUMBER REV 
IN 
IN 
IN 
IN 
IN 
IN 
IN 
IN 
IN 
OUT 
IN 
IN 
IN 
IN 
IN 
IN 
IN 
IN 
IN 
IN 
OUT 
OUT 
OUT 
PVCCIO_CPU1 
IN 
IN 
BI 
OUT 
OUT 
OUT 
OUT 
OUT 
OUT 
OUT 
BI 
OUT 
P3V3_STBY P3V3_STBY 
IN 
IN 
OUT 
PVCCIO_CPU1 
206 OF 270 
Wed Feb 08 16:35:25 2017 
1
1
1
SVID ADDRESS 
PXE1610C 
VRHOT_N 
THPAD 
BPWM1 
APWM1 APWM2 
APWM3 
APWM4 
APWM5 
APWM6 
SDA 
SCL 
VCLK 
VDIO 
RESET_N 
AISEN6 
AIREF6 
AISEN5 
AIREF5 
AISEN4 
AIREF4 
XADDR1 
AISEN3 
AIREF3 
XADDR2 
AISEN2 
AIREF2 
ATSEN 
AISEN1 
AIREF1 
VDD 
BTSEN 
BISEN1 BIREF1 
PINALRT_N 
VALRT_N 
AVSEN 
AVREF 
BVSEN 
BVREF 
VINSEN IINSEN 
VD12 
AVRRDY 
AVREN 
MP0 MP1 
MP2 
MP3 
MP4 
TP FAB1 DELETE RES 0203 
TP FAB1 NC 0321 
TP FAB1 NC 0321 
TP FAB1 DELETE RES 0203 
TP FAB1 NC 0321 
TP FAB1 CHANGE TO 1K OHM 0218 
TP FAB1 NC 0321 
TP FAB1 NC 0321 
TP FAB1 DEL RES 0314 
TP FAB1 NC 0321 
PVSA_CPU1: 0X01(BUS #1) 
SMBUS ADDRESS: 0XB0 
PVCCIN_CPU1: 0X00(BUS #1) 
VCCIN CPU1 (1 OF 4) 
WIWYNN CORPORATION ROOM=PROC_VRD_VCCIN_CPU1 



CHIP 
1/16W 
VR_PVCCIN_CPU1_PHASE2_RC 
CHIP 
1/16W 
TP FAB1 CO-LAY WITH TI PARTS 11/16 
TP FAB1 ADD NET NAME 12/04 
F S
F S
16V 
C95333-007 
0805 
C95333-007 
C9R11 
C95333-007 
10UF 
16V 
1
2
10% 
X6S 
0805 
0805 
X6S 
10% 
16V 
10UF 
C9P26 
2
VR_PVCCIN_CPU1_PH2_OCSET 
A_TSENSE_PVCCIN_CPU1 
VR_FET_SW_P12V_STBY_PVCCIN_CPU1 
VR_FET_SW_P12V_STBY_PVCCIN_CPU1 
VR_PVCCIN_CPU1_AIREF2 
H73688-001 
ISENSE_PVCCIN_CPU1_PH2_IMON 
VR_PVCCIN_CPU1_PHASE2 
VR_PVCCIN_CPU1_PWM2 
TP_PVCCINC_CPU1_PH2_GL_0 
TP_PVCCINC_CPU1_PH2_GL_1 
EU1D4 
2
39 
32 
1
34 
H73688-001 
31 
38 
37 
5
3
30 
4
25 
41 
6
33 
36 
10 
7
40 
IC 
35 
0.22UF 
10% 
C1E8 
0
RT15 
VR_PVCCIN_CPU1_PH1_BOOT 
G22178-002 
0402 
C1E25 1
VR_PVCCIN_CPU1_AIREF1 
A_TSENSE_PVCCIN_CPU1 
VR_PVCCIN_CPU1_PH1_OCSET 
TP_PVCCINC_CPU1_PH1_GL_0 
22.0UF 
20% 
4V 
C9P3 
E15431-004 
1
0402 
EMPTY 
1/16W 
68.1K 
R1E13 
0603V 
X6S 
20% 
4V 
22.0UF 
C1E3 
2
1
X6S 
E15431-004 
0603V 
2
IND-120NH-30-GP 
0.0 
5% 
2
VR_PVCCIN_CPU1_PHASE1_RC 
10% 
50V 
0402LF 
TP_PVCCINC_CPU1_PH1_GL_1 
ISENSE_PVCCIN_CPU1_PH1_IMON 
X7R 
1000PF 
CT27 
CT23 
1000PF 
0402LF 50V 
10% 
X7R 
0402LF 
A36096-046 
X7R 
10% 
50V CT26 
1000PF 
2
CT22 
1000PF 
50V 
10% 
X7R 
A36096-046 
0402LF 
2
1
R1E14 
68.1K 
1% 
1/16W 
EMPTY 
G21796-187 
1
1% 
1
2
0805 
C95333-007 
X6S 
10% 
16V 
1 C9P25 
10UF 
2
0805 
C95333-007 
X6S 
10% 
16V 
10UF 
C9P22 1
2
VR_PVCCIN_CPU1_PWM1 
16V 
C9R10 
10UF 1
10% 
X6S 2
0805 
1
2 C95333-007 
X6S 
10% 
10UF 
C9R7 
0402 
D97712-011 
X6S 
10% 
16V 
1.0UF 1
2
0402V 
A36096-030 
X7R 
10% 
16V 
2
0402 
A36096-104 
X7R 
10% 
C1D36 1
2
0.220UF 
16V 
16V 
2
C1E13 1
2
1.0UF 
16V 
10% 
X6S 
D97712-011 
0402 
2
1 C1E14 
0.1UF 
16V 
10% 
X7R 
A36096-030 
0402V 
2
1 1.0UF 
16V 
10% 
0402 
D97712-011 
X6S 
1C1E11 
0402 
2
0.220UF 
16V 
10% 
X7R 
A36096-104 
2
X7R 1 A36096-155 
0402 
10% 
0603 
RT17 
G22178-002 
0
CHIP 
1/10W 
VR_PVCCIN_CPU1_PH1_PHASE 
5.0% 
CHIP 
1/10W 
CT24 
0402V 
16V 
0.1UF 
10% 
X7R 
0.1UF 
CT25 
0603 5.0% 
A36096-030 
VR_PVCCIN_CPU1_PHASE1 
VR_PVCCIN_CPU1_PH1_BOOT_R 
X7R 
A36096-046 
1R3F-GP 
RT18 1R3F-GP 
A36096-046 
0402 
1 2
R9R2 
G21497-005 
5% 
0.0 0402 
VR_PVCCIN_CPU1_PH1_VCIN 
C1E6 
16V 
0.22UF 
C1E7 
L1E1 
L1D3 
RT16 
IND-120NH-30-GP 
0402 
2
X6S 
0603V 
E15431-004 
C1E9 
1 1
20% 
4V 
22.0UF 
C9R8 
22.0UF 
4V 
20% 
X6S 
0603V 
E15431-004 
G21796-187 
C1D35 
0.1UF 
0402 
D97712-011 
X6S 
16V 
1.0UF 
2
1 C1D34 C1E24 
10% 
C1E23 
G21497-005 
X7R 
35 
IC 
40 
7
10 
36 
33 
6
41 
25 
4
30 
3
EU1E2 
5
37 
38 
31 
34 
1
32 
39 
2
1
R9R11 
1
VR_PVCCIN_CPU1_PH2_BOOT 
VR_PVCCIN_CPU1_PH2_PHASE 
0402V 
A36096-030 
10% 
16V 
VR_PVCCIN_CPU1_PH2_BOOT_R 
A36096-155 
TP FAB1 CHANGE TO 0 OHM 0107 
TP FAB1 CHANGE RES TO 1 OHM 0603 0107 
TP FAB1 CHANGE TO 0 OHM 0107 
TP FAB1 CHANGE RES TO 1 OHM 0603 0107 
207 208 209 206 
206 
206 
206 
206 
207 208 209 206 
206 
206 
VR_PVCCIN_CPU1_PH2_VCIN 
10V 
0402 
GROUP=PWR_MLCC_CAP 
GROUP=PWR_MLCC_CAP 
GROUP=PWR_MLCC_CAP 
GROUP=PWR_MLCC_CAP 
IRMS=66A@DELTA_T<40C 
ISAT=94A@25C 
1% 
NOPOP 
1 OHM 
1% 
1/10W 
NOPOP 
1/10W 
1 OHM 
0603 
0603 
1UF 
10% 
10V 
0402 
1UF 
10% 
120NH 
DCR=0.17MOHM 
120NH 
DCR=0.17MOHM 
ISAT=94A@25C 
IRMS=66A@DELTA_T<40C 
SC1U10V2KX-4-GP 
SC1U10V2KX-4-GP 
1 2
1
2
NOPOP 
1
2
1
2
2
2
1
2
21
1
NOPOP 
1 2
21
1
DO NOT SCALE DRAWING 
TP FAB1 ADD NET NAME 12/04 TP FAB1 CO-LAY WITH TI PARTS 11/16 
TP FAB1 CO-LAY WITH TI PARTS 11/16 
TP FAB1 CO-LAY WITH TI PARTS 11/16 
TP FAB1 CO-LAY WITH TI PARTS 11/16 
TP FAB1 CO-LAY WITH TI PARTS 11/16 
SHEET 
B
AA
B
B
SIZE 
SCALE: 
234
1234
DEPARTMENT CODE 
1
DOCUMENT NUMBER REV 
PVCCIN_CPU1 
OUT 
OUT 
P5V_STBY 
P5V_STBY 
IN 
IN 
OUT 
PVCCIN_CPU1 
OUT 
OUT 
OUT 
1 2
2 1
2 1
1 2
207 OF 270 
Wed Feb 08 16:35:25 2017 
GL<1> 
GL<0> 
PGND<1> 
PGND<0> 
PGND<2> LGND 
VOS 
EN 
VDRV 
VCC 
VIN<0> VIN<1> 
PHASE 
REFIN 
BOOST 
PWM 
SW 
NC 
IOUT 
OCSET 
TOUT_FLT 
GL<1> 
GL<0> 
PGND<1> 
PGND<0> 
PGND<2> LGND 
VOS 
EN 
VDRV 
VCC 
VIN<0> VIN<1> 
PHASE 
REFIN 
BOOST 
PWM 
SW 
NC 
IOUT 
OCSET 
TOUT_FLT 
TDA21470 
TDA21470 
TP FAB1 CHANGE PN 0310 
TP FAB1 DEL NET 0309 
TP FAB1 CHANGE L1D3 PN 0122 
TP FAB1 DEL NET 0309 
TP FAB1 CHANGE PN 0310 
TP FAB1 CHANGE L1E1 PN 0122 
NOPOP 
NOPOP 
NOPOP 
NOPOP 
VCCIN CPU1 (2 OF 4) 
PLACE ON TOP 
PLACE ON TOP 
SPOF 
WIWYNN CORPORATION 
SPOF 
ROOM=PROC_VRD_VCCIN_CPU1 



CHIP 
1/16W 
VR_PVCCIN_CPU1_PHASE4_RC 
1/16W 
CHIP 
TP FAB1 ADD NET NAME 12/04 
F S
F S
TP FAB1 CHANGE TO 0 OHM 0107 
TP FAB1 CHANGE RES TO 1 OHM 0603 0107 
TP FAB1 CHANGE TO 0 OHM 0107 
206 
207 208 209 206 
206 
206 
206 
207 208 209 206 
206 
206 
2.5V 
VR_FET_SW_P12V_STBY_PVCCIN_CPU1 
VR_PVCCIN_CPU1_AIREF4 
VR_PVCCIN_CPU1_PH4_OCSET 
C1D17 
EU1D3 
IC 
EU1D1 IC 
GROUP=PWR_BULK_CAP 
699013-049 
C9R2 
GROUP=PWR_MLCC_CAP
GROUP=PWR_MLCC_CAP 
GROUP=PWR_MLCC_CAP 
GROUP=PWR_BULK_CAP GROUP=PWR_BULK_CAP GROUP=PWR_BULK_CAP GROUP=PWR_BULK_CAP GROUP=PWR_BULK_CAP GROUP=PWR_BULK_CAP 
GROUP=PWR_MLCC_CAP
E15431-004 
0603V 
X6S 
E15431-004 
C9P10 
0603V 
20% 
4V 
22.0UF 
C1D14 
22.0UF 
4V 
20% 
1
2
R1E3 
2
X6S 
1
3018 
2
3018 
ALUM 
2.5V 
699013-049 699013-049 
ALUM 
3018 
699013-049 
20% 
470UF 
1
2.5V 
ALUM 
3018 
ALUM 
3018 3018 
ALUM 
C9P18 
470UF 
1
2
20% 
2.5V 
3018 
1
470UF 
20% 2
C9P8 1 C9P5 
20% 
470UF 
ALUM 
C9P23 
2
470UF 
1
2.5V 
20% 20% 
2
1 C9R9 
2.5V 
470UF 
699013-049 
C9R3 
2
699013-049 
1
2
C9N24 
470UF 
20% 
2.5V 
699013-049 
ALUM 
1% 
IRMS=66A@DELTA_T<40C 
DCR=0.17MOHM 
ISAT=94A@25C 
120NH 
IND-120NH-30-GP 
L1D1 
IRMS=66A@DELTA_T<40C 
DCR=0.17MOHM 
ISAT=94A@25C 
120NH 
L1D2 
IND-120NH-30-GP 
0402 
10V 
10% 
1UF 
VR_PVCCIN_CPU1_PH4_VCIN 
C1D6 
0.22UF C1D5 
G21497-005 
C1D7 
1.0UF 
2
R9P8 
5% 
D97712-011 
C1D13 
0.1UF 
16V 
10% 
VR_PVCCIN_CPU1_PH4_BOOT_R 
16V 
0.22UF 
C1D16 1C1D15 
1UF 
VR_PVCCIN_CPU1_PH3_VCIN 
1
0.0 
R9P22 
2
D97712-011 
VR_PVCCIN_CPU1_PH3_BOOT_R 
EMPTY 
G21796-187 
TP_PVCCIN_CPU1_PH4_GL_0 
CT21 
10% 
A36096-030 
37 
H73688-001 
34 
35 
7
40 
31 
33 
39 
41 
1
6
5
2
10 
30 
25 
4
3 38 
32 
36 
CT16 
0.1UF 
16V 
10% 
X7R 
A36096-030 
0402V 
0603 5.0% 
TP_PVCCIN_CPU1_PH3_GL_0 
TP_PVCCIN_CPU1_PH3_GL_1 
0402V 
G22178-002 1/10W 
16V 
VR_PVCCIN_CPU1_PH3_BOOT 
VR_PVCCIN_CPU1_PH4_BOOT 
0
RT14 
0603 5.0% 
32 
39 
33 
TP_PVCCIN_CPU1_PH4_GL_1 
A_TSENSE_PVCCIN_CPU1 
VR_PVCCIN_CPU1_PH3_PHASE 
VR_PVCCIN_CPU1_PH4_PHASE 
VR_PVCCIN_CPU1_PWM4 
VR_PVCCIN_CPU1_AIREF3 
ISENSE_PVCCIN_CPU1_PH3_IMON 
VR_PVCCIN_CPU1_PH3_OCSET 
A_TSENSE_PVCCIN_CPU1 
ISENSE_PVCCIN_CPU1_PH4_IMON 
VR_PVCCIN_CPU1_PHASE3 
0402LF 
A36096-046 
X7R 
10% 
50V CT19 
1000PF 
X7R 
0.1UF 
0402LF 
A36096-046 
1000PF 
X7R 
10% 
50V 
CTI7 G21796-187 
EMPTY 
1/16W 
1% 
68.1K 
0402 
2
1
R1D55 
2
1/16W 
0402 
68.1K 
1% 
1
R1D54 31 
38 
35 
34 
6
41 
1
4
3
5
7
40 
25 
30 
H73688-001 
36 
2
37 
10 
1/10W 
CHIP 
G22026-038 
100.0 
2
1
1% 
0603 
0603V 
E15431-004 
X6S 
20% 
4V 
22.0UF 
2
1
0805 
2
C9P2 1
10% 
16V 
X6S 
10UF 
C95333-007 
X6S 2
1
0805 
C95333-007 
10% 
16V 
10UF 
C9P1 
C95333-007 
X6S 
C9P24 
10UF 
10% 
16V 
1
2
0805 
VR_PVCCIN_CPU1_PWM3 
10% 
16V 
C9P9 
10UF 1
2 X6S 
0805 
C95333-007 
C9P7 
10UF 
10% 
16V 
1
0805 
X6S 2
0805 
1
16V 
10% 
10UF 
C9P4 
C95333-007 
X6S 2
D97712-011 
10% 
2 X6S 
16V 
0402 
1 1.0UF 
C1D12 
A36096-030 
X7R 2
10% 
0402V 
16V 
1
X6S 
1
2
0402 
1C1D10 
16V 
2X7R 
10% 
0.220UF 
A36096-104 
0402 
0402 
A36096-155 
X7R 
10% 
16V 
1
2
0402 
D97712-011 
C1D23 
1.0UF 
10% 
16V 
1
X6S 2
10% 
X7R 
A36096-030 
0402V 
0.1UF 
C1D28 1
2
16V 
0402 
X6S 
10% 
16V 
1
2
0402 
A36096-104 
X7R 
10% 
2
16V 
0.220UF 
C1D20 1
2
X7R 
VR_FET_SW_P12V_STBY_PVCCIN_CPU1 
X6S 
20% 
4V 
E15431-004 
0603V 
1
2
0.0 0402 
1
CHIP 
G22178-002 
1/10W CHIP 
0
RT11 
0402LF 50V 
1000PF 
CT20 
X7R 
A36096-046 
CT18 
VR_PVCCIN_CPU1_PHASE4 
22.0UF 
C1D3 10% 
C95333-007 
X7R 0402LF 
10% 
50V 
1000PF A36096-046 
NOPOP 
1R3F-GP 
1 OHM 
RT12 
VR_PVCCIN_CPU1_PHASE3_RC 
1/10W 
1% 
NOPOP 
0603 
1 OHM 
1R3F-GP 
RT13 
1/10W 
0603 
0402 
5% 
1.0UF 
G21497-005 
10% 
0402 
A36096-155 
0402 
10V 
10% 
TP FAB1 CO-LAY WITH TI PARTS 11/16 
SC1U10V2KX-4-GP 
SC1U10V2KX-4-GP 
1
1
1
2
1
2
1
2
21
2
2
1
1
2
2
TP FAB1 CHANGE RES TO 1 OHM 0603 0107 
TP FAB1 ADD NET NAME 12/04 
21
21
NOPOP 
NOPOP 
DO NOT SCALE DRAWING 
TP FAB1 CO-LAY WITH TI PARTS 11/16 
TP FAB1 CO-LAY WITH TI PARTS 11/16 
TP FAB1 CO-LAY WITH TI PARTS 11/16 
TP FAB1 CO-LAY WITH TI PARTS 11/16 
TP FAB1 CO-LAY WITH TI PARTS 11/16 
SHEET 
B
AA
B
B
SIZE 
SCALE: 
234
1234
DEPARTMENT CODE 
1
DOCUMENT NUMBER REV 
PVCCIN_CPU1 
OUT 
OUT 
P5V_STBY 
P5V_STBY 
IN 
IN 
OUT 
PVCCIN_CPU1 
PVCCIN_CPU1 
OUT 
OUT 
OUT 
1 2
2 1
1 2
2 1
208 OF 270 
Wed Feb 08 16:35:26 2017 
GL<1> 
GL<0> 
PGND<1> 
PGND<0> 
PGND<2> 
LGND 
VOS 
EN 
VDRV 
VCC 
VIN<0> 
VIN<1> 
PHASE 
REFIN 
BOOST 
PWM 
SW 
NC 
IOUT 
OCSET 
TOUT_FLT 
GL<1> 
GL<0> 
PGND<1> 
PGND<0> 
PGND<2> 
LGND 
VOS 
EN 
VDRV 
VCC 
VIN<0> 
VIN<1> 
PHASE 
REFIN 
BOOST 
PWM 
SW 
NC 
IOUT 
OCSET 
TOUT_FLT 
TDA21470 
TDA21470 
TP FAB1 CHANGE L1D1 PN 0122 
TP FAB1 CHANGE L1D2 PN 0122 
TP FAB1 DEL NET 0309 
TP FAB1 DEL NET 0309 
TP FAB1 CHANGE PN 0310 
TP FAB1 CHANGE PN 0310 
NOPOP 
NOPOP 
NOPOP 
NOPOP 
VCCIN CPU1 (3 OF 4) 
PLACE ON TOP 
PLACE ON TOP 
SPOF 
WIWYNN CORPORATION 
SPOF ROOM=PVCCIN_CPU1_PWR_VR 
ROOM = PVCCIN_CPU1_DECAP_VR 
ROOM=PVCCIN_CPU1_PWR_VR 



CHIP 
F S
TP FAB1 CHANGE TO 0 OHM 0107 
TP FAB1 CHANGE RES TO 1 OHM 0603 0107 
TP FAB1 ADD NET NAME 12/04 
206 
206 
207 208 206 
206 
206 
71 
71 
206 
50V 
16V 
10% 10% 
0805 
2 X6S 
10UF 
C9N27 
H73688-001 
VR_FET_SW_P12V_STBY_PVCCIN_CPU1 
VR_FET_SW_P12V_STBY_PVCCIN_CPU1 
VR_PVCCIN_CPU1_PH5_BOOT_R 
16V 35 
EU1C3 IC 
VR_PVCCIN_CPU1_AIREF5 
ISENSE_PVCCIN_CPU1_PH5_IMON 
A_TSENSE_PVCCIN_CPU1 
2
X6S 
GROUP=PWR_MLCC_CAP
GROUP=PWR_MLCC_CAP 
C9P20 
22.0UF 
C1D24 
14V 
IRMS=66A@DELTA_T<40C 
DCR=0.17MOHM E15431-004 
20% 
X6S 
0603V 
E15431-004 
1
20% 
4V 
22.0UF 
2 0603V 
X6S 
2VR_PVCCIN_CPU1_PHASE5_RC 
ISAT=94A@25C 
120NH 
L1C2 
IND-120NH-30-GP 
IRMS=34A@DELTA_T<45C 
DCR=0.22MOHM 
ISAT=50A@25C 
80NH 
L1B2 
IND-80NH-1-GP 
TP_PVCCIN_CPU1_PH5_GL_1 
0402 
1
R1E7 
0.0 5% 
2
G21497-005 
1/16W CHIP 
G21497-005 
1/16W 
0402 
CHIP 
1
0.0 
R1E6 
2
5% 
100.0 
1/16W 
0402 
1 2
1% 
R1E4 
G21796-017 
0402 
2 X6S 
10% 
D97712-011 
1.0UF 1 C1C26 
0402V 
1
10% 
X7R 2 A36096-030 
16V 
0402 
10% 
16V 
2
1
2A36096-104 
X7R 
10% 
16V 
1C1C24 
0.220UF 
0402 
X7R 2
1
2
1% 
1/16W 
0402 
1.00K 
R1E5 
EMPTY 
G21796-026 
A31228-047 
2 OSCON 
2626 
16V 
20% 
1 C1C1 
270UF C1E18 
270UF 
2
1
2626 
20% 
16V 
OSCON 
A31228-047 
C1C2 
270UF 
1
2
2626 
20% 
16V 
OSCON 
A31228-047 
1
16V 
C95333-007 
7
31 
38 
37 
36 
34 
3
30 
25 
10 
40 
1
6
41 
5
4
VR_PVCCIN_CPU1_PWM5 
0402 
EMPTY 
1/16W 
1% 
1 68.1K 
R1D52 
2
X7R 
16V 
0402LF 
A36096-046 
X7R 
10% 
CT15 
1000PF 
X6S 
0805 
1
2 C95333-007 
16V 
10UF 
C9N26 
X7R 
50V 
0402LF 
A36096-046 CT14 
0
RT9 
10UF 
10% 
C9N25 1
2 X6S 
0805 
C95333-007 
1/16W 
0402 
1% 100.0 
1
R1E8 
2
G21796-017 
VSENSE_PVCCIN_CPU1_N 
VSENSE_PVCCIN_CPU1_SKT_VRTN 
VR_PVCCIN_CPU1_PH5_OCSET 
VR_PVCCIN_CPU1_PHASE5 
VR_PVCCIN_CPU1_PH5_BOOT 
VSENSE_PVCCIN_CPU1_SKT_VSEN 
VSENSE_PVCCIN_CPU1_P 
VR_PVCCIN_CPU1_PH5_PHASE 
CHIP 
1/10W 
10% 
33 
32 
0.1UF 
39 
0402V 
A36096-030 
CT13 
TP_PVCCIN_CPU1_PH5_GL_0 
0603 
G22178-002 5.0% 
1000PF 
G21796-187 
1% 
NOPOP 
10% 
1 OHM 
1R3F-GP 
RT10 
1/10W 
0603 
0402 
A36096-155 
1
21
0.0 
5% 
R9P32 
G21497-005 
0402 
1/16W 
D97712-011 
C1C25 
0.1UF 
C1D32 
VR_PVCCIN_CPU1_PH5_VCIN 
10% 
16V 
0.22UF 
C1D33 
1UF 
10% 
10V 
0402 
1.0UF C1C18 
TP FAB1 CO-LAY WITH TI PARTS 11/16 
SC1U10V2KX-4-GP 
DESIGN NOTE: 
1
2
1
2
1
2
21
RIPPLE GUIDE= +/- 5MV 
DC TOL = +/-17MV 
AC + RIPPLE TOL =  +/-22MV 
TP FAB1 CHANGE RES PN 0218 
ROUT AS DIFF PAIR 
10MIL WIDTH 
5MIL SPACING 
VBOOT=1.7V 
VOUT=1.8V(NOM) 
IOUT DI/DT = 778 A/US 
IOUT STEP=187 APP 
IOUT PK=228A 
IOUT TDC=88A 
LL=0.9MOHM 
SW FREQ=625 KHZ 
21
21
NOPOP 
DO NOT SCALE DRAWING 
TP FAB1 CO-LAY WITH TI PARTS 11/16 
TP FAB1 CO-LAY WITH TI PARTS 11/16 
SHEET 
B
AA
B
B
SIZE 
SCALE: 
234
1234
DEPARTMENT CODE 
1
DOCUMENT NUMBER REV 
IN 
IN 
P5V_STBY 
P12V_STBY 
OUT 
OUT 
PVCCIN_CPU1 
IN 
PVCCIN_CPU1 
OUT 
OUT 
IN 
1 2
1 2
INPUT FILTER 
SOCKET SIDE 
PVCCIN CPU1 VOLTAGE SENSE 
VR CONTROLLER SIDE 
209 OF 270 
Wed Feb 08 16:35:26 2017 
GL<1> 
GL<0> 
PGND<1> 
PGND<0> 
PGND<2> 
LGND 
VOS 
EN 
VDRV 
VCC 
VIN<0> 
VIN<1> 
PHASE 
REFIN 
BOOST 
PWM 
SW 
NC 
IOUT 
OCSET 
TOUT_FLT 
TP FAB1 CHANGE PN 0310 
TDA21470 
TP FAB1 DEL NET 0309 
TP FAB1 CHANGE L1C2 PN 0122 
TP FAB1 CHANGE L1B2 PN 0122 
TP FAB1 DELETE ADM4073, CAP, RES 0321 
NOPOP 
NOPOP 
VCCIN CPU1 (4 OF 4) 
PLACE ON TOP 
WIWYNN CORPORATION 
SPOF 
ROOM=PVCCIN_CPU1_PWR_VR 
ROOM = PVCCIN_CPU1_FILTER_VR ROOM = PVCCIN_CPU1_VSENSE_VR 



1/16W 
CHIP 
X7R 
A36096-104 
1% 
VR_PVSA_CPU1_BIREF1 
VR_FET_SW_P12V_STBY_PVCCIN_CPU1 
C9N22 
22.0UF 
20% 20% 1.0% 
699013-049 
470UF 
C9N20 
3018 
ALUM 
2.5V 
20% 
1
2
L1C1 
IND-300NH-20-GP 
0402 R9N3 
VR_PVSA_CPU1_VCIN 
G21497-005 
5% 
0.0 
21
C1C4 
10% 
2
16V 
0.22UF 
X7R 
0402 
A36096-155 
2
1
10% 
0402 
X7R 
16V 
0.220UF 
C1C12 
10% 
16V 
1
D97712-011 
X6S 2
0402 
X7R 
1
2
10% 
0.1UF 
0402V 
16V 
A36096-030 
C1C15 1
2
16V 
10% 
X6S 
0402 
D97712-011 
1.0UF 
1
0402 
100.0 
1/16W 
R1C12 
2
G21796-017 
G21497-005 
2
5% 
R1C7 
1
CHIP 
0.0 
0402 
1/16W 
1
0.0 
1/16W 
2
5% 
R1C5 
G21497-005 
CHIP 
0402 
G21796-017 
2
1% 
R1C4 
1
100.0 
0402 
1/16W 
0402 
G21796-026 
EMPTY 
R1C6 
1% 
1/16W 
1
2
1.00K 
1
2
16V 
10UF 
C9N13 
10% 
X6S 
C95333-007 
0805 
1
2 X6S 
10% 
C9N19 
0805 
C95333-007 
16V 
10UF 
C95333-007 
X6S 
10UF 1
2
10% 
16V 
0805 
C9N21 
10 
7
2
5
EU1C1 
IC 
30 
3
25 
6
1
39 
34 
4
40 
33 
35 
36 
H73684-001 
32 
41 
38 
37 
31 
R1C37 
1
2
68.1K 
1% 
1/16W 
EMPTY 
G21796-187 
0402 
0402V 
CT57 
0.1UF 
16V 
10% 
A36096-030 
0402LF 
CT55 
50V 
A36096-046 
X7R 
10% 
1000PF 
CT56 X7R 
0402LF 
1000PF A36096-046 
50V 
0
RT37 
5.0% 
G22178-002 
0603 
CHIP 
1/10W 
ISENSE_PVSA_CPU1_IMON 
VR_PVSA_CPU1_OCSET 
A_TSENSE_PVSA_CPU1 
VR_PVSA_CPU1_PHASE 
VR_PVSA_CPU1_BOOT_R 
VR_PVSA_CPU1_PWM 
TP_PVSA_CPU1_GL_0 
VR_PVSA_CPU1_PHASE_SW 
TP_PVSA_CPU1_GL_1 
VSENSE_PVSA_CPU1_SKT_VSEN 
VSENSE_PVSA_CPU1_P 
VR_PVSA_CPU1_BOOT 
VSENSE_PVSA_CPU1_SKT_VRTN VSENSE_PVSA_CPU1_N 
10% 
1R3F-GP 
RT38 
1C1C3 
1.0UF 
C1C17 C1C5 
ALUM 
699013-049 
3018 
2
1
20% 
470UF 
C9N11 
VR_PVSA_CPU1_PHASE_SW_RC 
1
2
1
2
C1C19 
22.0UF 
4V 
X6S 
E15431-004 
0603V 
4V 
X6S CHIP 
1/16W 
51.1 
R9N4 
0402 0603V 
E15431-004 G21796-208 
TP FAB1 CHANGE TO 0 OHM 0107 
206 
206 
206 
206 
73 
206 
73 206 
GROUP=PWR_BULK_CAP GROUP=PWR_BULK_CAP 
GROUP=PWR_MLCC_CAP 
GROUP=PWR_MLCC_CAP 
IRMS=66A@DELTA_T<40C 
DCR=0.17MOHM 
0603 
NOPOP 
ISAT=33A@25C 
300NH 
1/10W 
1% 
1 OHM 
1UF 
0402 
10% 
10V 
2.5V 
SC1U10V2KX-4-GP 
DESIGN NOTE: 
ROUT AS DIFF PAIR 
DC TOL = +/-5MV 
RIPPLE = +/- 10MV 
IOUT STEP=5A/US 
VBOOT=0.9V 
10MIL WIDTH 
5MIL SPACING 
SW FREQ=520 KHZ 
IOUT DI/DT =20A/US 
IOUT TDC=15A 
IOUT PK=16A 
TOTAL TOL = 0.917MAX/0.779VMIN 
VOUT=0.85V (TYP) SVID 
2
NOPOP 
21
1
1
2
2
1
21
2
1
DO NOT SCALE DRAWING 
TP FAB1 CO-LAY WITH TI PARTS 11/16 
TP FAB1 CO-LAY WITH TI PARTS 11/16 
TP FAB1 CO-LAY WITH TI PARTS 11/16 
SHEET 
B
AA
B
B
SIZE 
SCALE: 
234
1234
DEPARTMENT CODE 
1
DOCUMENT NUMBER REV 
PVSA_CPU1 
OUT 
IN 
PVSA_CPU1 
PVSA_CPU1 
P5V_STBY 
IN 
IN 
OUT 
OUT 
OUT 
IN 
1 2
2 1
SOCKET SIDE 
PVSA CPU0 VOLTAGE SENSE 
VR CONTROLLER SIDE 
210 OF 270 
Wed Feb 08 16:35:26 2017 
GL<1> 
GL<0> 
PGND<1> 
PGND<0> 
PGND<2> LGND 
VOS 
EN 
VDRV 
VCC 
VIN<0> VIN<1> 
PHASE 
REFIN 
BOOST 
PWM 
SW 
NC 
IOUT 
OCSET 
TOUT_FLT 
TDA21460 
TP FAB1 ADD NET NAME 12/04 
TP FAB1 CHANGE RES TO 1 OHM 0603 0107 
TP FAB1 DEL NET 0309 
TP FAB1 CHANGE PN 0310 
TP FAB1 CHANGE L1C1 PN 0122 
NOPOP 
NOPOP 
VSA CPU1 
PLACE ON TOP 
SPOF 
WIWYNN CORPORATION 
ROOM=PVSA_CPU1_PWR_VR 
ROOM = PVSA_CPU1_DECAP_VR ROOM = PVSA_CPU1_VSENSE_VR 



A36096-046 
0402 
A_TSENSE_PVCCIO_CPU0 
G21796-009 
VSENSE_PVCCIO_CPU0_AVSP 
ISENSE_PVCCIO_CPU0_PH1_IMON 
100.0K 
1/16W 
RF13 
150.0 
0402 
G21796-017 
EMPTY 
SVID_CLK_PVCCIO_CPU0 
1/16W 
0402 
G85996-004 
0.1% 1.0K CHIP 
VR_PVCCIO_CPU0_EN 
CF13 
G21796-003 
G21796-026 
0402 
1000PF 
SVID_ALERT0_CPU0_R_N 
0402 CHIP 1/16W 
R3P20 
2
G21796-250 
G21796-082 
0402 0402 
G21796-043 
4.02K 1
R3N22 
2
1/16W 
1% 
CHIP 
H89187-001 
R3N31 
1/16W 
CHIP 
1% 
3.16K 
5% 
22.1 
1/16W 
1.00K 
PU_VR_PVCCIO_CPU0_FAULT1 32 
31 
2
1
FM_PVCCIO_CPU0_EN 
PWRGD_PVCCIO_CPU0 
VR_PVCCIO_CPU0_PWM1 
SVID_ALERT_PVCCIO_CPU0 
SMB_VR_STBY_LVC3_SCL 
SMB_VR_STBY_LVC3_SDA 
VSENSE_PVCCIO_CPU0_AVSN 
SVID_VDIO_PVCCIO_CPU0 
VR_PVCCIO_CPU0_VD12 
VR_PVCCIO_CPU0_VINSEN 
SVID_DIO0_CPU0_R 
49.9 
G21796-047 
CHIP 2
1
1% 
R3P17 
1
220PF 
C4W1 
2
8
19 
23 26 
25 
36 
33 
34 
14 
24 
27 
13 
18 
16 
12 
9
5
28 
7
6
15 
39 
4
20 
38 
11 
40 
10 
22 
21 
IC 
EU3P1 
37 
35 
29 
30 
R3P21 
CHIP 
0.0 5% 0402 
R3P26 
2
1 C3N39 
50V 
0402LF 
A36096-050 
10% 
X7R 
220PF 
1
1/16W 
1% 
R3N19 
10.0 
CHIP 
G21796-066 
0402 
2
2 X7R 
10% 
1 C3P6 
0402LF 
50V 
2 CHIP 
1% 
R3P18 
1
0402 
CHIP 
G21497-005 
2
0.0 1/16W 
1
R3P1 
2 EMPTY 
0402 
G21796-311 
1/16W 
1
R3N23 
2.26K 
1.0% 
1
1.0% 
0402 
CHIP 2
G21796-026 
1/16W 
R3P25 
1% 
1 1.00K 
1% 
CHIP 
0402 
2
2
1% 
CHIP 
1% 
R3P15 
1/16W 1 2
0402 
1
2
5% 
1/16W 
CHIP 
0402 
0.0 
G21497-005 
R3P22 
2
1 0.1UF 
C3P7 
0402V 
A36096-030 
X7R 
16V 
10% 
C3P3 
1.0UF 
0402V 
D97712-004 
X6S 
10% 
6.3V 
1/16W 
5% 
R3P11 
0402 
2
CHIP 
1
0.0 
2
1
X7R 
C3P5 
0402V 
10% 
16V 
0.1UF 
A36096-030 2
1
X6S 
6.3V 
0402V 
10% 
1.0UF 
D97712-004 
C3P4 
R3P13 
1% 
1
2
100.0 
0402 
0402V 
10% 
R3P16 
1.5K 1
1 100.0K 
R3P12 
A36096-030 
16V 
0.1UF 
C3P2 
SVID_CLK0_CPU0_R 
CHIP 
1/16W 
1/16W 
CHIP 
G21796-160 
1/16W X7R 
VR_PVCCIO_CPU0_VINSEN 
41 
G21497-005 
10% 
X7R 50V 
0402LF 
A36096-050 
VR_PVCCIO_CPU0_AVSP 
1/16W 
G21497-005 
SC22P50V2JN-4GP 
0402 
G21796-010 
VR_PVCCIO_CPU0_AIREF1 
1% 
1/16W 
PWRGD_PVCCIO_CPU0_R 
IRQ_PVCCIO_CPU0_VRHOT_N 
17 
3
VR_FET_SW_P12V_STBY_PVCCIO_CPU0 
VR_PVCCIO_CPU0_VD12 
TP FAB1 CHANGE RES 0408 
TP FAB3 CHANGE RES 0804 
TP FAB3 CHANGE CAP 0912 
212 
212 
212 
194 201 21 
190 
118 190 
212 
138 159 193 194 201 206 
213 215 218 223 226 235 
212 
211 
211 
21 194 201 
21 194 201 
211 
212 
211 
0402 
50V 
NPO 
22PF 5% 
GROUP=POWER_FAIR 
GROUP=POWER_FAIR 
VR_PVCCIO_CPU0_XADDR2 
VR_PVCCIO_CPU0_VDD 
VR_PVCCIO_CPU0_XADDR1 
DESIGN NOTE: 
DESIGN NOTE: 
TP FAB1 DELETE RES 0203 21
1
1
2
2
1 2
2
1
2
1
DO NOT SCALE DRAWING 
INFINEON:NOPOP 
RF13 & CF13 
FAIRCHILD:POP 
SHEET 
B
AA
B
B
SIZE 
SCALE: 
234
1234
DEPARTMENT CODE 
1
DOCUMENT NUMBER REV 
IN 
IN 
OUT 
IN 
P3V3_STBY 
OUT 
BI 
OUT 
IN 
IN 
IN 
IN 
IN 
OUT 
OUT 
PVCCIO_CPU0 
IN 
P3V3_STBY 
OUT 
PVCCIO_CPU0 
OUT 
211 OF 270 
Wed Feb 08 16:35:27 2017 
PXE1110C 
AVRRDY 
PINALRT_N 
THPAD 
BPWM1 
APWM1 
SDA 
SCL 
VCLK 
VDIO 
RESET_N 
XADDR1 
XADDR2 
ATSEN 
AISEN1 AIREF1 
VDD 
BTSEN 
BISEN1 
BIREF1 
DNC<0> DNC<1> DNC<2> 
DNC<4> 
GND<0> GND<1> 
VRHOT_N 
VALRT_N 
AVSEN 
AVREF 
BVSEN 
BVREF 
VINSEN IINSEN 
VD12 
DNC<3> 
MP0 MP1 MP2 
MP3 MP4 
AVREN 
TP FAB1 CO-LAY WITH FAIRCHILD PARTS 1203 
TP FAB1 ADD CAP 0218 TP FAB1 NC 0321 TP FAB1 NC 0321 
TP FAB1 NC 0321 
ROOM = PVCCIO_CPU0 
BOM_COST = PROC_VRD_PVCCIO_CPU0 
TP FAB1 DEL RES 0314 
TP FAB1 NC 0321 
TP FAB1 NC 0321 TP FAB1 DEL NETS 0309 
TP FAB1 POP RES 0316 
TP FAB1 NC 0321 
TP FAB1 NC 0321 
PVCCIN_CPU0: 0X02(BUS #1) 
SVID ADDRESS 
SMBUS ADDRESS: 0X94 
PVCCIO CPU0 (1 OF 2) 
WIWYNN CORPORATION 



1/16W 
CHIP 
699013-049 
20% 
1
699013-049 
C22W31 
IND-100NH-35-GP 
VSENSE_PVCCIO_CPU0_AVSP 
VR_FET_SW_P12V_STBY_PVCCIO_CPU0 
C3N34 
0805 
L7C1 
C22W29 
C7C17 
VR_PVCCIO_CPU0_PH1_BOOT_R 
X7R 
X6S 
L7C2 
ISENSE_PVCCIO_CPU0_PH1_IMON 
VR_PVCCIO_CPU0_AIREF1 
EU7C1 
31 
4
0.22UF 
X7R 
A36096-155 
0402 
6
A_TSENSE_PVCCIO_CPU0 
VR_PVCCIO_CPU0_OCSET 
VR_PVCCIO_CPU0_PH1_SW 
VR_PVCCIO_CPU0_PWM1 
VR_PVCCIO_CPU0_PH1_VCIN 
TP_PVCCIO_CPU0_GL_0 
TP_PVCCIO_CPU0_GL_1 
37 
32 
40 
41 
IC 
3
30 
25 
36 
10 
5
1
35 
7
2
39 
33 H73684-001 
34 
38 
VR_PVCCIO_CPU0_PH1_SW_RC 
1000PF 
50V 
10% 
X7R 
A36096-046 
0402LF 
1R3F-GP 
A36096-046 
0402LF 
VR_FET_SW_P12V_STBY_PVCCIO_CPU0 
R7C3 
X6S 
E15431-004 
0603V 0603V 
E15431-004 
22.0UF 
C3N38 
3018 
470UF 
20% 
2.5V 
ALUM 
1
22
1
ALUM 
2.5V 
20% 
470UF 
C3N35 
3018 
699013-049 2
ALUM 
2.5V 
470UF 
3018 
C3N26 
IND-150NH-56-GP 
C7C18 1C7C20 
2
R3N7 
1
0.0 
G21497-005 
5% 0402 
C7C7 C7C8 C22W32 C22W33 C22W30 C22W28 
C7C6 1
4V VR_PVCCIO_CPU0_PH1_PHASE 
VR_PVCCIO_CPU0_PH1_BOOT 
VSENSE_PVCCIO_CPU0_AVSN 
VSENSE_PVCCIO_CPU0_SKT_VSEN 
VSENSE_PVCCIO_CPU0_SKT_VRTN 
1.0% 
51.1 1
2
20% 
2
1
G21796-017 
1/16W CHIP 
0402 100.0 1% 
R3N21 
G21796-017 
1/16W 
100.0 1% 
R3N20 
CHIP 
0402 
0402V 
A36096-030 
EMPTY 
10% 
16V 
0.1UF 
C3P1 
10% 
C95333-007 2 X6S 
16V 
1 10UF 
C95333-007 2 X6S 
16V 
0805 
10% 
1 10UF 
C3N33 
10% 
X6S 
C95333-007 
0805 
2
16V 
10UF 1 C3N36 
1.0UF 
16V 
10% 
D97712-011 
0402 
2
1 C7C12 
A36096-030 
10% 
2
1 C7C11 
0.1UF 
X7R 
0402V 
16V 
1C7C14 
0402 
2X7R 
10% 
16V 
A36096-104 
0.220UF 
D97712-011 
X6S 
1
2
10% 
0402 
16V 
1.0UF 
10% 
16V 
2
1/10W G22178-002 
CHIP 
5.0% 
0
0603 
RT47 
10% 
50V 
CT71 
1000PF 
0402V 
A36096-030 
X7R 
10% 
CT70 16V 
0.1UF 
N_A 
SH3P2 
21
SH3P1 
N_A 
1 2
0402 
G21796-187 
EMPTY 
1/16W 
R7C25 
1% 
68.1K 
CT72 
4V 
2 X6S 
22.0UF 
20% 
C7C10 
RT48 
0402 
G21796-208
CHIP 
1/16W 
TP FAB1 CHANGE TO 0 OHM 0107 
211 
211 
211 
211 
211 
211 
39 
39 
0805 
X6S 
16V 
20% 
100NH 
16V 
0805 0805 
1 OHM 
1% 
1/10W 
NOPOP 
DCR=0.17MOHM 
IRMS=66A@DELTA_T<40C 
ISAT=75A@25C 
GROUP=PWR_BULK_CAP GROUP=PWR_BULK_CAP GROUP=PWR_BULK_CAP 
GROUP=PWR_MLCC_CAP
GROUP=PWR_MLCC_CAP 
150NH 
IRMS=29A@DELTA_T<45C 
DCR=0.16MOHM 
ISAT=16A@25C 
0402 
10V 
10% 
1UF 
0805 
X6S 
16V 
20% 
22UF 
X6S 
16V 
X6S 
16V 
20% 
22UF 
X6S 
16V 
20% 
22UF 22UF 22UF 
20% 
16V 
X6S 
0805 0805 
X6S 
20% 
22UF 
X6S 
0805 
16V 
20% 
22UF 
0805 
20% 
22UF 
0603 SC22U16V5MX-4-GP 
SC22U16V5MX-4-GP 
SC22U16V5MX-4-GP 
SC22U16V5MX-4-GP 
SC22U16V5MX-4-GP 
SC1U10V2KX-4-GP 
SC22U16V5MX-4-GP 
SC22U16V5MX-4-GP 
SC22U16V5MX-4-GP 
DESIGN NOTE: 
PUT TOGETHER PUT TOGETHER 
TOTAL TOL = 1.057VMAX/0.937VMIN 
IOUT TDC=14.44A 
DC TOL = +/-5MV 
IOUT PK= 21.44A 
VBOOT=1.0V 
SW FREQ=641 KHZ 
IOUT DI/DT =22 A/US 
IOUT STEP=14APP 
RIPPLE = +/- 10MV 
VOUT=1.0V (TYP) SVID 
1
21
21
2
21
1 2
2
1
1
2
NOPOP 
DO NOT SCALE DRAWING 
TP FAB1 CO-LAY WITH TI PARTS 11/16 
TP FAB1 CO-LAY WITH TI PARTS 11/16 
TP FAB1 CO-LAY WITH TI PARTS 11/16 
SHEET 
B
AA
B
B
SIZE 
SCALE: 
234
1234
DEPARTMENT CODE 
1
DOCUMENT NUMBER REV 
PVCCIO_CPU0 
OUT 
PVCCIO_CPU0 
OUT 
IN 
IN 
P5V_STBY 
P12V_STBY 
IN PVCCIO_CPU0
OUT 
OUT 
OUT 
2
2 1
2 1
2
2 1
1 2
1 2
2 1
2 1
2 1
1
1
212 OF 270 
Wed Feb 08 16:35:27 2017 
GL<1> 
GL<0> 
PGND<1> 
PGND<0> 
PGND<2> LGND 
VOS 
EN 
VDRV 
VCC 
VIN<0> VIN<1> 
PHASE 
REFIN 
BOOST 
PWM 
SW 
NC 
IOUT 
OCSET 
TOUT_FLT 
TP FAB1 CHANGE ONE 100UF CPA TO FOUR 22UF CAPS 0107
TP FAB1 CHANGE L7C1 PN 0122 
ROUTE AS DIFF PAIR 
5MIL SPACING 
5MIL WIDTH 
SOCKET SIDE VR CONTROLLER SIDE 
TP FAB1 CHANGE L7C2 PN 0122 
TP FAB1 CHANGE PN 0310 
TP FAB1 ADD NET NAME 12/04 
TP FAB1 CHANGE RES TO 1 OHM 0603 0107 
TDA21460 
TP FAB1 DEL NET 0309 
NOPOP 
NOPOP 
PVCCIO CPU0 (2 OF 2) 
BOOM = PROC_VRD_PVCCIO_CPU0 
ROOM = PVCCIO_CPU0 
SPOF 
PLACE ON TOP 
ROOM= PVCCIO_CPU0 
WIWYNN CORPORATION 
SPOF 



X7R 28 
19 
G21796-009 
1% 
CHIP 
CHIP 
1/16W 
SC22P50V2JN-4GP 
0.1% 
G85996-004 
RF14 1.0K 
G21796-003 
1/16W 
VR_PVCCIO_CPU1_AIREF1 
0402 
1/16W 
EMPTY 
G21796-017 
0402 
VR_PVCCIO_CPU1_EN 
CF14 
SVID_VDIO_PVCCIO_CPU1 
10% 
CHIP 
G21796-043 G21796-043 
0402 
CHIP 
1% 
R4E2 
3.16K 
1/16W 
2
1
0402 
1% 
R4D64 
3.16K 
1/16W 
2
1
24 
VR_PVCCIO_CPU1_AVSP 
IRQ_PVCCIO_CPU1_VRHOT_N 
SVID_ALERT_PVCCIO_CPU1 
VR_PVCCIO_CPU1_PWM1 
PU_VR_PVCCIO_CPU1_FAULT1 
PWRGD_PVCCIO_CPU1_R 
SVID_ALERT0_CPU1_R_N 
VR_PVCCIO_CPU1_VD12 
PWRGD_PVCCIO_CPU1 
VSENSE_PVCCIO_CPU1_AVSP 
25 
26 
36 
33 
34 
7
6
30 
40 
16 
29 
20 
38 
21 
10 
9
11 
17 
3
5
2
23 
27 
22 
15 
8
1
4
32 
31 
35 
41 
14 
13 
18 
VR_FET_SW_P12V_STBY_PVCCIN_CPU0 
EMPTY 
G21796-010 
1% 
R6P40 
100.0K 
1/16W 
0402 
R6P41 
0.0 
CHIP 
0402 
C4D31 
0402V 
X6S 
10% 
1 1.0UF 
6.3V 
D97712-004 
0402 10.0 
1 2
G21796-066 
1% 
1/16W CHIP 
X7R 
C4D44 
2
1 10% 220PF 
50V 
0402LF 
C4D33 
0402LF 
1
50V 
2
1000PF 
A36096-046 
R4D49 
0402 
1.00K 
1% 
CHIP 
1/16W 150.0 
21/16W 1
0.0 
1/16W 
G21497-005 
R4D54 
5% 0402 
CHIP 
X7R 
0402V 
A36096-030 
10% 
16V 
0.1UF 
C4D38 
1 1.5K 
1% 
CHIP 
R4D60 
1 100.0K 
1% 
0402 
R6P33 
110 
2 EMPTY 
1/16W 
1% 
1
R4D47 
0.0 
5% 
1/16W 
CHIP 
G21497-005 
0402 
1.0UF 
C4D36 
6.3V 
10% 
0402V 
D97712-004 
X6S 
1
CHIP 
R4D56 
5% 
2
0.0 1/16W 
G21497-005 
0402 
1% 
CHIP 
1/16W 
0402 
1.00K 
R4D42 
G21796-026 
2
0402 
G21796-311 
EMPTY 
1/16W 
1.0% 
1 2.26K 
R6P49 
0402 
2
1.0% 
CHIP 1/16W 
22.1 
1
R4D46 
G21796-250 
16V 
10% 
X7R 
0402V 
1
2
A36096-030 
0.1UF 
C4D32 
1
10% 
50V 
0402LF 
X7R 
A36096-050 
2
SVID_CLK0_CPU1_R 
2
0402V 
X7R 
16V 
0.1UF 
C4D40 
A36096-030 
10% 
2
0402 
G21796-160 
CHIP 
2
R4E7 
SMB_VR_STBY_LVC3_SCL 
SMB_VR_STBY_LVC3_SDA 
220PF 
C4W2 
SVID_DIO0_CPU1_R 
VR_PVCCIO_CPU1_VD12 
1/16W 
5% 
VR_PVCCIO_CPU1_VINSEN 
H89187-001 
37 
12 
0402 
G21796-026 
1/16W 
0402 
G21497-005 
VR_PVCCIO_CPU1_VINSEN 
SVID_CLK_PVCCIO_CPU1 
EU4D5 
IC 
39 
VSENSE_PVCCIO_CPU1_AVSN 
A36096-050 
R4D57 
R6P35 
100.0 
1% 
G21796-203 
R4D51 
ISENSE_PVCCIO_CPU1_PH1_IMON 
A_TSENSE_PVCCIO_CPU1 
FM_PVCCIO_CPU1_EN 
TP FAB1 CO-LAY WITH FAIRCHILD PARTS 1203 
TP FAB3 CHANGE CAP 0912 
TP FAB4 CHANGE RF14 TO 909OHM FOR VR FAILCHILD, SINGLE SIDE BOM 20170123 
TP FAB1 CHANGE R4D64 AND NOPOP R4E2 0408 
TP FAB3 CHANGE R4D64 AND POP R4E2 0804 
214 
214 
193 206 55 
213 
191 
214 
55 193 206 
138 159 193 194 201 206 211 
215 218 223 226 235 
55 193 206 
213 
213 
213 
214 
214 
214 
190 
GROUP=POWER_FAIR 
FAIR_SS=064.9090D.M001 
GROUP=POWER_FAIR 
5% 
0402 
50V 
NPO 
22PF 
VR_PVCCIO_CPU1_XADDR2 VR_PVCCIO_CPU1_VDD 
VR_PVCCIO_CPU1_XADDR1 
DESIGN NOTE: 
DESIGN NOTE: 
21
21
1
2
2
1
1 2
1
2
21
2
1
1
2
1
2
1
2
1
2
DO NOT SCALE DRAWING 
FAIRCHILD:POP 
INFINEON:NOPOP 
RF14 & CF14 
SHEET 
B
AA
B
B
SIZE 
SCALE: 
234
1234
DEPARTMENT CODE 
1
DOCUMENT NUMBER REV 
IN 
IN 
IN 
BI 
OUT 
OUT 
OUT 
IN 
IN 
IN 
IN 
IN 
IN 
OUT 
OUT 
OUT 
PVCCIO_CPU1 PVCCIO_CPU1 
P3V3_STBY 
OUT 
P3V3_STBY 
213 OF 270 
Wed Feb 08 16:35:27 2017 
PXE1110C 
AVRRDY 
PINALRT_N 
THPAD 
BPWM1 
APWM1 
SDA 
SCL 
VCLK 
VDIO 
RESET_N 
XADDR1 
XADDR2 
ATSEN 
AISEN1 AIREF1 
VDD 
BTSEN 
BISEN1 
BIREF1 
DNC<0> DNC<1> DNC<2> 
DNC<4> 
GND<0> GND<1> 
VRHOT_N 
VALRT_N 
AVSEN 
AVREF 
BVSEN 
BVREF 
VINSEN IINSEN 
VD12 
DNC<3> 
MP0 MP1 MP2 
MP3 MP4 
AVREN 
TP FAB1 DEL NETS 0309 
TP FAB1 DELETE RES 0203 
ROOM = PVCCIO_CPU1 
TP FAB1 NC 0321 
TP FAB1 NC 0321 
TP FAB1 NC 0321 
TP FAB1 ADD CAP 0218 
TP FAB1 NC 0321 
TP FAB1 DEL RES 0314 
TP FAB1 NC 0321 
TP FAB1 NC 0321 
BOM_COST = PROC_VRD_PVCCIO_CPU1 
TP FAB1 NC 0321 
SVID ADDRESS 
PVCCIO_CPU1: 0X02(BUS #1) 
SMBUS ADDRESS: 0XB4 
PVCCIO CPU1 (1 OF 2) 
WIWYNN CORPORATION 



CHIP 
1/16W 
VR_PVCCIO_CPU1_PH1_SW_RC 
X6S 
C95333-007 
VSENSE_PVCCIO_CPU1_SKT_VSEN 
C4E13 
VR_PVCCIO_CPU1_AIREF1 
34 
A_TSENSE_PVCCIO_CPU1 
38 
VR_PVCCIO_CPU1_PH1_SW 
C4E9 
VR_PVCCIO_CPU1_PH1_PHASE 
VR_FET_SW_P12V_STBY_PVCCIN_CPU0 
VR_FET_SW_P12V_STBY_PVCCIN_CPU0
C22W18 
2
2.5V 
20% 
470UF 
C22W20 C22W21 
0402 
G21796-208
CHIP 
1/16W 
1.0% 
51.1 
R7R1 
C4E7 
470UF 
20% 
3018 
699013-049 
2.5V 
ALUM 
1
2
C6R12 
3018 
699013-049 
ALUM 
1470UF 
20% 
3018 
C6R5 
699013-049 
2.5V 
ALUM 
1
2
IND-150NH-56-GP 
L4E2 
C4E23 
C4E28 
2 X7R 
A36096-155 
0402 
G21497-005 
5% 
VR_PVCCIO_CPU1_PH1_VCIN 
R6R5 
2
0.0 
1
C4E22 
1.0UF 
C22W14 C22W13 C4E14 C22W15 C4E8 C22W17 C22W16 C22W19 
G21796-187 
0402 
1R3F-GP 
RT42 
X7R 
10% 
50V 
VSENSE_PVCCIO_CPU1_SKT_VRTN 
ISENSE_PVCCIO_CPU1_PH1_IMON 
TP_PVCCIO_CPU1_GL_1 
TP_PVCCIO_CPU1_GL_0 
VR_PVCCIO_CPU1_OCSET 
VR_PVCCIO_CPU1_PH1_BOOT 
VR_PVCCIO_CPU1_PWM1 
VR_PVCCIO_CPU1_PH1_BOOT_R 
2
10% 
1
16V 
0.1UF 
C95333-007 
10% 
16V 
0805 
2
1
X6S 
10UF 
C6R8 C6R10 
0805 
2
1 10UF 
16V 
10% 
C95333-007 
C6R14 
10UF 
10% 
16V 
X6S 
1
2
0805 
10% 
2 X6S 
D97712-011 
0402 
C4E15 
1.0UF 
16V 
1
2
1C4E18 
0.220UF 
16V 
10% 
X7R 
A36096-104 
0402 
0.1UF 
16V 
0402V 
A36096-030 
X7R 
10% 
2
1
16V 
1
2 X6S 
10% 
D97712-011 
0402 
0402 
10% 
16V 
0.22UF 1
G22178-002 1/10W 
0603 5.0% 
CHIP 0
RT41 
1000PF 
CT62 
0402LF 
A36096-046 
0402V 
A36096-030 
X7R 
10% 
16V CT63 
0.1UF 
0402LF 
A36096-046 
X7R 
10% 
50V CT61 
1000PF EMPTY 
1/16W 
1% 
68.1K 
R4E21 
31 
33 
32 
36 
35 
41 
H73684-001 
EU4E2 
IC 
37 
10 
2
40 
5
7
25 
3
4
1
6
39 
30 
C3D27 
0402V 
EMPTY 
1 2
SH3D1 
2
N_A 
1
A36096-030 
N_A 
SH3D2 
1
100.0 1% 
CHIP 
2
0402 
1/16W 
G21796-017 
R3E1 
2
R3D28 
1
0402 100.0 
1/16W 
1% 
G21796-017 
CHIP 
VSENSE_PVCCIO_CPU1_AVSP 
VSENSE_PVCCIO_CPU1_AVSN 
1
2
C7R1 
22.0UF 
4V 
20% 
X6S 
C3E1 
4V 
0603V 0603V 
E15431-004 
X6S 
E15431-004 
20% 
22.0UF 
TP FAB1 ADD NET NAME 12/04 
TP FAB1 CHANGE TO 0 OHM 0107 
73 
213 
213 
73 
213 
213 
213 
213 
GROUP=PWR_BULK_CAP 
22UF 
DCR=0.17MOHM 
ISAT=75A@25C 
150NH 
0402 
10V 
10% 
1UF 
0805 
X6S 
16V 
20% 
22UF 
0805 
X6S 
16V 
20% 
22UF 
0805 
X6S 
16V 
20% 
22UF 
X6S 
0805 
16V 
20% 
22UF 
20% 
0805 
16V 
22UF 22UF 
X6S 
0805 
16V 
20% 
16V 
X6S 
0805 
22UF 
20% 
22UF 22UF 
16V 
20% 20% 
16V 
X6S 
0805 
NOPOP 
1 OHM 
1% 
0805 
16V 
20% 
22UF 
X6S X6S 
0805 0805 
X6S 
16V 
20% 
22UF 
20% 
16V 
X6S 
0805 
X6S 
IRMS=66A@DELTA_T<40C 
0603 
1/10W 
GROUP=PWR_MLCC_CAP 
GROUP=PWR_MLCC_CAP
GROUP=PWR_BULK_CAP GROUP=PWR_BULK_CAP 
SC22U16V5MX-4-GP 
SC1U10V2KX-4-GP 
SC22U16V5MX-4-GP 
SC22U16V5MX-4-GP 
SC22U16V5MX-4-GP 
SC22U16V5MX-4-GP 
SC22U16V5MX-4-GP 
SC22U16V5MX-4-GP 
SC22U16V5MX-4-GP 
SC22U16V5MX-4-GP 
SC22U16V5MX-4-GP 
SC22U16V5MX-4-GP 
SC22U16V5MX-4-GP 
DESIGN NOTE: 
TP FAB1 CHANGE RES TO 1 OHM 0603 0107 
VOUT=1.0V (TYP) SVID 
TOTAL TOL = 1.057VMAX/0.937VMIN 
IOUT STEP=14APP 
IOUT PK= 21.44A 
IOUT TDC=14.44A 
DC TOL = +/-5MV 
RIPPLE = +/- 10MV 
PUT TOGETHER PUT TOGETHER 
VBOOT=1.0V 
SW FREQ=641 KHZ 
IOUT DI/DT =22 A/US 
PUT TOGETHER 
2
1
21
21
2
1 NOPOP 1
2
1
2
1
2
DO NOT SCALE DRAWING 
TP FAB1 CO-LAY WITH TI PARTS 11/16 
TP FAB1 CO-LAY WITH TI PARTS 11/16 
TP FAB1 CO-LAY WITH TI PARTS 11/16 
SHEET 
B
AA
B
B
SIZE 
SCALE: 
234
1234
DEPARTMENT CODE 
1
DOCUMENT NUMBER REV 
IN 
IN 
P5V_STBY 
IN 
PVCCIO_CPU1
OUT 
OUT 
OUT 
PVCCIO_CPU1 
PVCCIO_CPU1 
OUT 
OUT 
1 2
1 2
2 1
2 1
2 1
1 2
1
1
2
1 2
2
2 1
1
2 1
2
1
1
2
2
214 OF 270 
Wed Feb 08 16:35:27 2017 
1
GL<1> 
GL<0> 
PGND<1> 
PGND<0> 
PGND<2> LGND 
VOS 
EN 
VDRV 
VCC 
VIN<0> VIN<1> 
PHASE 
REFIN 
BOOST 
PWM 
SW 
NC 
IOUT 
OCSET 
TOUT_FLT 
TDA21460 
TP FAB1 CHANGE PN 0310 
ROUTE AS DIFF PAIR 
BOM_COST = PROC_VRD_PVCCIO_CPU1 
ROOM = PVCCIO_CPU1 
SOCKET SIDE 
5MIL SPACING 
5MIL WIDTH 
TP FAB1 DEL NET 0309 
TP FAB1 CHANGE L4E2 PN 0122 
TP FAB1 CHANGE ONE 100UF CPA TO FOUR 22UF CAPS 0107
VR CONTROLLER SIDE 
NOPOP 
NOPOP 
PVCCIO CPU1 (2 OF 2) 
SPOF 
PLACE ON TOP 
ROOM= PVCCIO_CPU1 
WIWYNN CORPORATION 
SPOF 



1/16W 
SVID_DIO1_CPU0_R 
G21796-017 
0402 
PWRGD_PVDDQ_ABC 
IRQ_PVDDQ_ABC_VRHOT_LVT3_N 
SVID_ALERT1_CPU0_R_N 
EMPTY 
SMB_VR_STBY_LVC3_SCL 
1
G21497-005 
1/16W 
CHIP 
2.26K 
1/16W 1/16W 
CHIP 2
D97712-004 
0402V 
IC 
EU7G1 
PWRGD_PVDDQ_ABC_R 
1.0K 
G85996-004 
0.1% 
SC22P50V2JN-4GP 
21 
2
0402 CHIP 
1/16W 
15 
1/16W 
150.0 
G21796-009 
R7G24 
R3T11 
CHIP 
0402 
1/16W 
0402 
1 CHIP 
SVID_CLK1_CPU0_R 
CHIP 
SC22P50V2JN-4GP 
1.0K 
G85996-004 
VR_PVDDQ_ABC_AIREF1 
1/16W 
C7G4 
CF15 
G21796-047 
R7G4 
A_TSENSE_PVDDQ_ABC 
100.0 
1% 
R7F36 
0402 1
1/16W 
CHIP 2
G21497-005 
VR_PVDDQ_ABC_VD12 
VR_PVDDQ_ABC_PWM1 
VR_PVDDQ_ABC_PWM2 
0402 
1.0% 
R7F24 
1/16W 
1
33.2 
2
IRQ_PVDDQ_ABC_VRHOT_LVT3_R_N 
0402 
CHIP 
1
R3T13 
0.0 1
5% 
1/16W 
G21497-005 
0402 
C7F17 
0.1UF 1.0UF 1.00K 1.00K 
0402 
4
3
R7G8 
1/16W 
C7F14 
1000PF 
VR_PVDDQ_ABC_VD12 
SVID_VDIO_PVDDQ_ABC 
C7F15 
0.1UF 
A36096-030 
0402V 
G21796-311 
CHIP 
G21796-311 
1.0% 
1/16W 
R7G10 
0402 
2.26K 
1.0% 
0402 
2.26K 
1/16W 
CHIP 
G21796-066 
0402 
CHIP 
0402LF 
H89186-001 
32 
220PF 
6.3V 
1.0UF 
0402LF 
33 
31 
8
0402V 
2
2
A36096-050 
VR_PVDDQ_ABC_VDD 
SVID_ALERT_PVDDQ_ABC 
FM_PVDDQ_ABC_EN 
VSENSE_PVDDQ_ABC_P 
VSENSE_PVDDQ_ABC_N 
VR_PVDDQ_ABC_AIINSEN 
VR_PVDDQ_ABC_VINSEN 
VR_PVDDQ_ABC_AIREF2 
VR_PVDDQ_ABC_VREN 
TP_PVDDQ_ABC_MP2 
ISENSE_PVDDQ_ABC_PH1_IMON 
1
1% 
1/16W 
2
0402 
49.9 
ISENSE_PVDDQ_ABC_PH2_IMON 
39 
22 12 
38 
16 
14 
23 
25 
40 
13 
9
19 
11 
17 
6
7
5
2
35 
29 
36 
41 
28 
18 
27 
37 
26 
24 
10 
20 
30 
0402 
21
0.0 5% 
CHIP 1% 
1% 
2
R7F22 
1% 
1
0402 
R7F27 
1/16W 
G21497-005 
CHIP 
1
5% 0.0 
1
50V 
A36096-046 2
0402LF 
10% 
X7R 
0402 
G21497-005 
0.0 
R7G2 
21
5% 
C7F16 
D97712-004 
10% 
X6S 
1
2
1
16V 
10% 
X7R 
C7F18 
X6S X7R 
10% 
16V 
1
0402V 
CHIP 2
R7F20 
100.0K 
1/16W 
1% 
EMPTY 
0402 
G21796-010 
1% 
21
X7R 
10% 1C7G3 
50V 
A36096-050 
50V X7R 
10% 220PF 1
2
0402 
G21497-005 
R7F21 
0.0 5% 
1/16W 
R7G9 
1/16W 
21
1% 10.0 
1/16W 
2
SMB_VR_STBY_LVC3_SDA 
0.0 21 5% R12W25 0402 
25% 0.0 R12W26 1/16W EMPTY 
G21497-005 
R12W27 
G21796-074 
R7F23 
CHIP 22.1 
G21796-250 
0402 1.0% 
RF15 0.1% 
CHIP 
0402 
VR_PVDDQ_ABC_AVSP 
A36096-030 
10% 
6.3V 
G21796-026 G21796-026 G21796-311 R3U2 
PU_VR_PVDDQ_ABC_FAULT1 
TP_PVDDQ_ABC_MP1 
34 
CF16 
SVID_CLK_PVDDQ_ABC 
RF16 
TP FAB1 NC 0321 
TP FAB4 CHANGE RF15 TO 909OHM FOR VR FAILCHILD, SINGLE SIDE BOM 20170123 
TP FAB1 DELETE RES 0203 
TP FAB3 POP R12W25 0919 
TP FAB1 ADD RES 0303 
TP FAB3 POP R7F36 1014 
TP FAB3 NOPOP R7F24 0919 
TP FAB4 NOPOP RF16 AND CF16 FOR SS BOM 20170124 
TP FAB1 CO-LAY WITH FAIRCHILD PARTS 1203 
21 194 218 
197 
94 119 145 
194 218 21 
138 159 211 213 235 193 194 201 206
218 223
226 
221 
21 194 218 
216 
216 
215 
216 
216 
215 
191 
217 
217 
197 
197 
216 
216 
216 
138 159 193 194 201 206 211 
213 218 223 226 235 
BOM_SS=NOPOP 
GROUP=POWER_FAIR 
GROUP=POWER_FAIR 
BOM_SS=NOPOP 0402 
NOPOP 
5% 
NOPOP 
CHIP 
NPO 
50V 
22PF 
FAIR_SS=064.9090D.M001 
GROUP=POWER_FAIR 
GROUP=POWER_FAIR 
50V 
0402 
22PF 
NPO 
5% 
VR_PVDDQ_ABC_XADDR2 
VR_PVDDQ_ABC_XADDR1 
DESIGN NOTE: 
DESIGN NOTE: 
VOUT = 1.2V 
SW FREQ = 833.33KHZ 
IOUT DI/DT = 15A/US/18.09A/US FOR DS/SS 
IOUT STEP = 45A/17.96A FOR DS/SS 
IOUT PK = 73A/29.38A FOR DS/SS 
IOUT TDC = 65.7A/25.86A FOR DS/SS 
AC & RIPPLE TOL = +/2.8% 
DC TOL = +/-0.5% 
RIPPLE GUIDELINE = +/- 0.5% 
2
1
2
21
1
21
2
11
2
2
2
1
1
2
1 2
1
21
DO NOT SCALE DRAWING 
INFINEON:NOPOP 
FAIRCHILD:POP 
CF15&CF16 
RF15&RF16 
SHEET 
B
AA
B
B
SIZE 
SCALE: 
234
1234
DEPARTMENT CODE 
1
DOCUMENT NUMBER REV 
IN 
IN 
IN 
OUT 
OUT 
OUT 
IN 
BI 
OUT 
BI 
OUT 
OUT 
IN 
PVCCIO_CPU0 
OUT 
P3V3_STBY 
IN 
IN 
IN 
P3V3_STBY 
IN 
IN 
PVCCIO_CPU0 
IN 
IN 
IN 
215 OF 270 
Wed Feb 08 16:35:28 2017 
PXM1310C 
MP2 
THPAD 
BPWM1 
APWM1 APWM2 
APWM3 
SDA SCL 
VCLK 
VDIO 
RESET_N 
XADDR1 
AISEN3 
AIREF3 
XADDR2 
AISEN2 
AIREF2 
ATSEN 
AISEN1 
AIREF1 
VDD 
BTSEN 
BISEN1 BIREF1 DNC<0> DNC<1> 
VRHOT_N 
PINALRT_N 
VALRT_N 
AVSEN 
AVREF 
BVSEN 
BVREF 
VINSEN 
VD12 
GND 
IINSEN 
AVRRDY 
AVREN 
MP0 MP1 
TP FAB1 NC 0321 
TP FAB1 NC 0321 
TP FAB1 NC 0321 
TP FAB1 NC 0321 
TP FAB1 DEL NETS 0309 
TP FAB1 NC 0321 
TP FAB1 CHANGE R7G8 RES AND NOPOP R7G10 0408 
TP FAB1 CHANGE R7G8 RES 0523 
TP FAB3 NOPOP R7G8 AND CHANGE R7G10 0804 
TP FAB1 NC 0321 
TP FAB1 POP RES 0316 
TP FAB1 DEL CAP 0218 
TP FAB1 NC 0321 
TP FAB1 DEL RES 0314 
PVDDQ_ABC: 0X00(BUS #2) 
SVID ADDRESS 
SMBUS ADDRESS: 0XE0 
VDDQ ABC VR (1 OF 3) 
WIWYNN CORPORATION 
ROOM=VDDQ_ABC_PWR_VR 



1/16W 
CHIP 
1/16W 
CHIP 
F S
F S
10UF R7G25 
G21796-187 
1/16W 
EMPTY 
68.1K 
1% 
0402 
2
1
C95333-002 
0805LF 
C6G3 1 22UF 
20% 
X6S 
2
R7G30 
68.1K 
1% 
1/16W 
1
L7G1 
VR_PVDDQ_ABC_AIREF1 
0402LF 
ISENSE_PVDDQ_ABC_PH1_IMON 
1000PF 
50V 
10% 
X7R 
A36096-046 
CT49 
A_TSENSE_PVDDQ_ABC 
VR_PVDDQ_ABC_PH1_OCSET 
38 
37 
31 
36 
A36096-046 
0402LF 
VR_PVDDQ_ABC_PH1_SW_RC 
1000PF 
VR_PVDDQ_ABC_AIREF2 
1R3F-GP 
ISENSE_PVDDQ_ABC_PH2_IMON 
50V 
10% 
CT50 
X7R 
RT34 
VR_PVDDQ_ABC_PH1_SW 
7
5
10 
2
40 
A_TSENSE_PVDDQ_ABC 
VR_PVDDQ_ABC_PH2_OCSET 37 
31 
38 
EU7G2 
IC 
3
30 
4
25 
35 
1
6
41 
39 
34 
VR_PVDDQ_ABC_PH1_BOOT_R 
TP_PVDDQ_ABC_PH1_GL_0 
TP_PVDDQ_ABC_PH1_GL_1 
0.22UF 
C7G34 1
16V 
0402 
A36096-155 
10% 
X7R 2
0 0603 
H73688-001 
A36096-030 
33 
32 
CT51 
16V 
0.1UF 
X7R 
0402V 
10% 
IC 
EU7G3 
30 
3
25 
4
35 
1
CHIP 
5.0% 
G22178-002 
0.22UF 
A36096-155 
1 C7G41 
16V 
10% 
2 X7R 
EMPTY 1000PF 41 36 TP_PVDDQ_ABC_PH2_GL_1 0402 
G21796-187 
0402 
2
0805LF 
C95333-002 
C7G27 
22UF 1
20% 
X6S 
2
L7G2 
50V 1000PF 
0402LF 
X7R 
1R3F-GP 
VR_PVDDQ_ABC_PH2_SW_RC 
A36096-046 
0402LF 
A36096-046 
X7R 
10% 
50V 
CT53 
CT54 
10% 
RT35 
VR_PVDDQ_ABC_PH2_SW 
2
10 
40 
5
7
H73688-001 
34 
6
39 
33 
32 
0.1UF 
10% 
16V 
A36096-030 
0402V 
X7R 
CT52 
VR_PVDDQ_ABC_PH2_BOOT_R 
TP_PVDDQ_ABC_PH2_GL_0 
VR_PVDDQ_ABC_PWM2 
CHIP 
1/10W 
5.0% 0
0603 
RT36 
C7G35 
1/10W 
RT33 
G22178-002 
21
R3U6 
G21497-005 
0402 
VR_PVDDQ_ABC_PH1_BOOT 
VR_PVDDQ_ABC_PH1_VCIN 
D97712-011 
0.0 5% 
C7G33 
1.0UF 1C7G29 
0.1UF 1
0402 
16V 
X6S 2
10% 
A36096-030 
X7R 2
10% 
16V 
0402V 
D97712-011 
VR_PVDDQ_ABC_PWM1 
C7G37 
1.0UF 110UF 
C3U4 1
0402 
10% 
X6S 2
16V 
C95333-007 
10% 
X6S 2
16V 
0805 
VR_FET_SW_P12V_STBY_PVDDQ_ABC 
C95333-007 
C3U3 
10UF 1C3U2 1
16V 
10% 
2 X6S 
0805 
C95333-007 
10% 
16V 
X6S 
0805 
2
C7G31 
VR_PVDDQ_ABC_PH1_PHASE 
1
2A36096-104 
0402 
0.220UF 
X7R 
16V 
10% 
C7G42 
2
G21497-005 
D97712-011 
0402 
VR_PVDDQ_ABC_PH2_VCIN 
R3U9 
5% 
1
0.0 
X6S 
16V 
1.0UF 
10% 
C7G40 1
2
C7G36 
0.1UF 
16V 
10% 
X7R 
A36096-030 D97712-011 
C7G30 1
10% 
X6S 2
16V 
1.0UF 
C95333-007 
C3U9 1
2
10UF 
X6S 
10% 
16V 
1
2
C95333-007 
C3U7 1
16V 
10UF 
2 X6S 
10% 
C95333-007 
C3U6 1
2
16V 
10% 
10UF 
X6S 
VR_FET_SW_P12V_STBY_PVDDQ_ABC 
0402 0805 0805 0402 0402V 0805 
VR_PVDDQ_ABC_PH2_PHASE 
VR_PVDDQ_ABC_PH2_BOOT 
C7G38 
16V 
1
10% 
X7R 
0402 
2
0.220UF 
A36096-104 
TP FAB1 CO-LAY WITH TI PARTS 11/16 
TP FAB3 CHANGE L7G1 0823 
TP FAB1 CHANGE L7G1 PN 0122 
TP FAB3-DVT NOPOP L7G1 IND FOR SS BOM 20161215 
TP FAB1 CHANGE L7G2 PN 0122 
TP FAB3 CHANGE L7G2 0823 
TP FAB3-DVT NOPOP L7G2 IND FOR SS BOM 20161215 
TP FAB1 CHANGE RES TO 1 OHM 0603 0107 
TP FAB1 CHANGE TO 0 OHM 0107 
TP FAB1 CHANGE TO 0 OHM 0107 
TP FAB3-DVT NOPOP FROM SS BOM 20161215 
TP FAB4 POP CAP ON SS BOM 20170207 
215 
215 
216 215 
215 
215 
216 215 
215 
215 
IRMS=66A@DELTA_T<40C 
GROUP=PWR_MLCC_CAP 
BOM_SS=068.1202N.M001 
SS_VALUE=120NH 
IRMS=66A@DELTA_T<40C 
DS_ISAT=134A@25C 
BOM_DS=068.9002N.1021 
SS_ISAT=94A@25C 
DCR=0.17MOHM 
DS_VALUE=90NH 
NOPOP 
1 OHM 
1/10W 
0603 
1% 
BOM_SS=NOPOP 
BOM_SS=NOPOP 
GROUP=PWR_MLCC_CAP 
BOM_SS=NOPOP 
BOM_SS=NOPOP 
BOM_DS=068.9002N.1021 
DS_VALUE=90NH 
DS_ISAT=134A@25C 
DCR=0.17MOHM 
BOM_SS=NOPOP 
BOM_SS=NOPOP 
BOM_SS=NOPOP 
NOPOP 
NOPOP 
1 OHM 
1/10W 
NOPOP 
1% 
0603 
BOM_SS=NOPOP 
BOM_SS=NOPOP 
BOM_SS=NOPOP 
BOM_SS=NOPOP 
1UF 
10% 
0402 
10V 
1UF 
10V 
0402 
10% 
BOM_SS=NOPOP 
BOM_SS=NOPOP 
BOM_SS=NOPOP 
TP FAB1 ADD NET NAME 12/04 
TP FAB1 ADD NET NAME 12/04 
TP FAB1CO-LAY WITH TI PARTS 11/16 
TP FAB1 CO-LAY WITH TI PARTS 11/16 
4V 
4V 
SC1U10V2KX-4-GP 
SC1U10V2KX-4-GP 
2
1
2
1
NOPOP 
1
2
1
21
1
2
21
2
1
2
1
2
21
DO NOT SCALE DRAWING 
TP FAB1 CO-LAY WITH TI PARTS 11/16 
TP FAB1 CO-LAY WITH TI PARTS 11/16 
TP FAB1 CO-LAY WITH TI PARTS 11/16 
SHEET 
B
AA
B
B
SIZE 
SCALE: 
234
1234
DEPARTMENT CODE 
1
DOCUMENT NUMBER REV 
P5V_STBY 
P5V_STBY 
IN 
PVDDQ_ABC 
OUT 
OUT 
OUT 
OUT 
OUT 
IN 
OUT 
PVDDQ_ABC 
1 2 1 2
1 2
1 2
216 OF 270 
Wed Feb 08 16:35:28 2017 
1
1
GL<1> 
GL<0> 
PGND<1> 
PGND<0> 
PGND<2> LGND 
VOS 
EN 
VDRV 
VCC 
VIN<0> VIN<1> 
PHASE 
REFIN 
BOOST 
PWM 
SW 
NC 
IOUT 
OCSET 
TOUT_FLT 
GL<1> 
GL<0> 
PGND<1> 
PGND<0> 
PGND<2> LGND 
VOS 
EN 
VDRV 
VCC 
VIN<0> VIN<1> 
PHASE 
REFIN 
BOOST 
PWM 
SW 
NC 
IOUT 
OCSET 
TOUT_FLT 
TP FAB1 CHANGE RES TO 1 OHM 0603 0107 
TP FAB1 DEL NET 0309 
TP FAB1 DEL NET 0309 
TDA21470 
TDA21470 
TP FAB1 CHANGE PN 0310 
TP FAB1 CHANGE PN 0310 
NOPOP 
NOPOP 
NOPOP 
VDDQ ABC VR (2 OF 3) 
PLACE ON TOP 
PLACE ON TOP 
SPOF 
WIWYNN CORPORATION 
SPOF 
ROOM = VDDQ_ABC_PWR_VR 



BOM_SS=E15431-004 BOM_SS=E15431-004 
BOM_SS=E15431-004 
BOM_SS=E15431-004 
BOM_SS=E15431-004 BOM_SS=E15431-004 
BOM_SS=E15431-004 
BOM_SS=E15431-004 
BOM_SS=E15431-004 
BOM_SS=E15431-004 BOM_SS=E15431-004 
BOM_SS=E15431-004 
BOM_SS=E15431-004 
BOM_SS=E15431-004 
BOM_SS=E15431-004 
BOM_SS=E15431-004 
BOM_SS=E15431-004 
BOM_SS=E15431-004 
BOM_SS=E15431-004 
BOM_SS=E15431-004 
BOM_SS=E15431-004 
BOM_SS=E15431-004 
BOM_SS=E15431-004 
BOM_SS=E15431-004 
BOM_SS=E15431-004 
BOM_SS=E15431-004 
BOM_SS=E15431-004 
BOM_SS=E15431-004 
BOM_SS=E15431-004 
BOM_SS=E15431-004 
BOM_SS=E15431-004 
BOM_SS=E15431-004 
602433-106 
0805 
G22026-003 
602433-106 
C5D55 
602433-112 20% 
602433-112 
0805 
602433-112 
0805 
0603V 
C5T5 
47UF 
0603V 
602433-106 
X5R 
C5T2 C5T13 
47UF 
4V 
20% 
X5R 
2 602433-106 
602433-112 
0805 0805 
602433-112 
C5T4 1 47UF 
4V 
20% 
0603V 
0603V 
602433-106 
X5R 
20% 
47UF 
4V 
47UF 
C5T1 
20% 
C5U11 1 1
4V 
2
1 C5G11 
E15431-004 
X6S 
20% 
4V 
22.0UF 
4V 
22.0UF 22.0UF 1C5D59 
20% 
1 C5G19 
C5D60 
0603V 
47UF 
602433-106 
0603V 
47UF 
C5G12 
0603V 
1 C5U4 
20% 
2
4V 
47UF 
C5U7 C5U6 
C5D58 
0603V 0603V 
E15431-004 
0603V 
VR_FET_SW_P12V_STBY_PVDDQ_ABC 
2
4V 
C5P39 
4V 
100UF 
C5P43 
602433-112 
0603V 
1
2
20% 
602433-112 
1
2
20% 
4V 
100UF 
C5P44 
E15431-004 
X6S 2X6S 2
100UF 100UF 
4V 
C5P41 
2
1
20% 20% 
C5U14 
602433-112 
4V 
2
1
A31228-047 
270UF 
20% 
C7G2 
16V 
2
1
2626 
OSCON 
47UF 
2
1
4V 
0603V 
X5R 
47UF 
C5F1 1
2
C5G10 1
0603V 
2
47UF 
2
0603V 0603V 
22
N_A 
1
1 2
2
1
2 X6S 
4V 
0603V 
E15431-004 
20% 
1
0603V 
E15431-004 
4V 
C5D54 1 22.0UF 1
4V 
X6S 2
1 22.0UF 
4V 
C5D56 C5D57 
4V 
20% 
22.0UF 
1
1
4V 
602433-106 
0603V 
1
602433-106 
0603V 
4V 
47UF 1
2
C5U9 
X5R 
4V 
1
2 X5R 
C5T12 
602433-106 2
0603V 
1 47UF 
4V 
C5T11 
0603V 
602433-106 
X5R 2
47UF 
4V 
1
X5R 2
C5T9 1 47UF 
4V 602433-106 
0603V 
X5R 2 602433-106 
1 C5T8 
4V 
47UF 
0603V 
602433-106 
0603V 
X5R 2
4V 
47UF 1 C5T7 
2 602433-106 
X5R 
47UF 
4V 
1 C5T6 
X5R 
4V 
1
602433-106 
0603V 
2
47UF 
X5R 
2
4V 
X5R 
4V 
47UF 
C5G2 
0603V 
1
2
4V 
1
0603V 
X5R 
C5G13 
2
4V 
1 47UF 
4V 
1
0603V 
47UF 
C5G6 
X5R 
1
2
20% 
602433-106 2
1 C5G7 
X5R 
0603V 
4V 
47UF 
4V 
20% 
602433-106 
X5R 2
0603V 
1 C5G1 1
4V 
20% 
602433-106 
X5R 2
0603V 
47UF 
C5G8 
2
1
4V 
47UF 
602433-106 2
1
0603V 
C5G17 
20% 
X5R 
C5G14 
47UF 
4V 
0603V 
1
2 X5R 
20% 
C5G16 
47UF 
602433-106 
20% 
X5R 
1
0603V 
2
4V 
0603V 
602433-106 
X5R 
20% 
4V 
47UF 
C5G15 1
2 602433-106 
X5R 2
C5G3 
4V 
47UF 
0603V 
1
20% 
G21796-017 
0402 
EMPTY 
1/16W 
R4U6 
100.0 
1% 
1
2
VSENSE_PVDDQ_ABC_N 
VSENSE_PVDDQ_ABC_P 
L7F2 
IND-100NH-35-GP 
2
11 C5U13 
100UF 
2
1
2
1
0603V 
E15431-004 
4V 
100UF 
20% 
1
20% 
4V 
100UF 
0805 
C5G20 
2
2
1
C7G28 
470UF 
ALUM 
3018 
2
699013-049 
20% 
2.5V 
C3U1 
ALUM 
699013-049 
3018 2
1
2.5V 
20% 
470UF 
2
1
3018 
ALUM 
2.5V 
20% 
470UF 
C3U5 
699013-049 
ALUM 
2.5V 
20% 
1 470UF 
C3U8 
2
1
R3U4 
120.0 
1% 
1/10W 
CHIP 
0603 
3018 
2
699013-049 
X6S 2E15431-004 
X6S 
20% 
1
2
SH4U1 
N_A 
SH4U2 
2
0603V 
4V 
2X5R 
1 147UF 
0603V 
602433-106 2
0603V 
602433-106 
X5R 
4V 
20% 
2 602433-106 
20% 20% 20% 
0603V 
4V 
0603V 
20% 
47UF 
X5R 
602433-106 
47UF 
20% 
4V 
C5F2 
X5R 
4V 
C5D61 
4V 
C5U10 
602433-112 
4V 
602433-112 
100UF 100UF 
C5U1 
4V 
C5P42 
2
20% 
4V 
22.0UF 100UF 
C5P38 
0805 
2
0805 
602433-112 
4V 
20% 20% 
100UF 
0805 0805 0805 
20% 
4V 
100UF 
C5G9 
100UF 
602433-112 
20% 
C5U15 
22.0UF 
20% 
X5R 
0603V 
20% 
47UF 
20% 20% 20% 20% 20% 20% 20% 20% 20% 20% 20% 20% 
0603V 
602433-106 602433-106 
47UF 
C5T10 
X5R 
C5U8 
47UF 
4V 
20% 
602433-106 
X5R 2X5R 2602433-106 602433-106 
0603V 
C5G4 
47UF 
20% 
X5R 
602433-106 602433-106 
C5G5 
20% 
X5R 
2602433-106 
1
4V 
602433-106 
X5R 
47UF 1
2
C5U2 
47UF 
602433-106 
X5R 
20% 
0603V 
4V 
C5U3 
0603V 
602433-106 
X5R 
4V 
47UF 
C5U5 
0603V 
602433-106 
X5R 
20% 
4V 
47UF 
C5G18 1
1
2
20% 
2
4V 
20% 
4V 602433-106 
0603V 
X5R 
20% 
4V 
X5R 
100UF 
4V 
20% 
0805 
602433-112 
20% 20% 
X6S 
E15431-004 0805 
47UF 
602433-106 602433-106 
X5R 
20% 
1
20% 
0805 
602433-112 
1 C4T4 
TP FAB1 CHANGE CAPACITY 0322 
TOP SIDE: 603 
TP FAB3-DVT CHANGE CAP IN SS BOM 20161220 
TP FAB3-DVT NOPOP FROM SS BOM 20161220 
TP FAB1 CHANGE CAP 0311 
TP FAB3-DVT CHANGE CAP IN SS BOM 20161220 
TP FAB3-DVT NOPOP FROM SS BOM 20161220 
TP FAB1 CHAGNE CAP 0311 
TP FAB1 CHANGE CONNECTION 0318 
TP FAB3-DVT NOPOP FROM SS BOM 20161220 
BOTTOM SIDE: 805 
215 
215 
NEW_PN=078.1071T.0811 NEW_PN=078.1071T.0811 NEW_PN=078.1071T.0811 NEW_PN=078.1071T.0811 
NEW_MATERIAL=X6S 
GROUP=PWR_MLCC_CAP 
GROUP=PWR_MLCC_CAP 
NEW_PN=078.1071T.0811 
NEW_MATERIAL=X6S 
NEW_PN=078.1071T.0811 
NEW_MATERIAL=X6S 
BOM_SS=NOPOP 
NEW_PN=078.1071T.0811 
NEW_MATERIAL=X6S 
GROUP=PWR_MLCC_CAP 
BOM_SS=NOPOP 
GROUP=PWR_MLCC_CAP 
GROUP=PWR_MLCC_CAP 
BOM_SS=NOPOP 
GROUP=PWR_MLCC_CAP 
GROUP=PWR_MLCC_CAP 
BOM_SS=NOPOP BOM_SS=NOPOP 
GROUP=PWR_MLCC_CAP 
BOM_SS=078.1061T.M001 
BOM_SS=NOPOP 
GROUP=PWR_MLCC_CAP 
GROUP=PWR_MLCC_CAP 
BOM_SS=NOPOP GROUP=PWR_MLCC_CAP 
NEW_PN=078.1071T.0811 
NEW_MATERIAL=X6S 
BOM_SS=NOPOP 
GROUP=PWR_MLCC_CAP GROUP=PWR_MLCC_CAP 
BOM_SS=NOPOP 
NEW_MATERIAL=X6S 
NEW_PN=078.1071T.0811 NEW_PN=078.1071T.0811
GROUP=PWR_MLCC_CAP 
BOM_SS=NOPOP 
NEW_MATERIAL=X6S 
NEW_PN=078.1071T.0811 
GROUP=PWR_MLCC_CAP 
GROUP=PWR_MLCC_CAP 
GROUP=PWR_MLCC_CAP 
GROUP=PWR_MLCC_CAP GROUP=PWR_MLCC_CAP 
NEW_PN=078.1071T.0811 
NEW_MATERIAL=X6S 
GROUP=PWR_MLCC_CAP
BOM_SS=NOPOP 
NEW_MATERIAL=X6S 
GROUP=PWR_MLCC_CAP 
GROUP=PWR_MLCC_CAP GROUP=PWR_MLCC_CAP 
100NH 
ISAT=16A@25C 
DCR=0.16MOHM 
IRMS=29A@DELTA_T<45C 
GROUP=PWR_BULK_CAP 
GROUP=PWR_BULK_CAP 
GROUP=PWR_BULK_CAP 
GROUP=PWR_BULK_CAP 
GROUP=PWR_MLCC_CAP 
GROUP=PWR_MLCC_CAP 
GROUP=PWR_MLCC_CAP 
GROUP=PWR_MLCC_CAP 
GROUP=PWR_MLCC_CAP 
GROUP=PWR_MLCC_CAP 
GROUP=PWR_MLCC_CAP 
GROUP=PWR_MLCC_CAP 
GROUP=PWR_MLCC_CAP 
GROUP=PWR_MLCC_CAP 
GROUP=PWR_MLCC_CAP 
GROUP=PWR_MLCC_CAP 
GROUP=PWR_MLCC_CAP 
GROUP=PWR_MLCC_CAP 
GROUP=PWR_MLCC_CAP 
GROUP=PWR_MLCC_CAP 
GROUP=PWR_MLCC_CAP 
GROUP=PWR_MLCC_CAP 
GROUP=PWR_MLCC_CAP GROUP=PWR_MLCC_CAP 
GROUP=PWR_MLCC_CAP 
GROUP=PWR_MLCC_CAP 
GROUP=PWR_MLCC_CAP 
GROUP=PWR_MLCC_CAP 
GROUP=PWR_MLCC_CAP 
NEW_MATERIAL=X6S 
GROUP=PWR_MLCC_CAP GROUP=PWR_MLCC_CAP 
GROUP=PWR_MLCC_CAP 
GROUP=PWR_MLCC_CAP 
GROUP=PWR_MLCC_CAP 
GROUP=PWR_MLCC_CAP GROUP=PWR_MLCC_CAP 
GROUP=PWR_MLCC_CAP 
GROUP=PWR_MLCC_CAP 
GROUP=PWR_MLCC_CAP 
GROUP=PWR_MLCC_CAP 
NEW_MATERIAL=X6S 
NEW_PN=078.1071T.0811 
BOM_SS=NOPOP 
BOM_SS=NOPOP 
GROUP=PWR_MLCC_CAP 
NEW_PN=078.1071T.0811 
NEW_MATERIAL=X6S 
GROUP=PWR_MLCC_CAP 
BOM_SS=NOPOP 
GROUP=PWR_MLCC_CAP 
BOM_SS=NOPOP 
BOM_SS=NOPOP 
BOM_SS=NOPOP 
BOM_SS=NOPOP 
BOM_SS=NOPOP 
GROUP=PWR_MLCC_CAP 
NEW_MATERIAL=X6S NEW_MATERIAL=X6S 
BOM_SS=NOPOP 
BOM_SS=NOPOP 
BOM_SS=NOPOP 
2 2
11
ROUT AS DIFF PAIR 
10MIL WIDTH 
5MIL SPACING 
1 2
DO NOT SCALE DRAWING SHEET 
B
AA
B
B
SIZE 
SCALE: 
234
1234
DEPARTMENT CODE 
1
DOCUMENT NUMBER REV 
PVDDQ_ABC 
PVDDQ_ABC 
PVDDQ_ABC 
IN 
IN 
PVDDQ_ABC 
PVDDQ_ABC 
PVDDQ_ABC 
PVDDQ_ABC 
PVDDQ_ABC 
PVDDQ_ABC 
PVDDQ_ABC 
PVDDQ_ABC 
P12V_STBY 
PVDDQ_ABC 
INPUT FILTER 
PVDDQ_ABC VOLTAGE SENSE 
217 OF 270 
Wed Feb 08 16:35:28 2017 
217 OF 270 
TP FAB1 CHANGE L7F2 PN 0122 
TP FAB1 CHANGE CAP OF SINGLE SIDE 0504 TP FAB1 CHANGE CAP 0322 
ROOM=VDDQ_ABC_CPU0 
PLACE NEAR VR OUTPUT INDUCTORS 
CAD NOTE: 
CAPS TO BE PLACED BETWEEN DIMMS 
TP FAB1 CHANGE CAP 0314 
PVDDQ CPU CAVITY CAPS 
TP FAB1 CHANGE CAP 0322 
VDDQ ABC DECAP (3 OF 3) 
WIWYNN CORPORATION ROOM = VDDQ_ABC_PWR_VR 



1/16W 0402 
R7B4 
1.00K 1
1% 
1/16W 
G21796-026 2
R7A9 
PWRGD_PVDDQ_DEF 
IRQ_PVDDQ_DEF_VRHOT_LVT3_N 
0402 
C7B1 
VR_PVDDQ_DEF_VD12 
0402 5% 0.0 
SVID_VDIO_PVDDQ_DEF 
PU_VR_PVDDQ_DEF_FAULT1 
G21497-005 0402 
1/16W 
SVID_ALERT1_CPU0_R_N 
G21796-074 
1% 
100.0 
2.26K 
1.0% 
SVID_ALERT_PVDDQ_DEF 
IRQ_PVDDQ_DEF_VRHOT_LVT3_R_N 
25 
SC22P50V2JN-4GP 
R7A17 
150.0 
1/16W 
CHIP 
CF17 
G21796-009 
CHIP 
0.1% 1.0K RF17 
G85996-004 0402 
5% 
0402 
R7B1 
R12W30 
0.0 G21497-005 21 5% R12W28 
SMB_VR_STBY_LVC3_SDA 
SMB_VR_STBY_LVC3_SCL 
1/16W 
G21497-005 
2
EMPTY 
VR_PVDDQ_DEF_VD12 
R7A7 
2
1% 
1
0402 
CHIP 1/16W 
10.0 
G21796-066 1 10% 
C7A28 
220PF 
X7R 50V 
A36096-050 
0402LF 2
CHIP 
R3M6 
G21497-005 
0.0 
1/16W 
5% 0402 
2
1220PF 10% 
50V 
1
0402 
21/16W 
1% 
1 C7B2 
2
0.1UF 
16V 
10% 
X7R 
A36096-030 
0402V 
1
2
1.0UF 
6.3V 
10% 
X6S 
D97712-004 
0402V 
R3M5 
100.0K 
1% 
1/16W 
EMPTY 
G21796-010 
0402 
1
2
R3M1 
0.0 
5% 
1/16W 
CHIP 
G21497-005 
0402 
C7A38 1
2
0.1UF 
16V 
10% 
A36096-030 
C7A37 1
2
1.0UF 
6.3V 
10% 
X6S 
0402V 
D97712-004 
1 1000PF 
50V 
10% 
C7B3 
A36096-046 
X7R 2
0402LF 
1
R7A12 
1 25% R12W29 0.0 
21
0.0 EMPTY 
1
0402 CHIP 
1/16W R7A11 
2
5% 
G21497-005 
0.0 
0402 
CHIP 
G21796-026 
0402 
1
1/16W 
1% 
1.00K 
R7B5 
2 CHIP 
1/16W 0402 33.2 1% 
IC 
22 
17 
18 
9
EU7A5 
21 
23 
6
12 
14 
13 
3
8
33 
4
40 
27 
16 
1
5
41 
7
11 
2
28 
15 
39 
24 
20 
10 
29 
34 
35 
38 
37 
19 
30 
36 
32 
31 
H89186-001 
2
0402 
EMPTY 
1% 
1
G21796-047 
1/16W 
49.9 
R3L13 
ISENSE_PVDDQ_DEF_PH1_IMON 
ISENSE_PVDDQ_DEF_PH2_IMON 
VR_PVDDQ_DEF_VINSEN 
VR_PVDDQ_DEF_AIINSEN 
A_TSENSE_PVDDQ_DEF 
VSENSE_PVDDQ_DEF_N 
VR_PVDDQ_DEF_AVSP 
VR_PVDDQ_DEF_VDD 
PWRGD_PVDDQ_DEF_R 
TP_PVDDQ_DEF_MP2 
TP_PVDDQ_DEF_MP1 
VR_PVDDQ_DEF_PWM2 
VSENSE_PVDDQ_DEF_P 
FM_PVDDQ_DEF_EN 
0402LF 
X7R 
CHIP 
1.0% 
2.26K 
R7A8 
1
2 CHIP 
16K 
G21796-317 
1.0% 
R7A10 
1/16W 1/16W 
0402 0402 
G21796-311 
VR_PVDDQ_DEF_PWM1 
VR_PVDDQ_DEF_AIREF1 
VR_PVDDQ_DEF_AIREF2 
CHIP 
1/16W 
CHIP 
G21497-005 1/16W 
22.1 
0402 
SVID_DIO1_CPU0_R 
1/16W 
EMPTY 
1
2
R3L11 
0402 
CHIP 
1.0% 
CHIP 
G21796-311 
G21796-017 
R3M3 
G21796-250 
1/16W 
0402V 
SVID_CLK_PVDDQ_DEF 
X7R 
A36096-050 
C7A29 
VR_PVDDQ_DEF_VREN 
SVID_CLK1_CPU0_R 
26 
0402 
1/16W 
CHIP G85996-004 
0.1% 
CF18 
SC22P50V2JN-4GP 
RF18 1.0K 
TP FAB3 NOPOP R3M3 0919 
TP FAB3 POP R7A9 1014 
TP FAB4 NOPOP RF18 AND CF18 FOR SS BOM 20170124 
TP FAB1 ADD RES 0303 
TP FAB3 POP R12W28 0919 
TP FAB3 CHANGE RES 0804 
TP FAB1 CHANGE R7A10 RES 0523 
TP FAB1 CHANGE R7A10 RES AND NOPOP R7A8 0408 
TP FAB1 DELETE RES 0203 
TP FAB4 CHANGE RF17 TO 953OHM FOR VR FAILCHILD, SINGLE SIDE BOM 20170123 
197 
94 119 146 
218 
194 215 21 
138 
159 193 194 201 206 211 213 215
223 226 235
138 159 211 213 235 193 194 201 
206 215 223 226 
218 
219 
219 
197 
197 
219 
220 
222 
219 
220 
191 219 
219 
219 
21 194 215 
21 194 
215 
GROUP=POWER_FAIR 
GROUP=POWER_FAIR 
BOM_SS=NOPOP 
0402 
5% 
NOPOP 
22PF NPO 50V 
NPO 50V 5% 22PF 
BOM_SS=NOPOP 
0402 
GROUP=POWER_FAIR 
FAIR_SS=064.9530D.M001 
GROUP=POWER_FAIR 
VR_PVDDQ_DEF_XADDR2 
VR_PVDDQ_DEF_XADDR1 
DESIGN NOTE: 
DESIGN NOTE: 
SW FREQ = 833.33KHZ 
IOUT DI/DT = 15A/US/18.09A/US FOR DS/SS 
IOUT STEP = 45A/17.96A FOR DS/SS 
AC & RIPPLE TOL = +/2.8% 
DC TOL = +/-0.5% 
RIPPLE GUIDELINE = +/- 0.5% 
VOUT = 1.2V 
IOUT TDC = 65.7A/25.86A FOR DS/SS 
IOUT PK = 73A/29.38A FOR DS/SS 
2
2
1
21
2
1
1
1
2
1
2
212
1
2
21
1
DO NOT SCALE DRAWING 
TP FAB1 CO-LAY WITH FAIRCHILD PARTS 1203 
RF17&RF18 
FAIRCHILD:POP 
INFINEON:NOPOP 
CF17&CF18 
SHEET 
B
AA
B
B
SIZE 
SCALE: 
234
1234
DEPARTMENT CODE 
1
DOCUMENT NUMBER REV 
IN 
IN 
IN 
PVCCIO_CPU0 
OUT 
OUT 
OUT 
P3V3_STBY 
OUT 
IN 
IN 
BI 
OUT 
BI 
OUT 
IN 
OUT 
IN 
IN 
P3V3_STBY 
IN 
PVCCIO_CPU0 
IN 
IN 
IN 
IN 
218 OF 270 
Wed Feb 08 16:35:28 2017 
PXM1310C 
MP2 
THPAD 
BPWM1 
APWM1 APWM2 
APWM3 
SDA 
SCL 
VCLK 
VDIO 
RESET_N 
XADDR1 
AISEN3 
AIREF3 
XADDR2 
AISEN2 
AIREF2 
ATSEN 
AISEN1 
AIREF1 
VDD 
BTSEN 
BISEN1 BIREF1 DNC<0> DNC<1> 
VRHOT_N 
PINALRT_N 
VALRT_N 
AVSEN 
AVREF 
BVSEN 
BVREF 
VINSEN 
VD12 
GND 
IINSEN 
AVRRDY 
AVREN 
MP0 MP1 
TP FAB1 NC 0321 
TP FAB1 DEL RES 0314 
TP FAB1 NC 0321 
TP FAB1 NC 0321 
TP FAB1 NOPOP RES 0316 
TP FAB1 NC 0321 
TP FAB1 NC 0321 
TP FAB1 NC 0321 
TP FAB1 NC 0321 
TP FAB1 DEL NETS 0309 
TP FAB1 DEL CAP 0218 
TP FAB1 NC 0321 
PVDDQ_DEF: 0X02(BUS #2) 
SVID ADDRESS 
SMBUS ADDRESS: 0XE4 
VDDQ DEF_VR (1 OF 3) 
WIWYNN CORPORATION ROOM=VDDQ_DEF_PWR_VR 



CHIP 
1/16W 
1/16W 
CHIP 
TP FAB1 CO-LAY WITH TI PARTS 11/16 
TP FAB1 CO-LAY WITH TI PARTS 11/16 
F S
F S
0402 
G21497-005 
C7A21 1
C95333-007 
VR_PVDDQ_DEF_PH2_VCIN 
D97712-011 
VR_PVDDQ_DEF_PH2_BOOT 
VR_PVDDQ_DEF_PH2_PHASE 
0.220UF 
A36096-030 
C7A20 C3L16 
16V 
X6S 2 D97712-011 
16V 
10% 
C3L17 
10UF 
16V 
10% 
X6S 
5% 0.0 
0402 
X6S 
22
C7A24 
VR_PVDDQ_DEF_PWM2 
C7A22 
0402 
X6S 
10% 
X7R 
16V 
10% 
CT48 
R3L8 
VR_PVDDQ_DEF_PH2_BOOT_R 39 0402LF 
A36096-046 
X7R 
A_TSENSE_PVDDQ_DEF 
VR_PVDDQ_DEF_PH2_OCSET 
20% 
10% 
0402V 
D97712-011 
X6S 
C3L13 
VR_FET_SW_P12V_STBY_PVDDQ_DEF 
16V 
C7A26 
X7R 
A36096-155 
TP_PVDDQ_DEF_PH2_GL_1 
TP_PVDDQ_DEF_PH2_GL_0 
CT46 
A36096-030 
VR_PVDDQ_DEF_PH2_SW 
1% 
EU7A4 
10% 
0402LF 
VR_PVDDQ_DEF_PH2_SW_RC 
CHIP 0603 
X7R 
10% 
VR_PVDDQ_DEF_PH1_BOOT 
D97712-011 
TP_PVDDQ_DEF_PH1_GL_1 
TP_PVDDQ_DEF_PH1_GL_0 
A36096-030 
CT45 
ISENSE_PVDDQ_DEF_PH2_IMON 
VR_PVDDQ_DEF_AIREF2 
16V 
1
0402 
X7R 
A36096-104 2
C3L15 
0805 
2
1 1
2
1
16V 
1 2
C7A25 
0.22UF 
1
16V 
10% 
2
0402 
0
1/10W RT31 
5.0% 
G22178-002 0.1UF 
0402V 
X7R 
10% 
16V 
RT32 
1R3F-GP 
CT47 
X7R 
1000PF 50V 
A36096-046 
L7A3 
22UF 
2
0805LF 
1
C95333-002 
X6S 
C6A4 
G21796-187 
1% 
0402 
EMPTY 
1/16W 
68.1K 
R7A21 
50V 
1000PF 
30 
38 
IC 
32 
4
34 
36 
33 
6
5
7
10 
1
3
25 
41 
H73688-001 
37 
31 
2
40 
35 
VR_PVDDQ_DEF_PH1_SW_RC 
A36096-046 
0402LF 
1000PF 
G21796-187 
EU7A1 
VR_PVDDQ_DEF_PH1_PHASE 
G22178-002 
0402 
A36096-155 
41 
34 
H73688-001 
0402 
RT29 
1R3F-GP 
20% 
X6S 
C95333-002 
22UF 
C6A1 
0805LF 
10% 
C7A18 16V 
1.0UF 
C7A16 
0.0 
G21497-005 
VR_PVDDQ_DEF_PH1_VCIN 
5% 
2
0402 
1
R3L6 
VR_PVDDQ_DEF_PH1_BOOT_R 
10% 
X6S 
0402 
VR_PVDDQ_DEF_AIREF1 
VR_PVDDQ_DEF_PH1_OCSET 
ISENSE_PVDDQ_DEF_PH1_IMON 
A_TSENSE_PVDDQ_DEF 
C7A17 
0.22UF 0.1UF 
16V 
10% 
X7R 
A36096-030 
C7A5 C7A11 
16V 
10% 
0402 
1.0UF 
0805 
10% 
X6S 
C95333-007 
10UF 
C3L4 
0805 
10UF 
C95333-007 
X6S 
10% 
16V 
0805 
C95333-007 
16V 
10% 
X6S 
C3L2 
10UF 
2
1
0402 
16V 
A36096-104 
0.220UF 
C7A12 
VR_PVDDQ_DEF_PWM1 
CHIP 
RT30 
0603 
5.0% 
0
0402LF 
1000PF 
CT43 50V 
10% 
X7R 
A36096-046 
16V 
R7A20 
68.1K 
30 
38 
33 
37 
2
7
40 
10 
IC 
1
4
3
6
35 
39 
5
36 
31 
0.1UF 
X7R 
32 
1/10W 
10% 
0402V 
EMPTY 
25 
50V 
X7R 10% 
CT44 
1/16W 
VR_PVDDQ_DEF_PH1_SW 
L7A1 
10% 
10UF 
1
10UF 
16V 
10% 
X6S 
C95333-007 
0805 
C95333-007 
0805 
1.0UF 
VR_FET_SW_P12V_STBY_PVDDQ_DEF 
10% 
X7R 
0402V 
16V 
2
0.1UF 
1
1.0UF 
TP FAB4 POP CAP ON SS BOM 20170208 
TP FAB1 CHANGE TO 0 OHM 0107 
TP FAB1 CHANGE L7A1 PN 0122 
TP FAB3 CHANGE L7A1 0823 
TP FAB1 ADD NET NAME 12/04 
TP FAB1 CHANGE RES TO 1 OHM 0603 0107 
TP FAB1 CHANGE L7A3 PN 0122 
TP FAB3 CHANGE L7A3 0823 
TP FAB3-DVT NOPOP L7A3 IND FOR SS BOM 20161215 
TP FAB1 CHANGE RES TO 1 OHM 0603 0107 
TP FAB1 ADD NET NAME 12/04 
TP FAB3-DVT CHANGE L7A1 IND FOR SS BOM 20161215 
TP FAB1 CHANGE TO 0 OHM 0107 
TP FAB3-DVT NOPOP FROM SS BOM 20161215 
BOM_SS=NOPOP 
BOM_SS=NOPOP 
218 
219 218 
218 
218 
218 
218 
219 218 
218 
IRMS=66A@DELTA_T<40C 
BOM_DS=068.9002N.1021 
BOM_SS=NOPOP 
DS_ISAT=134A@25C 
BOM_SS=NOPOP 
0603 
0402 
10V 
10% 
1UF 
BOM_SS=NOPOP 
BOM_SS=NOPOP 
BOM_SS=NOPOP 
BOM_SS=NOPOP 
BOM_SS=NOPOP 
1/10W 
1% 
1 OHM BOM_SS=NOPOP 
NOPOP 
DS_ISAT=134A@25C 
DCR=0.17MOHM 
DS_VALUE=90NH 
BOM_SS=NOPOP 
BOM_SS=NOPOP 
GROUP=PWR_MLCC_CAP 
BOM_SS=NOPOP 
BOM_SS=NOPOP 
NOPOP 
IRMS=66A@DELTA_T<40C 
BOM_DS=068.9002N.1021 
SS_VALUE=120NH 
BOM_SS=068.1202N.M001 
DCR=0.17MOHM 
GROUP=PWR_MLCC_CAP 
1UF 
0402 
10V 
10% 
0603 
1/10W 
1 OHM 
1% 
SS_ISAT=94A@25C 
DS_VALUE=90NH 
TP FAB1 CO-LAY WITH TI PARTS 11/16 
TP FAB1 CO-LAY WITH TI PARTS 11/16 
4V 
4V 
SC1U10V2KX-4-GP 
SC1U10V2KX-4-GP 
1 2
2
2
1 1
2
NOPOP 
1 2
2
1
1
NOPOP 2
1
1 2
1
2
1
2
1
1 2
2
DO NOT SCALE DRAWING 
TP FAB1 CO-LAY WITH TI PARTS 11/16 
TP FAB1 CO-LAY WITH TI PARTS 11/16 
2
1
SHEET 
B
AA
B
B
SIZE 
SCALE: 
234
1234
DEPARTMENT CODE 
1
DOCUMENT NUMBER REV 
P5V_STBY 
IN 
PVDDQ_DEF 
OUT 
OUT 
OUT 
OUT 
OUT 
IN 
OUT 
P5V_STBY 
PVDDQ_DEF 
1
1 2
1 22
2
1
Wed Feb 08 16:35:29 2017 
219 OF 270 
1
1
GL<1> 
GL<0> 
PGND<1> 
PGND<0> 
PGND<2> LGND 
VOS 
EN 
VDRV 
VCC 
VIN<0> VIN<1> 
PHASE 
REFIN 
BOOST 
PWM 
SW 
NC 
IOUT 
OCSET 
TOUT_FLT 
GL<1> 
GL<0> 
PGND<1> 
PGND<0> 
PGND<2> LGND 
VOS 
EN 
VDRV 
VCC 
VIN<0> VIN<1> 
PHASE 
REFIN 
BOOST 
PWM 
SW 
NC 
IOUT 
OCSET 
TOUT_FLT 
TP FAB1 CHANGE PN 0310 
TDA21470 
TP FAB1 DEL NET 0309 
TP FAB1 CHANGE PN 0310 
TDA21470 
TP FAB1 DEL NET 0309 
NOPOP 
NOPOP 
NOPOP 
NOPOP 
1
2 2
1
2
11
22
1
2
1
VDDQ DEF_VR (2 OF 3) 
PLACE ON TOP 
PLACE ON TOP 
SPOF 
WIWYNN CORPORATION 
SPOF 
ROOM = VDDQ_DEF_PWR_VR 



BOM_SS=E15431-004 
BOM_SS=E15431-004 
BOM_SS=E15431-004 
BOM_SS=E15431-004 
BOM_SS=E15431-004 
BOM_SS=E15431-004 
BOM_SS=E15431-004 
BOM_SS=E15431-004 
BOM_SS=E15431-004 
BOM_SS=E15431-004 
BOM_SS=E15431-004 
BOM_SS=E15431-004 
BOM_SS=E15431-004 
BOM_SS=E15431-004 
BOM_SS=E15431-004 
BOM_SS=E15431-004 
BOM_SS=E15431-004 
BOM_SS=E15431-004 
BOM_SS=E15431-004 
BOM_SS=E15431-004 
BOM_SS=E15431-004 
BOM_SS=E15431-004 
BOM_SS=E15431-004 
BOM_SS=E15431-004 
BOM_SS=E15431-004 
BOM_SS=E15431-004 
BOM_SS=E15431-004 
BOM_SS=E15431-004 
BOM_SS=E15431-004 
BOM_SS=E15431-004 BOM_SS=E15431-004 
BOM_SS=E15431-004 
X5R 
100UF C5P3 
100UF 100UF 100UF 
C5P6 1
C5D8 
22.0UF 
E15431-004 
0805 
602433-112 
20% 
4V 4V 
20% 
602433-112 2
22.0UF 
E15431-004 
0603V 
20% 
X6S 
E15431-004 2E15431-004 
0603V 
C5B1 
47UF 47UF 
602433-112 
602433-112 
20% 
100UF 
C5L1 
20% 
20% 20% 
602433-112 
0805 0603V 
X6S 
4V 
22.0UF 
C5D6 
20% 
C5D7 C5D9 1
602433-112 
602433-106 
C5D3 C5D4 
0603V 
C5M11 
0805 
602433-112 602433-112 
C5M12 
2
100UF 
SE100U16VM-48-GP 
C5P1 
4V 
20% 
0805 
C5L3 
C7W2 
SH4L1 
IND-100NH-35-GP 
EMPTY 
VSENSE_PVDDQ_DEF_N 
100.0 
1/16W 
G21796-017 
0402 
1% 
2
L7A5 
C7W10 
0603V 
C7W6 
47UF 1 47UF 
C5A9 
47UF 47UF 1
22.0UF 
47UF 
C5A15 
2 602433-106 
0603V 
1
VR_FET_SW_P12V_STBY_PVDDQ_DEF 
602433-106 
X5R 
20% 
4V 
1 C5A3 
C7W8 
N_A 
602433-106 
C7W11 C7W7 
X5R 
0603V 
602433-106 
X5R 
602433-106 
4V 
602433-106 
1
4V 4V 0805 
100UF 
2
C5M9 1
X5R 
1 1
X5R 
0603V 
20% 
C5M5 
47UF 
20% 20% 
X5R 
2602433-106 
0603V 
C5D2 
E15431-004 
0603V 
X6S 
20% 
4V 
22.0UF 1SH4L2 
C5A19 
47UF 
1/10W 
699013-049 
G22026-003 
2
11
2
20% 
4V 
100UF 
602433-112 
0805 
C5P2 
2
22 X6S 
20% 
4V 4V 
C5P4 1
4V 
20805 
C5P5 1 1
2
4V 
2 2 0805 
C5M8 1
4V 
602433-112 
1
2
20% 
4V 
100UF 1 C5L14 
0805 
4V 
20% 
4V 
1
4V 
4V 
VSENSE_PVDDQ_DEF_P 
R4L2 
1
4V 
C5A11 
2
1
0603V 
47UF 
20% 
C4M2 
47UF 
2
0603V 
1
X5R 
4V 
2 X5R 
C5M1 
4V 
1
20% 
47UF 
602433-106 602433-106 
0603V 
20% 
X5R 
2
1 47UF 
4V 
C5M2 
602433-106 
20% 
0603V 
C5M4 
4V 
47UF 
2 X5R 
602433-106 
X5R 
1
4V 
2
0603V 
602433-106 
C5M6 
4V 
47UF 1
0603V 
2 X5R 
20% 
1
0603V 
47UF 
C5M7 
4V 
X5R 
602433-106 
C5L13 
47UF 
20% 
4V 
0603V 
1
2
20% 
C5L12 
47UF 
0603V 
2
1
602433-106 
4V 
X5R 
47UF 
602433-106 
0603V 
C5L11 1
4V 
2 X5R 
20% 
X5R 
602433-106 
0603V 
2
C5L10 
20% 
1 47UF 
4V 
C5L9 
2 X5R 
20% 
4V 
47UF 
0603V 
1
602433-106 602433-106 
0603V 
20% 
X5R 
2
1
4V 
C5L7 
20% 
0603V 
X5R 
602433-106 
4V 
47UF 1
2
47UF 
C5L6 
20% 
X5R 
2
1
0603V 
602433-106 
4V 
4V 
1
2 X5R 
20% 
0603V 
602433-106 
C5A18 
4V 
47UF 1
2 X5R 
20% 
0603V 
2
1
0603V 
602433-106 
X5R 
20% 
4V 
47UF 
C5A17 
4V 
47UF 1
2
20% 
C5A4 
602433-106 
X5R 
0603V 0603V 
602433-106 
C5A16 
20% 
X5R 
2
1 47UF 
4V 2
0603V 
20% 
X5R 
1
4V 
0603V 
602433-106 
4V 
1
2 X5R 
20% 
C5A8 
2
0603V 
1
X5R 
20% 
4V 
47UF 
C5A7 
X5R 
C5A6 
20% 
47UF 
4V 
0603V 
602433-106 2
1
602433-106 
20% 
2
4V 
C5A14 
X5R 
0603V 
C5A2 
4V 
1
2
20% 
0603V 
602433-106 
4V 
2 X5R 
20% 
2 X5R 
602433-106 
0603V 
C5A12 
20% 
4V 
47UF 1
2
20% 
4V 
47UF 
0603V 
602433-106 2
1 C5A1 
1
4V 
1 22.0UF 1
X6S 2
20% 
4V 
20% 
X6S 
E15431-004 
1 C5D1 
2
0603V 0603V 
X6S 
20% 
4V 
2 E15431-004 
1 22.0UF 
20% 
X6S 
E15431-004 2
0603V 
1
2
22.0UF 
2
21
N_A 
47UF 
20% 
X5R 
1
2
47UF 
2
1
2
20% 
1
20% 
4V 
X5R 
2
1
2
4V 
602433-106 
0603V 
1
2
1 47UF 
20% 
4V 
2 X5R 
C5L15 
C7W13 C7W12 C7W9 
2 602433-112 
4V 
20% 
1 100UF 1
1
2
1
2 2
1
0603 
CHIP 
1% 
R4L4 
120.0 1
2
1
2
C4L5 
3018 
ALUM 
2.5V 
20% 
C6A5 
470UF 
20% 
ALUM 
699013-049 
3018 
C3L14 
470UF 
20% 
2.5V 
ALUM 
699013-049 
3018 3018 
ALUM 
2.5V 
20% 
470UF 
C3L6 
C7W5 
C5A13 
4V 
20% 
C5L8 
47UF 
602433-106 
0603V 0603V 
602433-106 
X5R 
1 47UF 
X5R 
47UF 
470UF 
2.5V 
699013-049 
1
2
20% 
4V 
20% 
2
20% 
4V 
47UF 
602433-106 
0805 
C5M3 
4V 
20% 
0603V 
4V 
0603V 
602433-106 
X5R 
0805 
20% 
2
C4M5 
47UF 
0805 
C5A20 
100UF 
602433-112 
C5B2 
47UF 
602433-106 
0603V 
602433-106 
X5R 
47UF 
C5M10 
C5A5 
602433-106 
4V 
0805 
602433-112 
100UF 
C5A10 C5L2 
100UF 
20% 
602433-112 
0805 
100UF 
20% 
602433-106 
0603V 
20% 
X5R 
602433-106 
0603V 
TP FAB1 DELETE CAP C7A19 AND CAP C7W2-C7W13 0324 
BOTTOM SIDE: 805 
TP FAB1 CHANGE L7A5 PN 0122 
TP FAB3-DVT CHANGE CAP 20161114 
TP FAB3-DVT DELETE C7W3, C7W4 ; CHANGE  C7W2 TO OSC 20161118 
TOP SIDE: 603 
TP FAB1 CHANGE CONNECTION 0318 
TP FAB3-DVT NOPOP FROM SS BOM 20161220 TP FAB3-DVT CHANGE CAP IN SS BOM 20161220 
TP FAB1 CHANGE CAP 0311 
TP FAB3-DVT NOPOP FROM SS BOM 20161220 
TP FAB1 CHANGE CAP 0311 
TP FAB3-DVT NOPOP FROM SS BOM 20161220 
TP FAB1 CHANGE CAPACITY 0322 
TP FAB3-DVT NOPOP FROM SS BOM 20161220 
NEW_PN=078.1071T.0811 
218 
218 
NEW_PN=078.1071T.0811 
NEW_MATERIAL=X6S 
NEW_PN=078.1071T.0811 
BOM_SS=NOPOP 
NEW_PN=078.1071T.0811 
NEW_MATERIAL=X6S 
GROUP=PWR_MLCC_CAP 
NEW_PN=078.1071T.0811 
GROUP=PWR_MLCC_CAP 
NEW_PN=078.1071T.0811 
NEW_MATERIAL=X6S 
GROUP=PWR_MLCC_CAP 
BOM_SS=NOPOP 
GROUP=PWR_MLCC_CAP 
GROUP=PWR_MLCC_CAP 
GROUP=PWR_MLCC_CAP 
BOM_SS=NOPOP 
NEW_MATERIAL=X6S 
BOM_SS=NOPOP 
BOM_SS=NOPOP 
BOM_SS=NOPOP 
BOM_SS=NOPOP 
GROUP=PWR_MLCC_CAP 
GROUP=PWR_MLCC_CAP 
NEW_MATERIAL=X6S 
GROUP=PWR_MLCC_CAP 
16V 
X6S X6S 
ISAT=16A@25C 
IRMS=29A@DELTA_T<45C 
DCR=0.16MOHM 
16V 
0805 
100UF 
100NH 
22UF 
20% 
22UF 
GROUP=PWR_MLCC_CAP 
22UF 
GROUP=PWR_MLCC_CAP 
16V 
20% 20% 
0805 
X6S 
16V 
22UF 
0805 
22UF 
0805 
20% 
0805 
GROUP=PWR_BULK_CAP 
GROUP=PWR_MLCC_CAP 
GROUP=PWR_MLCC_CAP 
NEW_MATERIAL=X6S 
GROUP=PWR_MLCC_CAP 
GROUP=PWR_MLCC_CAP 
GROUP=PWR_MLCC_CAP 
GROUP=PWR_MLCC_CAP 
GROUP=PWR_MLCC_CAP 
GROUP=PWR_MLCC_CAP 
GROUP=PWR_MLCC_CAP GROUP=PWR_MLCC_CAP 
GROUP=PWR_MLCC_CAP GROUP=PWR_MLCC_CAP 
GROUP=PWR_MLCC_CAP 
GROUP=PWR_MLCC_CAP 
GROUP=PWR_MLCC_CAP 
GROUP=PWR_MLCC_CAP 
GROUP=PWR_MLCC_CAP 
GROUP=PWR_MLCC_CAP 
GROUP=PWR_MLCC_CAP 
GROUP=PWR_MLCC_CAP 
GROUP=PWR_MLCC_CAP 
GROUP=PWR_MLCC_CAP GROUP=PWR_MLCC_CAP 
GROUP=PWR_BULK_CAP GROUP=PWR_BULK_CAP 
GROUP=PWR_BULK_CAP 
NEW_MATERIAL=X6S 
X6S 
20% 
16V 
X6S 
20% 
16V 
X6S 
0805 
22UF 
16V 
0805 0805 
16V 
20% 
22UF 22UF 
20% 
X6S 
0805 
20% 
22UF 
X6S X6S 
16V 16V 
GROUP=PWR_MLCC_CAP GROUP=PWR_MLCC_CAP GROUP=PWR_MLCC_CAP GROUP=PWR_MLCC_CAP 
GROUP=PWR_MLCC_CAP 
GROUP=PWR_MLCC_CAP 
GROUP=PWR_MLCC_CAP 
GROUP=PWR_MLCC_CAP 
GROUP=PWR_MLCC_CAP 
GROUP=PWR_MLCC_CAP 
GROUP=PWR_MLCC_CAP GROUP=PWR_MLCC_CAP GROUP=PWR_MLCC_CAP 
BOM_SS=NOPOP BOM_SS=NOPOP BOM_SS=NOPOP 
GROUP=PWR_MLCC_CAP 
BOM_SS=NOPOP 
NEW_MATERIAL=X6S 
BOM_SS=NOPOP 
GROUP=PWR_MLCC_CAP 
NEW_PN=078.1071T.0811 
NEW_MATERIAL=X6S 
BOM_SS=NOPOP 
GROUP=PWR_MLCC_CAP 
NEW_PN=078.1071T.0811 
GROUP=PWR_MLCC_CAP 
GROUP=PWR_MLCC_CAP 
BOM_SS=NOPOP 
NEW_PN=078.1071T.0811 
NEW_MATERIAL=X6S 
GROUP=PWR_MLCC_CAP 
BOM_SS=NOPOP 
NEW_PN=078.1071T.0811 
GROUP=PWR_MLCC_CAP 
NEW_PN=078.1071T.0811 
NEW_MATERIAL=X6S 
BOM_SS=NOPOP 
GROUP=PWR_MLCC_CAP 
NEW_MATERIAL=X6S 
BOM_SS=NOPOP 
GROUP=PWR_MLCC_CAP
NEW_MATERIAL=X6S 
NEW_PN=078.1071T.0811
NEW_PN=078.1071T.0811 
NEW_MATERIAL=X6S 
BOM_SS=NOPOP 
GROUP=PWR_MLCC_CAP 
NEW_PN=078.1071T.0811 
BOM_SS=NOPOP 
GROUP=PWR_MLCC_CAP 
GROUP=PWR_MLCC_CAP 
GROUP=PWR_MLCC_CAP 
BOM_SS=NOPOP 
GROUP=PWR_MLCC_CAP 
BOM_SS=NOPOP BOM_SS=078.1061T.M001 
BOM_SS=NOPOP 
GROUP=PWR_MLCC_CAP 
GROUP=PWR_MLCC_CAP 
SC22U16V5MX-4-GP 
SC22U16V5MX-4-GP 
SC22U16V5MX-4-GP 
SC22U16V5MX-4-GP 
SC22U16V5MX-4-GP 
SC22U16V5MX-4-GP 
SC22U16V5MX-4-GP 
SC22U16V5MX-4-GP 
SC22U16V5MX-4-GP 
ROUT AS DIFF PAIR 
5MIL SPACING 
10MIL WIDTH 
21
DO NOT SCALE DRAWING SHEET 
B
AA
B
B
SIZE 
SCALE: 
234
1234
DEPARTMENT CODE 
1
DOCUMENT NUMBER REV 
PVDDQ_DEF 
PVDDQ_DEF 
PVDDQ_DEF 
IN 
IN 
PVDDQ_DEF 
PVDDQ_DEF 
PVDDQ_DEF 
PVDDQ_DEF 
PVDDQ_DEF 
PVDDQ_DEF 
PVDDQ_DEF 
PVDDQ_DEF 
P12V_STBY 
PVDDQ_DEF 
2
2
1
1
1
2
1
1
2
2
2
2
1
1
1
2
2
1
1
2
PVDDQ_DEF VOLTAGE SENSE 
INPUT FILTER 
220 OF 270 
Wed Feb 08 16:35:29 2017 
220 OF 270 
PLACE NEAR VR OUTPUT INDUCTORS 
TP FAB1 CHANGE CAP 0322 
CAD NOTE: 
ROOM=VDDQ_DEF_CPU0 
TP FAB1 CHANGE CAP OF SINGLE SIDE 0504 
TP FAB1 CHANGE CAP 0314 
CAPS TO BE PLACED BETWEEN DIMMS 
PVDDQ CPU CAVITY CAPS 
TP FAB1 CHANGE CAP 0322 
VDDQ DEF DECAP (3 OF 3) 
WIWYNN CORPORATION ROOM = PVDDQ_DEF_PWR_VR 



G21497-005 
C6U16 
100UF 
602433-112 
C6W11 
100UF 
A36096-046 
0603V 
0805 
602433-112 
C5U16 1
2
20% 
4V 
1
2
20% 
4V 
100UF 
602433-112 
0805 
C5U12 
22UF 
C4G24 
0402LF 
10% X6S 
D97712-011 
0402 
VSENSE_PVDDQ_ABC_VTT 
G21497-005 
1/16W 
PLACE CLOSE TO CONTROLLER 
PWRGD_PVDDQ_ABC_R 
VR_PVTT_ABC_VREF 
PWRGD_PVTT_ABC_CPU0_R 
VR_PVTT_ABC_SNS 
VR_PVTT_ABC_BIAS 
FM_PVTT_ABC_EN_R 
PLACE NEAR CENTER 
OF PVTT PLANE 
SPOF 2
SH5U1 
1
N_A 
0.0 5% 
R6U5 
0402 
0402 
G21796-021 
EMPTY 
1/16W 
1% 
1.0M 
R6U15 
1
2
0402 
0.0 5% 
CHIP 
1/16W 
R4G23 
21
1% 
2
R4G19 
G21796-074 
0402 
1
10% 
C4G14 
X7R 
50V 
1000PF 1
2
CHIP 
1/16W 
1% 
2
1 10.0K 
R4G18 
4V 
0805LF 
X6S 
20% 
1
2
D97712-011 
0402 
10% 
1.0UF 16V 
X6S 
C4G16 1
2
50V 
10% 
1000PF 
0402LF 
EMPTY 
C4G23 1
2
0603LF 
E15431-001 
X6S 
20% 
4V 
10UF 1
2
0603LF 
E15431-001 
X6S 
20% 
4V 
10UF 
C6U15 1
2
H55101-001 
6
1
8
2
9
EU4G3 
IC 
7
4
10 
5
3
11 
0402 
CHIP 
5% 0.0 
G21497-005 
1/16W 
R6U4 
21
2
16V 1.0UF 
C4G15 1
2
E15431-003 
X6S 
10% 
6.3V 
4.7UF 
C6U12 1
0603 
1
4V 
20% 
2 X5R 
0402 
G21796-016 
33.2 
CHIP 
PLACE CLOSE TO CONTROLLER 
PWRGD_PVTT_CPU0 
1/16W 
602433-106 
47UF 
C5T3 
1
2
20% 
4V 
0805 
215 
222 191 
GROUP=PWR_MLCC_CAP 
NEW_PN=078.1071T.0811 
NEW_PN=078.1071T.0811 
NEW_PN=078.1071T.0811 
GROUP=PWR_MLCC_CAP 
GROUP=PWR_MLCC_CAP 
GROUP=PWR_MLCC_CAP 
GROUP=PWR_MLCC_CAP 
NEW_MATERIAL=X6S 
NEW_MATERIAL=X6S 
NEW_MATERIAL=X6S 
A36096-046 
1
2
C95333-002 
CAD NOTE: 
CAD NOTE: 
CAD NOTE: 
CAD NOTE: 
CAD NOTE: 
IOUT STEP=+ 1.523A / - 1.546A 
AC & RIPPLE=+3.5/-7.3% 
IOUT PEAK=+-/1.4A 
IOUT TDC=+/-1.4A 
RIPPLE GUIDELINE= +/-1% 
IOUT DI/DT=6A/US 
VOUT=0.5 VDDQ 
DC TOL= +/-1.5% 
DO NOT SCALE DRAWING SHEET 
B
AA
B
B
SIZE 
SCALE: 
234
1234
DEPARTMENT CODE 
1
DOCUMENT NUMBER REV 
PVDDQ_ABC 
P3V3 
OUT 
PVTT_ABC 
IN 
PVTT_ABC 
P3V3 
PVTT DDR SPECIFICATION: 
CRTICAL: PLACE 0 OHM NEAR  VDDQ SENSE RESISTOR. 
221 OF 270 
Wed Feb 08 16:35:29 2017 
MIC5166 
THPAD 
VTT 
PGND SNS 
VDDQ 
PG 
AGND BIAS 
VREF 
VIN 
EN 
PLACE BETWEEN DIMMS 
TP FAB1 CHANGE CONNECTION 0303 
TP FAB1 CHANGE RES TO CAP 0311 
TP FAB3 CHANGE CAP 0803 
DDR VTT VR CHANNEL ABC 
ROOM = VTT_ABC_PWR_VR 
BOM = MEM_VRD_VTT_ABC 
YRANIMILERP
WIWYNN CORPORATION 



0402LF 
0402 
4V 
C5M13 
602433-112 
0805 
20% 
602433-112 
0603V 
602433-106 
X5R 
20% 
A36096-046 
4V 
C4W5 
0805 
602433-112 
100UF 
20% 
2
1
C4A12 
G21796-074 
2
22UF 
C4A9 
3
N_A 
E15431-001 
VR_PVTT_DEF_VREF 
PWRGD_PVTT_CPU0 
PWRGD_PVDDQ_DEF_R 
VR_PVTT_DEF_SNS 
VR_PVTT_DEF_BIAS 
VSENSE_PVDDQ_DEF_VTT 
FM_PVTT_DEF_EN_R 
PWRGD_PVTT_DEF_CPU0_R 
PLACE CLOSE TO CONTROLLER 
PLACE CLOSE TO CONTROLLER 
SPOF 
OF PVTT PLANE 
PLACE NEAR CENTER 
0603 
E15431-003 
X6S 2
1
10% 
6.3V 
4.7UF 
C4A11 
0402 0.0 1/16W 5% 
R6L10 
G21497-005 
0402 
G21796-021 
EMPTY 
1/16W 
1% 
1.0M 
R6L4 
2
1
CHIP 
1/16W 0.0 5% 
G21497-005 
R4A2 
1 2
21
0402 
1 2
SH5L1 
20% 
X6S 
4V 
C4A1 1
2 0805LF 
0402 
G21796-016 
CHIP 
1/16W 
R6L9 
2
1
1% 
10.0K 
X7R 
10% 
50V 
2
1 1000PF 
D97712-011 
X6S 
1.0UF 16V 
10% 2 0402 
1
0402LF 
10% 
1000PF 
EMPTY 
50V 
C4A2 
2
1
20% 
X6S 
2
10UF 
E15431-001 
0603LF 
1
0603LF 
X6S 
20% 
C6L4 
10UF 
4V 
2
1
H55101-001 
6
9
2
8
7
10 
IC 
EU4A1 
1
5
11 
4
0402 
D97712-011 
10% X6S 
1.0UF 
C4A10 
16V 
2
10402 
CHIP 1/16W 
0.0 5% 
G21497-005 
21
R6L11 
1% 
R4A6 
CHIP 1/16W 
33.2 
47UF 
1
C6L3 
4V 
C5L5 
100UF 
4V 
2
1
2
C5L4 1
100UF 
4V 
20% 
0805 
221 191 
218 
GROUP=PWR_MLCC_CAP 
NEW_PN=078.1071T.0811 
NEW_PN=078.1071T.0811 
NEW_PN=078.1071T.0811 
GROUP=PWR_MLCC_CAP 
GROUP=PWR_MLCC_CAP 
NEW_MATERIAL=X6S 
GROUP=PWR_MLCC_CAP 
GROUP=PWR_MLCC_CAP 
NEW_MATERIAL=X6S 
NEW_MATERIAL=X6S 
A36096-046 
C95333-002 
1
2 CAD NOTE: 
CAD NOTE: 
CAD NOTE: 
CAD NOTE: 
CAD NOTE: 
IOUT TDC=+/-1.4A 
IOUT PEAK=+-/1.4A 
RIPPLE GUIDELINE= +/-1% 
AC & RIPPLE=+3.5/-7.3% 
IOUT STEP=+ 1.523A / -1.546A 
IOUT DI/DT=6A/US 
VOUT=0.5 VDDQ 
DC TOL= +/-1.5% 
CHIP 
DO NOT SCALE DRAWING SHEET 
B
AA
B
B
SIZE 
SCALE: 
234
1234
DEPARTMENT CODE 
1
DOCUMENT NUMBER REV 
P3V3 
PVDDQ_DEF 
PVTT_DEF 
OUT 
IN 
PVTT_DEF 
P3V3 
PVTT DDR SPECIFICATION: 
222 OF 270 
Wed Feb 08 16:35:30 2017 
MIC5166 
THPAD 
VTT 
PGND SNS 
VDDQ 
PG 
AGND BIAS 
VREF 
VIN 
EN 
PLACE BETWEEN DIMMS 
TP FAB3 CHANGE CAP 0803 
TP FAB1 CHANGE RES TO CAP 0311 
CRTICAL: PLACE 0 OHM NEAR  VDDQ SENSE RESISTOR. 
TP FAB1 CHANGE CONNECTION 0303 
DDR VTT VR CHANNEL DEF 
ROOM = VTT_DEF_PWR_VR 
BOM_COST = MEM_VRD_VTT_DEF 
YRANIMILERP
WIWYNN CORPORATION 



1/16W 
TP FAB4 NOPOP RF20 AND CF20 FOR SS BOM 20170124 
TP FAB4 CHANGE RF19 TO 953OHM FOR VR FAILCHILD, SINGLE SIDE BOM 20170123 
TP FAB1 ADD RES 0303 
TP FAB3 POP R12W31 0919 
TP FAB1 CHANGE R1G23 RES 0523 
TP FAB1 CHANGE R1G23 RES AND NOPOP R1G22 0408 
TP FAB3 NOPOP R1G23 AND CHANGE R1G22 0804 
TP FAB3 NOPOP R1G12 0919 
TP FAB3 POP R1G6 1014 
TP FAB1 CO-LAY WITH FAIRCHILD PARTS 1203 
TP FAB1 NC 0321 
55 193 226 
138 159 211 213 235 193 
194 201 206 215 218 226 
138 159 193 194 201 206 
211 213 215 218 226 235 
224 
197 
224 
193 226 55 
94 119 144 
191 
225 
55 193 226 
229 
224 
225 
224 
224 
197 
197 
224 
223 
224 
223 
SVID_DIO1_CPU1_R 
SMB_VR_STBY_LVC3_SCL 
SMB_VR_STBY_LVC3_SDA 
0402 
C1G27 
0.1UF 
SVID_CLK_PVDDQ_GHJ X7R 
A36096-030 
0402V 
EU1G2 
IC 
15 
FAIR_SS=064.9530D.M001 
50V 
GROUP=POWER_FAIR 
GROUP=POWER_FAIR 
1/16W 
CHIP 
0402 
RF19 1.0K 0.1% 
G85996-004 
SC22P50V2JN-4GP 
0402 
CF19 
22PF 
A_TSENSE_PVDDQ_GHJ 
150.0 
0402 
G21796-311 
R1G6 
2.26K 
1.0% 
1/16W 
CHIP 
G21497-005 0402 
5% EMPTY 
1/16W 
1% 
1 100.0 
R9U3 
0402 
G21796-017 
2 CHIP 
0402 
1/16W 
G21796-026 
0402 
0402 
PWRGD_PVDDQ_GHJ 
1.0% 22.1 G21796-250 
R1G12 
0402 
PU_VR_PVDDQ_GHJ_FAULT1 R12W31 5% 1 2G21497-005 0.0 
2 1/16W 
VR_PVDDQ_GHJ_PWM1 
IRQ_PVDDQ_GHJ_VRHOT_LVT3_R_N 
1/16W 
SVID_ALERT1_CPU1_R_N 
IRQ_PVDDQ_GHJ_VRHOT_LVT3_N 
CHIP 1/16W 
CHIP NOPOP 
R1G8 33.2 1% 
G21497-005 
1
2
1% 
R1G22 
3.16K 
1/16W 
0402 
G21796-043 
27 
2
28 
X7R 
A36096-046 
5% 
NPO 
0402 
NOPOP 
1/16W 
1.0% 
R1G23 
2 CHIP 
1 5.36K 
20402LF 
A36096-050 
FM_PVDDQ_GHJ_EN 
VSENSE_PVDDQ_GHJ_P 
SVID_CLK1_CPU1_R 
SVID_ALERT_PVDDQ_GHJ 
TP_PVDDQ_GHJ_MP1 
SVID_VDIO_PVDDQ_GHJ 
PWRGD_PVDDQ_GHJ_R 
VR_PVDDQ_GHJ_VDD 
VR_PVDDQ_GHJ_AIREF1 
VR_PVDDQ_GHJ_VREN 
VSENSE_PVDDQ_GHJ_N 
VR_PVDDQ_GHJ_AVSP 
ISENSE_PVDDQ_GHJ_PH1_IMON 
ISENSE_PVDDQ_GHJ_PH2_IMON 
VR_PVDDQ_GHJ_VINSEN 
VR_PVDDQ_GHJ_AIINSEN 
TP_PVDDQ_GHJ_MP2 
1% 
1
2 CHIP 
G21796-047 
1/16W 
49.9 
R9U4 
18 
12 
31 
32 
36 
30 
20 
10 
35 
37 
38 
11 
39 
29 
34 
1
5
H89186-001 
9
17 
26 
23 
21 
6
14 
13 
33 
8
19 
25 
7
16 
3
4
24 
22 
40 
2
G21796-074 
1
0.0 
1 2
R12W33 
1
5% 
2
G21497-005 
0.0 R1G9 
CHIP 
1/16W 
CHIP 
1
1% 
1/16W 
1.00K 
R1G11 
2
G21796-026 
0402 
1/16W 
1% 
R1G16 
1.00K 1
0402 
CHIP 2
R12W32 EMPTY 10.0 5% G21497-005 
6.3V 
D97712-004 
0402V 
X6S 
1.0UF 
C1G23 
16V 
0.1UF 
10% 
1
A36096-030 
0402V 
2 X7R 
1
CHIP 
0.0 
2
0402 
R1G10 
G21497-005 
1
10% 
50V 
0402LF 
2
C1G21 
1.0UF 
0402V 
D97712-004 
X6S 
10% 
6.3V 
1 C1G25 
2
10% 
16V 
R9U10 
0.0 
0402 
CHIP 
1/16W 
1
2
5% 
R9U8 
G21796-010 
EMPTY 
1/16W 
1% 
0402 
100.0K 
10% 1220PF 
50V X7R 
C1G24 
1% 
21
R9U7 
G21497-005 
5% 
CHIP 1/16W 
0.0 0402 
2
R1G5 
G21796-066 
1
10.0 1% 0402 
CHIP 1/16W 
10% 
C1G16 1
X7R 
0402LF 
220PF 
A36096-050 
50V 
2
41 
1/16W 
5% 
VR_PVDDQ_GHJ_PWM2 
VR_PVDDQ_GHJ_VD12 
1000PF 
VR_PVDDQ_GHJ_AIREF2 
R1G7 
G21796-009 
0402 
1/16W CHIP 
0402 
10% 
C1G22 
VR_PVDDQ_GHJ_VD12 
CHIP 
G21796-297 
RF20 1/16W 
0402 CHIP G85996-004 
1.0K 0.1% 
CF20 
0402 NPO 
22PF 5% 
SC22P50V2JN-4GP 
50V 
BOM_SS=NOPOP 
GROUP=POWER_FAIR 
BOM_SS=NOPOP 
GROUP=POWER_FAIR 
VR_PVDDQ_GHJ_XADDR1 
VR_PVDDQ_GHJ_XADDR2 
DESIGN NOTE: 
DESIGN NOTE: 
1
21
2
1
1 2
2
1
2
1
2
21
21
SW FREQ = 833.33KHZ 
IOUT DI/DT = 15A/US/18.09A/US FOR DS/SS 
VOUT = 1.2V 
DC TOL = +/-0.5% 
IOUT TDC = 65.7A/25.86A FOR DS/SS 
AC & RIPPLE TOL = +/2.8% 
RIPPLE GUIDELINE = +/- 0.5% 
IOUT PK = 73A/29.38A FOR DS/SS 
IOUT STEP = 45A/17.96A FOR DS/SS 
21 1 2
DO NOT SCALE DRAWING 
FAIRCHILD:POP 
CF19&CF20 
RF19&RF20 
INFINEON:NOPOP 
SHEET 
B
AA
B
B
SIZE 
SCALE: 
234
1234
DEPARTMENT CODE 
1
DOCUMENT NUMBER REV 
IN 
IN 
IN 
OUT 
OUT 
OUT 
IN 
BI 
OUT 
BI 
OUT 
OUT 
IN 
IN 
PVCCIO_CPU1 
P3V3_STBY 
OUT 
IN 
IN 
P3V3_STBY 
IN 
PVCCIO_CPU1 
IN 
IN 
IN 
IN 
223 OF 270 
Wed Feb 08 16:35:30 2017 
SVID ADDRESS 
PXM1310C 
MP2 
THPAD 
BPWM1 
APWM1 
APWM2 
APWM3 
SDA 
SCL 
VCLK 
VDIO 
RESET_N 
XADDR1 
AISEN3 
AIREF3 
XADDR2 
AISEN2 
AIREF2 
ATSEN 
AISEN1 
AIREF1 
VDD 
BTSEN 
BISEN1 
BIREF1 
DNC<0> 
DNC<1> 
VRHOT_N 
PINALRT_N 
VALRT_N 
AVSEN 
AVREF 
BVSEN 
BVREF 
VINSEN 
VD12 
GND 
IINSEN 
AVRRDY 
AVREN 
MP0 
MP1 
TP FAB1 NC 0321 
TP FAB1 DELETE RES 0203 
TP FAB1 DEL RES 0314 
TP FAB1 DEL CAP 0218 
TP FAB1 POP RES 0316 
TP FAB1 NC 0321 
TP FAB1 NC 0321 
TP FAB1 NC 0321 TP FAB1 DEL NETS 0309 
TP FAB1 NC 0321 
TP FAB1 DEL NET 0309 
PVDDQ_GHJ: 0X00(BUS #2) 
SMBUS ADDRESS: 0XA0 
VDDQ GHJ_VR (1 OF 3) 
WIWYNN CORPORATION ROOM=VDDQ_GHJ_PWR_VR 



1/16W 
CHIP 
CHIP 
1/16W 
TP FAB1 CO-LAY WITH TI PARTS 11/16 
4V 
F S
F S
VR_PVDDQ_GHJ_PH2_VCIN 
D97712-011 
0.220UF 
C1F26 
A36096-030 
C1F21 
C95333-007 
VR_FET_SW_P12V_STBY_PVDDQ_GHJ 
1 C1G13 
1.0UF 
16V D97712-011 
0402V 0805 
C95333-007 2 C95333-007 
0805 
10UF 
16V 
0402 
10% 
X7R 
C9T6 
10UF 
16V 
0805 
X6S 
10% 
VR_PVDDQ_GHJ_PH2_BOOT 
VR_PVDDQ_GHJ_PWM2 
X6S 
C9T9 
10% 
10UF 
VR_FET_SW_P12V_STBY_PVDDQ_GHJ 
X7R 
10% 
VR_PVDDQ_GHJ_PH1_PHASE 
VR_PVDDQ_GHJ_PH1_BOOT 
G22178-002 
EU1F1 
EMPTY 
1/16W 
1% 
1000PF 
CT32 36 
34 
VR_PVDDQ_GHJ_PH2_BOOT_R 
RT21 
16V 
0.1UF 
VR_PVDDQ_GHJ_PH2_SW_RC 
CT33 
C1F28 
0.1UF 
16V 
10% 
33 
TP_PVDDQ_GHJ_PH2_GL_0 
TP_PVDDQ_GHJ_PH2_GL_1 
0.22UF 
41 
CHIP 
G22178-002 
R1G25 
C1G20 
50V 
VR_PVDDQ_GHJ_PH2_SW 
X7R 
VR_PVDDQ_GHJ_PH2_OCSET 
ISENSE_PVDDQ_GHJ_PH2_IMON 38 
A36096-046 
0402LF 
20% 
0402 
10% 
X7R 
0402V 
H73688-001 
A36096-030 
16V 
X7R 
A36096-155 
10 
RT22 
1R3F-GP 
2 X6S 
L1G1 
0805LF 
68.1K 
1
A36096-046 
20% 
G21796-187 
0402 
C95333-002 
22UF 
C1G17 1
X6S 2VR_PVDDQ_GHJ_PH1_SW_RC 
VR_PVDDQ_GHJ_PH1_SW 
CT29 1000PF 10% 0402LF 
50V X7R A36096-046 
RT20 
1R3F-GP 
EU1G1 
5.0% 
37 VR_PVDDQ_GHJ_PH1_OCSET 
30 
37 
VR_PVDDQ_GHJ_AIREF2 
VR_PVDDQ_GHJ_PH1_BOOT_R 
D97712-011 
36 
1000PF 
50V 
10% 
X7R 
C1G29 
0402 
A_TSENSE_PVDDQ_GHJ 
CT31 
A_TSENSE_PVDDQ_GHJ 
VR_PVDDQ_GHJ_AIREF1 
ISENSE_PVDDQ_GHJ_PH1_IMON 
TP_PVDDQ_GHJ_PH1_GL_1 
1
10% 
10UF 
X6S 
1
2
1 C9U3 
2 2 X6S 2
1 C1G28 1
1.0UF 
10% 
0402 
16V 
1
0402 
2A36096-104 
X7R 
1
2
10% 
A36096-155 
0402 16V 
10% 
2
X7R 
A36096-030 
10% 
16V 
0.1UF 
C1G14 
2
1
X7R 
0402V 0402 
1
2
C1G6 
1.0UF 
16V 
X6S 
C1F27 
D97712-011 
1.0UF 
10% 
0402 
X6S 
1
2
16V 
2
1
X6S 
16V 
10UF 
C95333-007 
C9T4 
0805 
2 C95333-007 
0805 
C9U4 
16V 
10% 
X6S 
11
16V 
2
0805 
10UF 
C9U6 
C95333-007 
X6S 
10% 
C1G11 
0.220UF 
16V 
1
0402 
10% 
X7R 
A36096-104 2
VR_PVDDQ_GHJ_PWM1 
R9U12 
2
5% 0.0 
1
0402 
G21497-005 
5.0% 0603 
1/10W 
0
RT19 
16V 
1000PF 
CT28 
A36096-046 
10% 
X7R 
50V 
0402LF 
10% 
0.1UF 
1/16W 
EMPTY 
R1G26 
1% 
6
7
2
1
4
25 
31 
5
3
32 
39 
35 
2
5
7
6
39 
35 
1
30 
4
3
IC 
31 
38 
25 
34 
H73688-001 
10 33 
32 
40 
1/10W 
0
VR_PVDDQ_GHJ_PH2_PHASE 
CHIP 
0603 
TP_PVDDQ_GHJ_PH1_GL_0 
IC 
41 
0402V 
A36096-030 
16V 
CT30 
40 
10% 
0.22UF 1
G21497-005 
0.0 0402 5% 
R9U1 
21
VR_PVDDQ_GHJ_PH1_VCIN 
C1G4 C1G5 
0402LF 
G21796-187 
68.1K 
22UF 
C95333-002 
0805LF 
10% 
L1F2 
16V 
10% 
2 X6S 
TP FAB4 POP CAP ON SS BOM 20170208 
TP FAB3 CHANGE L1F2 0823 
TP FAB3-DVT CHANGE L1G1 IND FOR SS BOM 20161215 
TP FAB1 CHANGE L1G1 PN 0122 
TP FAB3 CHANGE L1G1 0823 
TP FAB1 CHANGE RES TO 1 OHM 0603 0107 
TP FAB1 CHANGE TO 0 OHM 0107 
TP FAB1 CHANGE L1F2 PN 0122 
TP FAB1 CHANGE TO 0 OHM 0107 
TP FAB3-DVT NOPOP L1F2 IND FOR SS BOM 20161215 
1UF 
BOM_SS=NOPOP 
223 
223 
223 
224 223 
224 223 
223 
223 
223 
DS_ISAT=134A@25C BOM_SS=NOPOP 
BOM_SS=NOPOP 
BOM_SS=NOPOP 
BOM_SS=NOPOP BOM_DS=068.9002N.1021 
DS_VALUE=90NH 
IRMS=66A@DELTA_T<40C 
NOPOP 
0603 
BOM_SS=NOPOP 1/10W 
BOM_SS=NOPOP 
10% 
10V 
0402 
DCR=0.17MOHM 
GROUP=PWR_MLCC_CAP 
IRMS=66A@DELTA_T<40C 
DCR=0.17MOHM 
BOM_SS=068.1202N.M001 
SS_VALUE=120NH 
SS_ISAT=94A@25C 
BOM_DS=068.9002N.1021 
DS_VALUE=90NH 
DS_ISAT=134A@25C 
GROUP=PWR_MLCC_CAP 
NOPOP 
0603 
1/10W 
1 OHM 
1% 
1 OHM 
1% 
1UF 
10% 
10V 
0402 
BOM_SS=NOPOP BOM_SS=NOPOP 
BOM_SS=NOPOP 
BOM_SS=NOPOP 
BOM_SS=NOPOP 
BOM_SS=NOPOP 
BOM_SS=NOPOP 
TP FAB1 CO-LAY WITH TI PARTS 11/16 
TP FAB1 ADD NET NAME 12/04 
TP FAB1 ADD NET NAME 12/04 
TP FAB1 CO-LAY WITH TI PARTS 11/16 
4V 
SC1U10V2KX-4-GP 
SC1U10V2KX-4-GP 
TP FAB1 CHANGE RES TO 1 OHM 0603 0107 
NOPOP 
2
2
1
21
1
2
NOPOP 
2
2
2
1
1
2
2
1
2
1
2
1
1
1
1
2
1
DO NOT SCALE DRAWING 
TP FAB1 CO-LAY WITH TI PARTS 11/16 
TP FAB1 CO-LAY WITH TI PARTS 11/16 
TP FAB1 CO-LAY WITH TI PARTS 11/16 
SHEET 
B
AA
B
B
SIZE 
SCALE: 
234
1234
DEPARTMENT CODE 
1
DOCUMENT NUMBER REV 
P5V_STBY 
P5V_STBY 
IN 
PVDDQ_GHJ 
OUT 
OUT 
OUT 
OUT 
OUT 
IN 
OUT 
PVDDQ_GHJ 
1
2 1
2 1
2
2 1
224 OF 270 
Wed Feb 08 16:35:30 2017 
1
GL<1> 
GL<0> 
PGND<1> 
PGND<0> 
PGND<2> LGND 
VOS 
EN 
VDRV 
VCC 
VIN<0> VIN<1> 
PHASE 
REFIN 
BOOST 
PWM 
SW 
NC 
IOUT 
OCSET 
TOUT_FLT 
GL<1> 
GL<0> 
PGND<1> 
PGND<0> 
PGND<2> LGND 
VOS 
EN 
VDRV 
VCC 
VIN<0> VIN<1> 
PHASE 
REFIN 
BOOST 
PWM 
SW 
NC 
IOUT 
OCSET 
TOUT_FLT 
TP FAB1 CHANGE PN 0310 
TP FAB1 NC 0321 
TDA21470 
TDA21470 
TP FAB1 NC 0321 
TP FAB1 CHANGE PN 0310 
TP FAB3-DVT NOPOP FROM SS BOM 20161215 
NOPOP 
NOPOP 
NOPOP 
NOPOP 
VDDQ GHJ VR(2 OF 3) 
PLACE ON TOP 
PLACE ON TOP 
SPOF 
WIWYNN CORPORATION 
SPOF 
ROOM = VDDQ_GHJ_PWR_VR 



BOM_SS=E15431-004 
BOM_SS=E15431-004 
BOM_SS=E15431-004 
BOM_SS=E15431-004 
BOM_SS=E15431-004 
BOM_SS=E15431-004 
BOM_SS=E15431-004 
BOM_SS=E15431-004 
BOM_SS=E15431-004 
BOM_SS=E15431-004 
BOM_SS=E15431-004 
BOM_SS=E15431-004 
BOM_SS=E15431-004 
BOM_SS=E15431-004 
BOM_SS=E15431-004 
BOM_SS=E15431-004 
BOM_SS=E15431-004 
BOM_SS=E15431-004 
BOM_SS=E15431-004 
BOM_SS=E15431-004 
BOM_SS=E15431-004 
BOM_SS=E15431-004 
BOM_SS=E15431-004 
BOM_SS=E15431-004 
BOM_SS=E15431-004 
BOM_SS=E15431-004 
BOM_SS=E15431-004 
BOM_SS=E15431-004 
BOM_SS=E15431-004 
BOM_SS=E15431-004 BOM_SS=E15431-004 
BOM_SS=E15431-004 
20% 
100UF 
602433-112 
C8P32 
602433-112 
22.0UF 
20% 
E15431-004 
0603V 
E15431-004 
X6S 
C2D44 1
X6S 2E15431-004 
VR_FET_SW_P12V_STBY_PVDDQ_GHJ 
C22W4 
2 602433-106 602433-106 602433-106 
4V 
20% 
2
602433-106 
X5R 
0603V 
20% 
602433-106 2 X5R 
20% 
47UF 1
0603V 
602433-106 
C2G11 
47UF 
4V 
20% 
X5R 
602433-106 
0603V 
1 47UF 
C8U2 
602433-106 
20% 
47UF 
C2G1 
C22W2 
0603V 
C2G9 
47UF 
602433-106 
0603V 
0402 
G21796-017 E15431-004 2 E15431-004 
L1F1 
IND-100NH-35-GP 
X5R 
1
120.0 
1% G22026-003 
0603 
470UF 
C9U5 
20% 
2.5V 
ALUM 
3018 
1
2
1
2
2.5V 
20% 
ALUM 
3018 
699013-049 
C9U9 
1
2
470UF 
20% 20% 
2.5V 
2
1
3018 
699013-049 
ALUM 
2.5V 
3018 
ALUM 
470UF 
C9T5 
1
2
100UF 
0805 
1
2
4V 
100UF 
0805 2
1
0603V 
SH7U1 
0805 
1
602433-112 
C7T1 
20% 
0805 
2
C8U11 1
2
47UF 
C2G15 
VSENSE_PVDDQ_GHJ_N 
VSENSE_PVDDQ_GHJ_P 
2
1
100.0 
R7U2 
1/16W 
1% 
1
EMPTY 2
C8U4 1
20% 
X5R 
2
47UF 
4V 602433-106 
20% 
X5R 
2
1 47UF 
4V 
C8T10 
20% 
X5R 
602433-106 
0603V 
4V 
47UF 1
2
C8T9 C8U5 
20% 
X5R 
2
1
0603V 
47UF 
602433-106 
4V 4V 
602433-106 
47UF 
0603V 
1
2 X5R 
20% 
C8T8 
20% 
1
X5R 2
0603V 
47UF 
602433-106 
4V 
C8T7 
4V 
602433-106 
47UF 
0603V 
1
2 X5R 
20% 
C8T6 C8U6 
20% 
X5R 
2
1
0603V 
47UF 
602433-106 
4V 
47UF 
4V 602433-106 
0603V 
1
2 X5R 
20% 
C8T5 
47UF 
20% 
X5R 
2
1
0603V 
602433-106 
4V 
C7T5 
47UF 
4V 602433-106 
0603V 
1
2 X5R 
20% 
C7T4 
4V 
47UF 
602433-106 
C8U3 
20% 
X5R 
2
1
0603V 
4V 
47UF 
X5R 
602433-106 
0603V 
1
2
20% 
C7U1 
4V 
602433-106 
X5R 
0603V 
C7U2 
20% 
2
1 47UF 
2
0603V 
602433-106 2
1 C8U7 
602433-106 
0603V 
X5R 
20% 
20% 
X5R 
2
1
4V 
2 602433-106 
0603V 
X5R 
602433-106 
0603V 
C2G14 
20% 
X5R 
2
1 47UF 
4V 
X5R 
2 602433-106 
0603V 
1
20% 
4V 4V 
47UF 1
2
20% 
C3G2 
0603V 
602433-106 
X5R 
C3G1 
20% 
2
1 47UF 
4V 
C2G6 
47UF 
4V 602433-106 
0603V 
X5R 
20% 
2
1
X5R 2
0603V 
C2G5 1 47UF 
4V 602433-106 
0603V 
2
C2G4 
20% 
X5R 
1 47UF 
4V 602433-106 
0603V 
X5R 
C2G3 
20% 
2
1 47UF 
4V 
47UF 
20% 
X5R 
602433-106 
0603V 
C2G2 
2
1
4V 
602433-106 
0603V 
20% 
X5R 
2
4V 
602433-106 2
1
0603V 
4V 
47UF 1
2 X5R 
20% 
C2G12 
2
1
4V 
47UF 1
2 X5R 
20% 
C2G10 
20% 
4V 
E15431-004 
22.0UF 1
2 X6S 
C2D42 
2
11
2 X6S 
4V 
20% 
X6S X6S 
20% 
4V 
X6S 
C2D45 
22.0UF 1
X6S 
4V 
20% 2
SH7U2 
1
2
N_A 
1
1 C8T11 
2 X5R 
4V 
20% 
0603V 
4V 
C8U9 
2
C8T1 1 47UF 
20% 
4V 
X5R 
0603V 
X5R 
4V 
20% 
47UF 
C2F1 
2
1
0603V 
2
4V 
X5R 
4V 
47UF 
2
C8T2 
4V 
47UF 
1
20% 
X5R 
2
1
2
1 C8T4 
20% 
4V 
47UF 
X5R 
C2G16 1
2
4V 
0805 
1
2 0805 
C2D43 
2
C8P31 
20% 
4V 
22.0UF 
4V 
0805 
602433-112 
4V 
20% 
2
1
C8P34 1
2
20% 
4V 
100UF 
602433-112 
0805 
4V 
4V 
C8U12 1
2
20% 
4V 
100UF 
602433-112 
0805 0805 
4V 
20% 
2
1100UF 
4V 
2
1 C8U8 
20% 
0805 
602433-112 
1/10W 
CHIP 
699013-049 
C2D41 
22.0UF 
4V 
20% 
0603V 
47UF 
4V 
47UF 
4V 
X5R 
20% 
602433-106 
0603V 
0603V 0603V 
E15431-004 
C2D47 
22.0UF 
4V 
20% 
20% 
100UF 
1
C3D25 
22.0UF 
602433-106 
C2D46 
22.0UF 
699013-049 
0603V 470UF 
C9U2 
N_A 
0603V 0603V 
1
C3G6 
X5R 
602433-106 
0603V 
602433-106 
20% 
4V 
0603V 
E15431-004 
C22W3 C1G2 C22W1 
602433-112 
C8U1 
0805 
602433-112 
0805 
602433-112 
20% 20% 
4V 
100UF 
100UF 
602433-112 
100UF 
1
20% 
47UF 
C2G13 C3G5 
47UF 
4V 
C8P30 
100UF 
4V 
20% 
602433-112 
0805 C2G7 
C8P33 C7P20 
20% 
602433-112 
0603V 100UF 
4V 
20% 20% 
4V 
100UF 
602433-106 
R1G20 
0603V 
20% 
1
100UF 
C8U13 
602433-106 
C2G8 
47UF 
602433-112 
1 C7U7 
602433-106 
0603V 
X5R 
4V 
47UF 
0603V 0603V 
TOP SIDE: 603 BOTTOM SIDE: 805 
TP FAB3-DVT CHANGE CAP C1G7, C1G12, C1G15 20161114 
TP FAB3-DVT CHANGE CAP IN SS BOM 20161220 
TP FAB3-DVT NOPOP FROM SS BOM 20161220 
TP FAB1 CHANGE ONE 47UF CPA TO TWO 22UF CAPS 0107 
TP FAB3-DVT NOPOP FROM SS BOM 20161220 
TP FAB1 CHANGE CAP 0311 
TP FAB3-DVT NOPOP FROM SS BOM 20161220 
TP FAB1 CHANGE CAP 0311 
TP FAB1 CHANGE CONNECTION 0318 
TP FAB1 CHANGE CAPACITY 0322 
TP FAB3-DVT NOPOP FROM SS BOM 20161220 
NEW_MATERIAL=X6S 
223 
223 
GROUP=PWR_MLCC_CAP 
NEW_MATERIAL=X6S 
GROUP=PWR_MLCC_CAP 
NEW_PN=078.1071T.0811 
NEW_MATERIAL=X6S 
GROUP=PWR_MLCC_CAP 
GROUP=PWR_MLCC_CAP 
BOM_SS=NOPOP 
NEW_PN=078.1071T.0811 
NEW_PN=078.1071T.0811 
NEW_MATERIAL=X6S BOM_SS=NOPOP 
GROUP=PWR_MLCC_CAP 
GROUP=PWR_MLCC_CAP 
GROUP=PWR_MLCC_CAP 
NEW_PN=078.1071T.0811 
BOM_SS=NOPOP 
BOM_SS=NOPOP 
BOM_SS=NOPOP BOM_SS=NOPOP 
NEW_PN=078.1071T.0811 
GROUP=PWR_MLCC_CAP GROUP=PWR_MLCC_CAP 
GROUP=PWR_MLCC_CAP 
GROUP=PWR_MLCC_CAP 
GROUP=PWR_MLCC_CAP 
GROUP=PWR_MLCC_CAP 
X6S 
0805 0805 
X6S 
0805 
22UF 
GROUP=PWR_MLCC_CAP 
IRMS=29A@DELTA_T<45C 
NEW_PN=078.1071T.0811 
GROUP=PWR_MLCC_CAP 
BOM_SS=NOPOP 
NEW_MATERIAL=X6S 
NEW_PN=078.1071T.0811 
GROUP=PWR_MLCC_CAP 
GROUP=PWR_MLCC_CAP 
GROUP=PWR_MLCC_CAP 
100NH 
ISAT=16A@25C 
DCR=0.16MOHM 
NEW_MATERIAL=X6S 
NEW_MATERIAL=X6S 
GROUP=PWR_BULK_CAP 
GROUP=PWR_MLCC_CAP 
GROUP=PWR_MLCC_CAP 
GROUP=PWR_MLCC_CAP 
GROUP=PWR_MLCC_CAP 
GROUP=PWR_MLCC_CAP 
GROUP=PWR_MLCC_CAP 
GROUP=PWR_MLCC_CAP 
GROUP=PWR_MLCC_CAP 
GROUP=PWR_MLCC_CAP 
GROUP=PWR_MLCC_CAP 
GROUP=PWR_MLCC_CAP 
GROUP=PWR_MLCC_CAP 
GROUP=PWR_MLCC_CAP GROUP=PWR_MLCC_CAP 
GROUP=PWR_MLCC_CAP 
GROUP=PWR_MLCC_CAP 
GROUP=PWR_MLCC_CAP 
GROUP=PWR_MLCC_CAP 
GROUP=PWR_MLCC_CAP 
GROUP=PWR_MLCC_CAP 
GROUP=PWR_MLCC_CAP 
GROUP=PWR_MLCC_CAP 
GROUP=PWR_MLCC_CAP 
GROUP=PWR_MLCC_CAP 
GROUP=PWR_MLCC_CAP 
GROUP=PWR_MLCC_CAP GROUP=PWR_MLCC_CAP GROUP=PWR_MLCC_ CAP 
GROUP=PWR_MLCC_CAP GROUP=PWR_MLCC_CAP 
NEW_MATERIAL=X6S 
GROUP=PWR_MLCC_CAP
NEW_MATERIAL=X6S 
GROUP=PWR_MLCC_CAP 
NEW_MATERIAL=X6S 
GROUP=PWR_BULK_CAP 
GROUP=PWR_BULK_CAP 
GROUP=PWR_BULK_CAP 
22UF 22UF 22UF 
16V 
20% 
X6S 
20% 
0805 
20% 
22UF 
GROUP=PWR_MLCC_CAP 
X6S 
20% 
16V 
X6S 
NEW_PN=078.1071T.0811 
GROUP=PWR_MLCC_CAP 
NEW_PN=078.1071T.0811
16V 
20% 
0805 
16V 16V 
GROUP=PWR_MLCC_CAP 
NEW_PN=078.1071T.0811 
NEW_PN=078.1071T.0811 
NEW_PN=078.1071T.0811 
GROUP=PWR_MLCC_CAP BOM_SS=NOPOP 
BOM_SS=NOPOP 
NEW_PN=078.1071T.0811 
NEW_MATERIAL=X6S 
BOM_SS=NOPOP 
GROUP=PWR_MLCC_CAP 
BOM_SS=NOPOP BOM_SS=NOPOP 
BOM_SS=NOPOP 
BOM_SS=NOPOP 
BOM_SS=NOPOP 
GROUP=PWR_MLCC_CAP 
BOM_SS=NOPOP 
NEW_MATERIAL=X6S 
BOM_SS=NOPOP 
GROUP=PWR_MLCC_CAP 
BOM_SS=NOPOP BOM_SS=NOPOP 
NEW_MATERIAL=X6S 
GROUP=PWR_MLCC_CAP 
NEW_MATERIAL=X6S 
NEW_PN=078.1071T.0811 
GROUP=PWR_MLCC_CAP 
BOM_SS=NOPOP 
GROUP=PWR_MLCC_CAP 
GROUP=PWR_MLCC_CAP 
BOM_SS=078.1061T.M001 
BOM_SS=NOPOP 
GROUP=PWR_MLCC_CAP BOM_SS=NOPOP 
GROUP=PWR_MLCC_CAP 
SC22U16V5MX-4-GP 
C1G12 
SC22U16V5MX-4-GP 
SC22U16V5MX-4-GP 
C1G15 
SC22U16V5MX-4-GP 
SC22U16V5MX-4-GP 
C1G7 
NEW_PN=077.C3361.0001 
NEW_VALUE=33UF 
NEW_SIZE=B2 
NEW_PN=077.C3361.0001 
NEW_SIZE=B2 
NEW_VALUE=33UF 
NEW_SIZE=B2 
NEW_VALUE=33UF 
NEW_PN=077.C3361.0001 
1
2 2
11
2
PUT TOGETHER 
5MIL SPACING 
PUT TOGETHER PUT TOGETHER 
10MIL WIDTH 
ROUT AS DIFF PAIR 
PUT TOGETHER 
1 2
DO NOT SCALE DRAWING SHEET 
B
AA
B
B
SIZE 
SCALE: 
234
1234
DEPARTMENT CODE 
1
DOCUMENT NUMBER REV 
PVDDQ_GHJ 
PVDDQ_GHJ 
PVDDQ_GHJ 
IN 
IN 
PVDDQ_GHJ 
PVDDQ_GHJ 
PVDDQ_GHJ 
PVDDQ_GHJ 
PVDDQ_GHJ 
PVDDQ_GHJ 
PVDDQ_GHJ 
PVDDQ_GHJ 
P12V_STBY 
PVDDQ_GHJ 
1 2
1
2 1
1
1
2
2
2
1
2
1
1
2
2
PVDDQ_ABC VOLTAGE SENSE 
INPUT FILTER 
Wed Feb 08 16:35:30 2017 
225 OF 270 225 OF 270 
TP FAB1 CHANGE CAP 0314 
PLACE NEAR VR OUTPUT INDUCTORS 
CAD NOTE: 
PVDDQ CPU CAVITY CAPS 
TP FAB1 CHANGE CAP OF SINGLE SIDE 0504 TP FAB1 CHANGE CAP 0322 
TP FAB1 CHANGE L1F1 PN 0122 
TP FAB1 CHANGE CAP 0322 
ROOM=VDDQ_GHJ_CPU1 
CAPS TO BE PLACED BETWEEN DIMMS 
VDDQ GHJ DECAP (3 OF 3) 
ROOM=VDDQ_GHJ_PWR_VR 
WIWYNN CORPORATION 



1/16W 
CHIP 
10% 
SVID_DIO1_CPU1_R 
1/16W 
R9M5 
8
31 
SC22P50V2JN-4GP 
ISENSE_PVDDQ_KLM_PH1_IMON 
VR_PVDDQ_KLM_AIINSEN 
CHIP 
0402 
1.0K RF22 
1
EU1B1 
VR_PVDDQ_KLM_PWM1 
VR_PVDDQ_KLM_PWM2 
SMB_VR_STBY_LVC3_SDA 
SMB_VR_STBY_LVC3_SCL 
SVID_VDIO_PVDDQ_KLM 
VR_PVDDQ_KLM_VINSEN 
VR_PVDDQ_KLM_VD12 
PU_VR_PVDDQ_KLM_FAULT1 
NC_PVDDQ_KLM_GP1 
28 
34 
IC 
11 
35 
37 
26 
36 
19 
29 
27 
2
5
4
3
1
40 
13 
14 
6
7
25 
23 
21 
15 
39 
12 
17 
9
33 
16 
41 
24 
22 
30 
32 
10 
20 
H89186-001 
ISENSE_PVDDQ_KLM_PH2_IMON 
A_TSENSE_PVDDQ_KLM 
VR_PVDDQ_KLM_AIREF1 
VR_PVDDQ_KLM_AVSP 
A36096-030 
10% 
G21796-311 
0402 
R1B13 
CHIP 
1/16W 
1.0% 
1% 
1/16W 
EMPTY 2
G21796-017 
0402 
IRQ_PVDDQ_KLM_VRHOT_LVT3_N 
G21497-005 
5% EMPTY G21497-005 
SVID_ALERT1_CPU1_R_N 
G21796-074 1/16W 
2
1/16W EMPTY 
5% 0.0 2
R12W35 0.0 
1
R1B10 
0402LF 
PWRGD_PVDDQ_KLM 
1.0% 
R1B5 
22.1 
33.2 
1
0402 
2
R12W34 
R1B15 
1 3.16K 
1/16W 
2 CHIP 
1% 
0402 
G21796-043 
CHIP 
1/16W 
1000PF 
G21796-317 
0402 
16K 
1.0% 
R1B12 
VSENSE_PVDDQ_KLM_N 
VR_PVDDQ_KLM_VD12 
VSENSE_PVDDQ_KLM_P 
FM_PVDDQ_KLM_EN 
VR_PVDDQ_KLM_VDD 
SVID_CLK1_CPU1_R 
EMPTY 
1% 
G21796-047 
2
1 49.9 
R9M6 
0402 
R1B4 
CHIP 0402 
1% 
0.0 R12W36 
1
5% 
G21796-026 
0402 
R1B2 
2 CHIP 
1% 
1
R1B1 
1.00K 
1/16W 
CHIP 
G21796-026 
0402 
2
1
1% 
1/16W 
0.0 
2
5% 
1
R1B11 
G21497-005 
0402 CHIP 
21 0402 
D97712-004 
X6S 
1.0UF 1
2
6.3V 
C1B3 
0402V 
10% 
16V 
0402V 
2 X7R 
0.1UF 1 C1B2 
A36096-030 
G21497-005 
0.0 
2
0402 5% 
1/16W 
50V 
C1B4 1
10% 
2 X7R 
A36096-046 
10% 
6.3V 
X6S 
1.0UF 
C1B6 
0402V 
D97712-004 
G21497-005 
0.0 
5% 
R9M3 
2
1
0402 
G21796-010 
1% 
2
0402 
100.0K 1
X7R 
16V 
1
0402V 
C1B5 
2
0.1UF 
220PF 
C1B11 
A36096-050 
0402LF 
10% 
X7R 50V 
2
1
0.0 
1/16W CHIP 
R9M9 
0402 
1/16W 
10.0 
1
1% 
2
CHIP 
0402 
G21796-066 
R1B16 
X7R 50V 
C1B12 
A36096-050 
0402LF 2
10% 220PF 
1
CF21 
G21497-005 
21
1/16W 
1 0402 
0402 
1.0K 
1% 
RF21 
G85996-004 
R1B8 
G21796-009 
150.0 
0.1% 
1/16W 
0.1% CHIP 
1/16W 
EMPTY 
1/16W 1/16W 
CHIP 
0402 G85996-004 
CF22 
SC22P50V2JN-4GP 
1/16W 2 CHIP SVID_CLK_PVDDQ_KLM 
VR_PVDDQ_KLM_AIREF2 
5% 
G21497-005 
VR_PVDDQ_KLM_VREN 
38 
18 NC_PVDDQ_KLM_GP0 
SVID_ALERT_PVDDQ_KLM 
IRQ_PVDDQ_KLM_VRHOT_LVT3_R_N 
PWRGD_PVDDQ_KLM_R 
1/16W 
CHIP G21796-250 
0402 
1 100.0 
R9M7 
1/16W 
1.00K 2.26K 
TP FAB3 NOPOP R1B5 0919 
TP FAB1 CO-LAY WITH FAIRCHILD PARTS 1203 
TP FAB4 NOPOP RF22 AND CF22 FOR SS BOM 20170124 
TP FAB1 CHANGE R1B12 RES AND NOPOP R1B15 0408 
TP FAB3 POP R12W34 0919 
TP FAB1 ADD RES 0303 
TP FAB1 CHANGE R1B15 RES 0815 
TP FAB1 CHANGE R1B12 RES 0523 
TP FAB3 POP R1B13 1014 
TP FAB1 NC 0321 
TP FAB4 CHANGE RF21 TO 909OHM FOR VR FAILCHILD, SINGLE SIDE BOM 20170123 
55 193 223 
227 
197 
227 
227 
138 
159 193 194 201 206 
211 213 215 218 223 
235 
138 159 211 213 235 193
194 201 206 215 218
223 
197 
226 
227 
227 
227 
94 119 145 
193 223 55 
197 
228 
226 
228 
191 
55 193 223 
227 
230 
GROUP=POWER_FAIR 
BOM_SS=NOPOP 
NPO 
GROUP=POWER_FAIR 
NOPOP 
22PF 
NPO 
50V 5% 
0402 5% 50V 
BOM_SS=NOPOP 
0402 
22PF 
GROUP=POWER_FAIR 
FAIR_SS=064.9090D.M001 
GROUP=POWER_FAIR 
VR_PVDDQ_KLM_XADDR2 
VR_PVDDQ_KLM_XADDR1 
DESIGN NOTE: 
DESIGN NOTE: 
IOUT DI/DT = 15A/US/18.09A/US FOR DS/SS 
SW FREQ = 833.33KHZ 
VOUT = 1.2V 
DC TOL = +/-0.5% 
IOUT TDC = 65.7A/25.86A FOR DS/SS 
IOUT PK = 73A/29.38A FOR DS/SS 
IOUT STEP = 45A/17.96A FOR DS/SS 
RIPPLE GUIDELINE = +/- 0.5% 
AC & RIPPLE TOL = +/2.8% 
21 1
1
2
1 1
2
2 2
DO NOT SCALE DRAWING 
RF21&RF22 
FAIRCHILD:POP 
INFINEON:NOPOP 
CF21&CF22 
SHEET 
B
AA
B
B
SIZE 
SCALE: 
234
1234
DEPARTMENT CODE 
1
DOCUMENT NUMBER REV 
IN 
IN 
IN 
OUT 
OUT 
OUT 
IN 
BI 
BI 
OUT 
OUT 
OUT 
IN 
IN 
PVCCIO_CPU1 
P3V3_STBY 
OUT 
IN 
IN 
P3V3_STBY 
IN 
PVCCIO_CPU1 
IN 
IN 
IN 
IN 
226 OF 270 
Wed Feb 08 16:35:31 2017 
SVID ADDRESS 
PXM1310C 
MP2 
THPAD 
BPWM1 
APWM1 APWM2 
APWM3 
SDA SCL 
VCLK 
VDIO 
RESET_N 
XADDR1 
AISEN3 
AIREF3 
XADDR2 
AISEN2 
AIREF2 
ATSEN 
AISEN1 
AIREF1 
VDD 
BTSEN 
BISEN1 BIREF1 DNC<0> DNC<1> 
VRHOT_N 
PINALRT_N 
VALRT_N 
AVSEN 
AVREF 
BVSEN 
BVREF 
VINSEN 
VD12 
GND 
IINSEN 
AVRRDY 
AVREN 
MP0 MP1 
TP FAB1 NC 0321 
TP FAB1 DEL CAP 0218 
TP FAB1 NC 0321 
TP FAB1 NC 0321 
TP FAB1 DEL RES 0314 
TP FAB1 DELETE RES 0203 
TP FAB1 NC 0321 TP FAB1 NC 0321 
TP FAB1 NC 0321 
TP FAB1 NOPOP RES 0316 
TP FAB1 NC 0321 
PVDDQ_KLM: 0X02(BUS #2) 
SMBUS ADDRESS: 0XA4 
VDDQ KLM_VR (1 OF 3) 
WIWYNN CORPORATION ROOM=VDDQ_KLM_PWR_VR 



TP FAB3-DVT NOPOP L1A1 IND FOR SS BOM 20161215 
TP FAB3 CHANGE L1A1 0823 
TP FAB1 CHANGE L1A1 PN 0122 
CHIP 
1/16W 
CHIP 
1/16W 
TP FAB1 CO-LAY WITH TI PARTS 11/16 
4V 
F S
F S
C1A9 
1.0UF 
D97712-011 
C1A13 
C1A11 
10% 
X6S 
A36096-030 
0402V 0402 0402 
X7R 
0.1UF 
C1A20 
16V 
1
1.0UF 
C1A6 C9L13 C9L14 
D97712-011 
34 
TP_PVDDQ_KLM_PH2_GL_1 
VR_PVDDQ_KLM_PH2_RC 
VR_PVDDQ_KLM_PH2_BOOT_R 
10% 
16V 
0.22UF 10UF 
16V 
10% 
X6S 
2 0402 
0603 
G21796-187 
ISENSE_PVDDQ_KLM_PH2_IMON VR_PVDDQ_KLM_PH2_VCIN 
39 
TP_PVDDQ_KLM_PH2_GL_0 
A36096-155 
6
C95333-002 
A36096-046 
0402LF 
R1A2 
A36096-046 
1R3F-GP 
VR_PVDDQ_KLM_PH2_OCSET 
VR_PVDDQ_KLM_PH2_SW 
A_TSENSE_PVDDQ_KLM 
VR_PVDDQ_KLM_PH2_PHASE X7R 
10% 
0402 
2
16V 
0.220UF 
1
A36096-104 
2
0805 
X6S 
1
10UF 
1
2 X7R 
1/10W 
0
CHIP 5.0% 
CT12 
10% 
16V 
0.1UF 
X7R 
A36096-030 
0402V 
X7R 
1000PF 
50V 
10% CT11 
L1A1 
0805LF 
20% 
2
1 C1A1 
22UF 
X6S 
CT10 
X7R 
10% 
50V 
1000PF 
0402LF 
1/16W 
EMPTY 
1
1% 
2
68.1K 
0402 
1
C95333-007 
0805 
2
C9L5 
X6S 
10% 
16V 
1
10% 
2
1
2
4
EU1A1 
1
37 
3
40 
41 
IC 
7
25 
38 
35 
10 
2
32 
5
33 
36 
30 
31 
H73688-001 
RT7 
VR_PVDDQ_KLM_PH1_RC 
L1A2 
1R3F-GP 
H73688-001 
C1B21 1
2 X7R 
10% 
0.22UF 
0402 
VR_PVDDQ_KLM_PH1_VCIN 
16V 
10 
5
X7R 
TP_PVDDQ_KLM_PH1_GL_0 
RT5 
1/10W 
0.1UF 
CT7 
39 
16V 0402 
0402V 
31 
34 
25 
41 
40 
2
32 
37 
3
30 
35 
4
1
7
33 
36 
6
1/16W 
68.1K 1
R1A3 
1% 
10% 
A36096-030 
0402LF 
A36096-046 
X7R 
10% 
50V 
CT9 
10% 
0 5.0% 
X7R 2
1
C95333-007 
X6S 
10% 
2
0805 
C95333-007 
X6S 2
10UF 
10% 
1
16V 
C9L6 
C95333-007 
10UF 
0805 
X6S 
1
2
1.0UF 1
2 X6S 
0402 
10% 
D97712-011 
C1A19 
10% 
C1B20 1
X6S 
1.0UF 
16V 2
16V 
2
1
VR_PVDDQ_KLM_PH1_SW 
ISENSE_PVDDQ_KLM_PH1_IMON 
VR_PVDDQ_KLM_PH1_OCSET 
A_TSENSE_PVDDQ_KLM 
10% 
RT6 
C1A2 
2
0402LF 
X7R 
1000PF 50V 
D97712-011 
0402 
TP_PVDDQ_KLM_PH1_GL_1 
VR_PVDDQ_KLM_PH1_BOOT_R 
38 
IC 
EU1A2 
VR_PVDDQ_KLM_AIREF1 
0805 
VR_FET_SW_P12V_STBY_PVDDQ_KLM 
1 10UF 
16V 
C9L11 C9L10 
16V 16V 
0402 
VR_PVDDQ_KLM_PH1_BOOT 
CHIP 
G22178-002 
0603 
G21796-187 
A36096-046 
EMPTY 
CT8 1000PF 
C95333-002 
0805LF 
1 C1A12 
X6S 2
20% 
22UF 
A36096-155 
VR_PVDDQ_KLM_AIREF2 
1
5% 0402 0.0 
G21497-005 
R9L9 
2
C1A10 
0.1UF 
10% 
X7R 
A36096-030 
0402V 
VR_PVDDQ_KLM_PWM1 
C1A18 
0.220UF 
16V 
10% 
A36096-104 
0402 
1
5% 
2
R9L4 
VR_PVDDQ_KLM_PH1_PHASE 
0.0 
G21497-005 
2C95333-007 
VR_PVDDQ_KLM_PWM2 
G22178-002 RT8 VR_PVDDQ_KLM_PH2_BOOT C1A8 
0805 
1
10UF 
16V 
10% 
16V 
10% 
X6S 
C95333-007 
16V 
VR_FET_SW_P12V_STBY_PVDDQ_KLM 
TP FAB4 POP CAP ON SS BOM 20170207 
TP FAB1 ADD NET NAME 12/04 
TP FAB1 CHANGE RES TO 1 OHM 0603 0107 
TP FAB3-DVT CHANGE L1A2 IND FOR SS BOM 20161215 
TP FAB1 CHANGE RES TO 1 OHM 0603 0107 
226 
227 226 
226 
227 226 
226 
226 
226 
226 
DS_ISAT=134A@25C 
BOM_SS=NOPOP BOM_SS=NOPOP 
10% BOM_SS=NOPOP 
BOM_SS=NOPOP 
BOM_SS=NOPOP 
GROUP=PWR_MLCC_CAP 
BOM_SS=NOPOP 
NOPOP 
IRMS=66A@DELTA_T<40C 
1/10W 
BOM_SS=NOPOP 
DCR=0.17MOHM 
SS_VALUE=120NH 
BOM_SS=NOPOP 
BOM_SS=NOPOP 
BOM_DS=068.9002N.1021 
BOM_SS=NOPOP 
1UF 
0402 
10V 
BOM_SS=NOPOP 
DS_VALUE=90NH 
DCR=0.17MOHM 
BOM_SS=NOPOP 
BOM_SS=NOPOP 
NOPOP 
1 OHM 
1% 
0603 
SS_ISAT=94A@25C 
BOM_SS=068.1202N.M001 
DS_ISAT=134A@25C 
DS_VALUE=90NH 
BOM_DS=068.9002N.1021 
IRMS=66A@DELTA_T<40C 
NOPOP 
1 OHM 
0603 
10% 
10V 
0402 
1UF 
GROUP=PWR_MLCC_CAP 
1% 
1/10W 
BOM_SS=NOPOP 
TP FAB1 CO-LAY WITH TI PARTS 11/16 
4V 
SC1U10V2KX-4-GP 
SC1U10V2KX-4-GP 
TP FAB3 CHANGE L1A2 0823 
TP FAB1 ADD NET NAME 12/04 
TP FAB1 CHANGE L1A2 PN 0122 
1 2
1
2
1
2
21
2
1
1 2
2
1
2
2
1
2
1
1
NOPOP 
DO NOT SCALE DRAWING 
TP FAB1 CO-LAY WITH TI PARTS 11/16 
TP FAB1 CO-LAY WITH TI PARTS 11/16 
TP FAB1 CO-LAYOUT WITH TI PARTS 11/16 
TP FAB1 CO-LAY WITH TI PARTS 11/16 
SHEET 
B
AA
B
B
SIZE 
SCALE: 
234
1234
DEPARTMENT CODE 
1
DOCUMENT NUMBER REV 
P5V_STBY 
IN 
PVDDQ_KLM 
OUT 
OUT 
OUT 
OUT 
OUT 
IN 
OUT 
P5V_STBY 
PVDDQ_KLM 
1 2
2 1
1
1 2
2
Wed Feb 08 16:35:31 2017 
227 OF 270 
1
1
GL<1> 
GL<0> 
PGND<1> 
PGND<0> 
PGND<2> LGND 
VOS 
EN 
VDRV 
VCC 
VIN<0> VIN<1> 
PHASE 
REFIN 
BOOST 
PWM 
SW 
NC 
IOUT 
OCSET 
TOUT_FLT 
GL<1> 
GL<0> 
PGND<1> 
PGND<0> 
PGND<2> LGND 
VOS 
EN 
VDRV 
VCC 
VIN<0> VIN<1> 
PHASE 
REFIN 
BOOST 
PWM 
SW 
NC 
IOUT 
OCSET 
TOUT_FLT 
TP FAB1 CHANGE PN 0310 
TP FAB3-DVT NOPOP FROM SS BOM 20161215 
TDA21470 
TP FAB1 DEL NET 0309 
TP FAB1 DEL NET 0309 
TDA21470 
TP FAB1 CHANGE PN 0310 
NOPOP 
NOPOP 
NOPOP 
NOPOP 
VDDQ KLM VR (2 OF 3) 
PLACE ON TOP 
PLACE ON TOP 
SPOF 
WIWYNN CORPORATION 
SPOF 
ROOM = VDDQ_KLM_PWR_VR 



BOM_SS=E15431-004 
BOM_SS=E15431-004 
BOM_SS=E15431-004 
BOM_SS=E15431-004 
BOM_SS=E15431-004 
BOM_SS=E15431-004 
BOM_SS=E15431-004 
BOM_SS=E15431-004 
BOM_SS=E15431-004 
BOM_SS=E15431-004 
BOM_SS=E15431-004 
BOM_SS=E15431-004 
BOM_SS=E15431-004 
BOM_SS=E15431-004 
BOM_SS=E15431-004 
BOM_SS=E15431-004 
BOM_SS=E15431-004 BOM_SS=E15431-004 
BOM_SS=E15431-004 
BOM_SS=E15431-004 
BOM_SS=E15431-004 
BOM_SS=E15431-004 
BOM_SS=E15431-004 
BOM_SS=E15431-004 
BOM_SS=E15431-004 BOM_SS=E15431-004 
BOM_SS=E15431-004 
BOM_SS=E15431-004 
BOM_SS=E15431-004 
BOM_SS=E15431-004 
BOM_SS=E15431-004 
BOM_SS=E15431-004 
C2A5 
100UF 
20% 
4V 
602433-112 
0805 
0603V 
E15431-004 
22.0UF 
C2D3 
602433-112 
0805 
22.0UF 
X6S 
E15431-004 
0603V 
C8M8 
47UF 
602433-106 
0603V 
602433-106 602433-106 2 X5R 
47UF 
C8M2 
C7L1 
100UF 
4V 
602433-112 
C8M10 
47UF 
602433-106 
1
4V 
X5R 
602433-106 
0603V 
4V 
0805 
602433-112 
0805 
602433-112 
20% 
4V 
100UF 
20% 
4V 
47UF 1C8L12 
SH7L2 
0805 
602433-112 
4V 
C2A8 
100UF 
11 C2A16 
100UF 
4V 
20% 
2
0603V 
22.0UF 
20% 
602433-112 
22.0UF 
E15431-004 
0603V 
X5R 2
100.0 
602433-106 
0603V 
47UF 
X5R 
20% 
4V 
20% 
47UF 
X5R X5R 
20% 
100UF 
4V 
20% 
0805 
4V 
100UF 
C8M11 
602433-112 
1
2602433-112 
20% 
4V 
602433-112 22
1
20% 
602433-106 
0603V 
C8L5 1 47UF 
4V 
20% 20% 20% 20% 20% 
47UF 
C2A4 C8M4 
47UF 
4V 
X5R 
602433-106 2 602433-106 2
20% 
4V 
1 C8M5 
20% 
602433-106 
0603V 
47UF 
C8M3 
0603V 
X5R 
20% 
20% 1
20% 
1
20% 
4V 
100UF 
0805 
100UF 
C7P1 
20% 
2
1
100UF 
4V 
20% 
2
1 C7P2 
0805 
X6S 
20% 
22.0UF 
C2D2 
0805 
4V 
100UF 
C8P3 
1
2
20% 
4V 
100UF 
602433-112 
0805 
C8P2 
22.0UF 
C2B2 1
4V 
X5R 
602433-106 
VR_FET_SW_P12V_STBY_PVDDQ_KLM 
VSENSE_PVDDQ_KLM_N 
VSENSE_PVDDQ_KLM_P 
R7L2 
EMPTY 
0402 
1/16W 
G21796-017 
1% 
1
2
2
1
4V 
20% 
2
0603V 
47UF 
602433-106 
4V 
C8L10 
602433-106 
47UF 
0603V 
1
2
20% 
0603V 
C2A3 1 47UF 
602433-106 
4V 
C7M1 
602433-106 
4V 
47UF 1
2
20% 
0603V 
C7M2 
47UF 
4V 
20% 
1
0603V 
4V 
0603V 
1
2602433-106 
X5R 2
1
0603V 
47UF 
C8M6 1C8L9 
X5R 2
1 47UF 
4V 
602433-106 
47UF 
0603V 
1
2 X5R X5R 2
1
0603V 
4V 
C8L7 
47UF 
0603V 
1
2 X5R 
0603V 
4V 
602433-106 
X5R 2602433-106 
0603V 
2 X5R 
4V 
47UF 
20% 
C8M1 
X5R 2
1
0603V 
602433-106 
602433-106 
C2A2 
4V 
47UF 1
2
4V 
C2A1 
0603V 
602433-106 
20% 
47UF 
X5R 
2
147UF 
4V 
20% 
1
2 X5R 
0603V 
602433-106 
0603V 
4V 
47UF 
20% 
C2A13 
602433-106 
1
2 X5R 
602433-106 
20% 
47UF 
4V 
C2A11 
X5R 2
1
0603V 
X5R 
602433-106 
20% 
47UF 
4V 
C2A10 
2
1
0603V 
X5R 
C2A9 
20% 
2
1
0603V 
47UF 
602433-106 
4V 
602433-106 
X5R 
20% 
4V 
C3A2 
2
1
0603V 
47UF 
602433-106 
20% 
4V 
C3A1 
X5R 2
1 47UF 
0603V 
C2A7 
20% 
4V 
X5R 
2
1 47UF 
602433-106 
0603V 
C2A6 
47UF 
602433-106 
0603V 
20% 
4V 
X5R 
2
1C2A14 
47UF 
20% 
X5R 
602433-106 
0603V 
1
4V 
2
4V 
20% 
47UF 2 X5R 
0603V 
602433-106 
C3A5 
47UF 
4V 
1
2
C3A6 
4V 
20% 
1
X5R 
4V 
C2D6 
E15431-004 
1
X6S 2
20% 
C2D5 1
E15431-004 
X6S 
0603V 
20% 
4V 
2E15431-004 
22.0UF 
4V 
X6S 
C2D7 1
2
4V 
E15431-004 
0603V 
4V 
C2D1 1
2
20% 
4V 
X6S 
4V 
X6S 
20% 
0603V 
E15431-004 
22.0UF 
C3D1 1
X6S 
20% 
2
2
SH7L1 
N_A 
1
2
N_A 
1
20% 
4V 
X5R 
1
2
0603V 
C8M9 147UF 
4V 2
0603V 
1C7M5 
20% 
4V 
2
0603V 
4V 
X5R 
47UF 
20% 
1
2
2
1
2
20% 
4V 
0603V 
1
2
A31228-047 
C1B10 
2626 
OSCON 
270UF 
16V 
20% 
2
1
IND-100NH-35-GP 
L1B1 
1
2
0805 2
1 C8P1 
C8P4 
100UF 
4V 
20% 
C2A12 
C2B1 
0603V 
602433-106 
47UF 
2
20% 
602433-112 
0805 
C8L2 1
0805 
20% 
4V 
100UF 
C8L11 
2
1C8L1 
2 2 602433-112 
2 2
1 1
2
1 1
2 2
1
C9L9 
470UF 
20% 
2.5V 
ALUM 
699013-049 
3018 
C9L12 
470UF 
20% 
699013-049 
3018 
ALUM 
C9L4 
699013-049 
3018 
ALUM 
699013-049 
3018 
ALUM 
20% 
470UF 
C9L2 
470UF 
20% 
2.5V 2.5V 2.5V 
0603 
G22026-003 
CHIP 
1/10W 
1% 
120.0 
R1A1 
0603V 
C8M7 
C2D4 
0603V 
602433-106 
X5R 2602433-106 
0603V 
602433-106 
4V 
602433-106 
47UF 
C8L6 1
2 X5R 
20% 
1 C2A15 1
2
47UF 
4V 
C7L5 
X5R 
20% 
47UF 
X5R X5R X5R X5R X5R 
20% 20% 20% 
4V 
20% 
4V 
C8L8 
47UF 
C7L4 
602433-106 602433-106 
0603V 0603V 
X5R 
0805 
602433-112 
0603V 
602433-106 
20% 
BOTTOM SIDE: 805 TOP SIDE: 603 
TP FAB3-DVT NOPOP FROM SS BOM 20161220 
TP FAB3-DVT CHANGE CAP IN SS BOM 20161220 
TP FAB1 CHANGE CAP 0311 
TP FAB3-DVT NOPOP FROM SS BOM 20161220 
TP FAB1 CHANGE CAP 0311 
TP FAB3-DVT NOPOP FROM SS BOM 20161220 
TP FAB1 CHANGE CAPACITY 0322 
TP FAB3-DVT NOPOP FROM SS BOM 20161220 
TP FAB1 CHANGE CONNECTION 0318 
NEW_PN=078.1071T.0811 
226 
226 
NEW_PN=078.1071T.0811 
NEW_PN=078.1071T.0811 
GROUP=PWR_MLCC_CAP 
GROUP=PWR_MLCC_CAP 
NEW_PN=078.1071T.0811 
NEW_MATERIAL=X6S 
BOM_SS=NOPOP 
GROUP=PWR_MLCC_CAP 
GROUP=PWR_MLCC_CAP 
GROUP=PWR_MLCC_CAP 
BOM_SS=NOPOP 
GROUP=PWR_MLCC_CAP 
NEW_MATERIAL=X6S 
NEW_PN=078.1071T.0811 NEW_PN=078.1071T.0811 
NEW_MATERIAL=X6S 
GROUP=PWR_MLCC_CAP 
BOM_SS=NOPOP 
NEW_MATERIAL=X6S 
BOM_SS=NOPOP 
NEW_MATERIAL=X6S 
GROUP=PWR_MLCC_CAP 
BOM_SS=NOPOP 
BOM_SS=NOPOP 
GROUP=PWR_MLCC_CAP 
GROUP=PWR_MLCC_CAP 
GROUP=PWR_MLCC_CAP 
BOM_SS=NOPOP BOM_SS=NOPOP 
GROUP=PWR_MLCC_CAP 
GROUP=PWR_MLCC_CAP 
NEW_MATERIAL=X6S 
NEW_PN=078.1071T.0811 NEW_PN=078.1071T.0811 
GROUP=PWR_MLCC_CAP 
NEW_MATERIAL=X6S BOM_SS=NOPOP 
GROUP=PWR_MLCC_CAP 
BOM_SS=NOPOP 
BOM_SS=NOPOP 
NEW_MATERIAL=X6S 
NEW_PN=078.1071T.0811 
BOM_SS=NOPOP 
NEW_MATERIAL=X6S 
GROUP=PWR_MLCC_CAP 
NEW_MATERIAL=X6S 
NEW_PN=078.1071T.0811 
NEW_MATERIAL=X6S 
BOM_SS=NOPOP 
GROUP=PWR_MLCC_CAP 
NEW_PN=078.1071T.0811 
NEW_MATERIAL=X6S 
BOM_SS=NOPOP GROUP=PWR_MLCC_CAP 
NEW_PN=078.1071T.0811 
BOM_SS=NOPOP 
BOM_SS=NOPOP 
GROUP=PWR_MLCC_CAP 
GROUP=PWR_MLCC_CAP 
BOM_SS=NOPOP 
BOM_SS=NOPOP 
GROUP=PWR_MLCC_CAP 
NEW_MATERIAL=X6S 
GROUP=PWR_MLCC_CAP 
GROUP=PWR_MLCC_CAP
GROUP=PWR_MLCC_CAP 
GROUP=PWR_MLCC_CAP 
GROUP=PWR_MLCC_CAP 
GROUP=PWR_MLCC_CAP 
GROUP=PWR_MLCC_CAP 
GROUP=PWR_MLCC_CAP 
GROUP=PWR_MLCC_CAP 
GROUP=PWR_MLCC_CAP 
GROUP=PWR_MLCC_CAP 
GROUP=PWR_MLCC_CAP 
GROUP=PWR_MLCC_CAP GROUP=PWR_MLCC_CAP 
GROUP=PWR_MLCC_CAP 
GROUP=PWR_MLCC_CAP 
GROUP=PWR_MLCC_CAP 
GROUP=PWR_MLCC_CAP 
GROUP=PWR_MLCC_CAP 
GROUP=PWR_MLCC_CAP 
GROUP=PWR_MLCC_CAP 
GROUP=PWR_MLCC_CAP 
GROUP=PWR_MLCC_CAP 
GROUP=PWR_MLCC_CAP 
GROUP=PWR_MLCC_CAP 
GROUP=PWR_MLCC_CAP 
GROUP=PWR_MLCC_CAP 
GROUP=PWR_MLCC_CAP GROUP=PWR_MLCC_CAP 
GROUP=PWR_MLCC_CAP 
GROUP=PWR_MLCC_CAP 
GROUP=PWR_MLCC_CAP 
GROUP=PWR_BULK_CAP 
GROUP=PWR_BULK_CAP 
GROUP=PWR_BULK_CAP 
GROUP=PWR_BULK_CAP 
NEW_MATERIAL=X6S 
100NH 
ISAT=16A@25C 
DCR=0.16MOHM 
IRMS=29A@DELTA_T<45C 
GROUP=PWR_MLCC_CAP 
GROUP=PWR_MLCC_CAP 
NEW_PN=078.1071T.0811 
NEW_PN=078.1071T.0811
GROUP=PWR_MLCC_CAP 
GROUP=PWR_MLCC_CAP GROUP=PWR_MLCC_CAP 
GROUP=PWR_MLCC_CAP 
GROUP=PWR_MLCC_CAP 
GROUP=PWR_MLCC_CAP 
BOM_SS=NOPOP BOM_SS=NOPOP 
BOM_SS=NOPOP 
BOM_SS=NOPOP 
BOM_SS=078.1061T.M001 
GROUP=PWR_MLCC_CAP 
GROUP=PWR_MLCC_CAP 
5MIL SPACING 
10MIL WIDTH 
ROUTE AS DIFF PAIR 
2
1
1
2
2
1
2
21
1
DO NOT SCALE DRAWING SHEET 
B
AA
B
B
SIZE 
SCALE: 
234
1234
DEPARTMENT CODE 
1
DOCUMENT NUMBER REV 
PVDDQ_KLM 
PVDDQ_KLM 
PVDDQ_KLM 
IN 
IN 
PVDDQ_KLM 
PVDDQ_KLM 
PVDDQ_KLM 
PVDDQ_KLM 
PVDDQ_KLM 
PVDDQ_KLM 
PVDDQ_KLM 
PVDDQ_KLM 
P12V_STBY 
PVDDQ_KLM 
PVDDQ_KLM VOLTAGE SENSE 
INPUT FILTER 
228 OF 270 
Wed Feb 08 16:35:31 2017 
228 OF 270 
ROOM=VDDQ_KLM_CPU1 
PLACE NEAR VR OUTPUT INDUCTORS 
CAD NOTE: 
TP FAB1 CHANGE CAP 0322 
TP FAB1 CHANGE L1B1 PN 0122 
CAPS TO BE PLACED BETWEEN DIMMS 
PVDDQ CPU CAVITY CAPS 
TP FAB1 CHANGE CAP 0314 
TP FAB1 CHANGE CAP 0322 
VDDQ KLM DECAP (3 OF 3) 
WIWYNN CORPORATION ROOM = VDDQ_KLM_PWR_VR 



47UF 
C8U10 
100UF 
602433-112 
100UF 
602433-112 
602433-106 
20% 
0603V 
C2F2 
4V 
C6W12 1
2
20% 
0805 
1
2
4V 
100UF 
0805 
C8T3 
0603LF 
E15431-001 
C6U13 
20% 
4V 
X6S 
1
2
10UF 
1
N_A 
SH8U1 
2
C6U11 
4.7UF 
2
6.3V 
1
10% 
X6S 
E15431-003 
0603 
2 0402 
D97712-011 
X6S 10% 
1.0UF 
C4G18 1 16V 
E15431-001 
X6S 
4V 
2
1 C6U14 
10UF 
0603LF 
EMPTY 
C4G12 
2
11000PF 
50V 
10% 
0402LF 
C4G21 
1.0UF 16V 
10% X6S 2
1
0402 
D97712-011 
0805LF 
X6S 
20% 
4V 
2
1
G21796-016 
CHIP 
1/16W 
1% 
10.0K 
0402 
1
R4G17 
2
0402LF 
X7R 
50V 
C4G13 
2
1
2
1
33.2 
1/16W 0402 
2
CHIP 
R4G15 
1
1% 
G21796-074 
10 
11 
4
H55101-001 
2
1
6
8
3
7
9
5
IC 
EU4G2 
2
0402 
1
CHIP 
R4G16 
G21497-005 
5% 0.0 1/16W 
R6U3 
1.0M 
2
1
1% 
1/16W 
EMPTY 
G21796-021 
0402 
G21497-005 
1/16W 0402 0.0 5% 
R6U6 
0402 
1/16W CHIP 
5% 0.0 
G21497-005 
R6U7 
1 2
PLACE CLOSE TO CONTROLLER 
OF PVTT PLANE 
PLACE NEAR CENTER 
PLACE CLOSE TO CONTROLLER 
PWRGD_PVTT_CPU1 
VR_PVTT_GHJ_SNS 
FM_PVTT_GHJ_EN_R 
VSENSE_PVDDQ_GHJ_VTT 
VR_PVTT_GHJ_BIAS 
VR_PVTT_GHJ_VREF 
PWRGD_PVDDQ_GHJ_R 
20% 
4V 
20% 
X5R 
SPOF 
22UF 
C4G20 
A36096-046 
10% 
1000PF 
PWRGD_PVTT_GHJ_CPU1_R 
0805 
602433-112 2
1
4V 
20% 
230 190 
223 
NEW_PN=078.1071T.0811 
NEW_PN=078.1071T.0811 
NEW_PN=078.1071T.0811 
GROUP=PWR_MLCC_CAP 
GROUP=PWR_MLCC_CAP GROUP=PWR_MLCC_CAP 
NEW_MATERIAL=X6S 
GROUP=PWR_MLCC_CAP 
GROUP=PWR_MLCC_CAP 
NEW_MATERIAL=X6S 
NEW_MATERIAL=X6S 
CHIP 
A36096-046 
C95333-002 
1
2
CAD NOTE: 
CAD NOTE: 
CAD NOTE: 
CAD NOTE: 
CAD NOTE: 
AC & RIPPLE=+3.5/-7.3% 
DC TOL= +/-1.5% 
VOUT=0.5 VDDQ 
IOUT DI/DT=6A/US 
RIPPLE GUIDELINE= +/-1% 
IOUT PEAK=+-/1.4A 
IOUT TDC=+/-1.4A 
IOUT STEP=+1.523A / -1 .546A 
DO NOT SCALE DRAWING SHEET 
B
AA
B
B
SIZE 
SCALE: 
234
1234
DEPARTMENT CODE 
1
DOCUMENT NUMBER REV 
PVDDQ_GHJ 
P3V3 
PVTT_GHJ 
OUT 
IN 
PVTT_GHJ 
P3V3 
PVTT DDR SPECIFICATION: 
229 OF 270 
Wed Feb 08 16:35:31 2017 
MIC5166 
THPAD 
VTT 
PGND SNS 
VDDQ 
PG 
AGND BIAS 
VREF 
VIN 
EN 
TP FAB1 CHANGE RES TO CAP 0311 
PLACED BETWEEN DIMMS 
TP FAB1 CHANGE CONNECTION 0303 
CRTICAL: PLACE 0 OHM NEAR  VDDQ SENSE RESISTOR. 
TP FAB3 CHANGE CAP 0803 
DDR VTT VR CHANNEL GHJ 
YRANIMILERP
ROOM = VTT_GHJ_PWR_VR 
WIWYNN CORPORATION 



C4A15 
100UF 
4V 
20% 
2
C8L3 
4V 
20% 
X5R 
1
602433-106 
0603V 
602433-112 
0805 2
C6W13 1
20% 
4V 
100UF 
2
20% 
4V 
100UF 
602433-112 
0805 0805 
602433-112 
0402LF 
VR_PVTT_KLM_SNS 
FM_PVTT_KLM_EN_R 
VSENSE_PVDDQ_KLM_VTT 
VR_PVTT_KLM_BIAS 
PWRGD_PVTT_KLM_CPU1_R PWRGD_PVTT_CPU1 
PWRGD_PVDDQ_KLM_R 
PLACE CLOSE TO CONTROLLER 
OF PVTT PLANE 
PLACE NEAR CENTER 
SPOF 
PLACE CLOSE TO CONTROLLER 
CHIP 
G21497-005 
5% 0.0 1/16W 
R6L6 
0402 
0402 
G21796-021 
EMPTY 
1/16W 
1% 
1.0M 
R6L5 
2
1
0402 
0.0 5% 
R4A3 
G21497-005 
1 2
CHIP 
1/16W 
EU4A2 
2
H55101-001 
6
3
8
11 
10 
7
IC 
5
4
9
1
D97712-011 
10% X6S 
1.0UF 16V 
2
1
0402 
C4A14 
E15431-001 
10UF 
2 X6S 
1 C6L5 
20% 
4V 
0603LF 
0402 CHIP 
33.2 
R4A4 
G21796-074 
1/16W 
2
1% 
1
N_A 
1 2
SH8L1 
1
2
A36096-046 
X7R 
10% 
50V 
1000PF 
C4A3 
2
1
0402 
G21796-016 
CHIP 
1/16W 
1% 
1
R4A5 
10.0K 
2
0805LF 
X6S 
20% 
22UF 
2
1
4V 
EMPTY 
0402LF 
C4A6 
2
1
10% 50V 
1000PF 
0603LF 
E15431-001 
X6S 
20% 
4V 
10UF 
2
1
0402 
CHIP 1/16W 
0.0 5% 
G21497-005 
1 2
R6L8 
D97712-011 
10% 
1.0UF 
X6S 
16V 1
2 0402 
C4A8 
0603 
E15431-003 
X6S 
10% 
6.3V 
4.7UF 
C4A7 
2
1
47UF 
C8M12 
VR_PVTT_KLM_VREF 
C4A13 
1 C8L4 
229 190 
226 
NEW_PN=078.1071T.0811 
NEW_PN=078.1071T.0811 
NEW_PN=078.1071T.0811 
GROUP=PWR_MLCC_CAP 
GROUP=PWR_MLCC_CAP 
GROUP=PWR_MLCC_CAP 
NEW_MATERIAL=X6S 
GROUP=PWR_MLCC_CAP 
GROUP=PWR_MLCC_CAP NEW_MATERIAL=X6S 
NEW_MATERIAL=X6S 
A36096-046 
C95333-002 
2
1
CAD NOTE: 
CAD NOTE: 
CAD NOTE: 
CAD NOTE: 
CAD NOTE: 
IOUT DI/DT=6A/US 
VOUT=0.5 VDDQ 
RIPPLE GUIDELINE= +/-1% 
DC TOL= +/-1.5% 
IOUT STEP=-1.546/+1.523A 
AC & RIPPLE=+3.5/-7.3% 
IOUT PEAK=+/-1.4A 
IOUT TDC=+/-1.4A 
DO NOT SCALE DRAWING SHEET 
B
AA
B
B
SIZE 
SCALE: 
234
1234
DEPARTMENT CODE 
1
DOCUMENT NUMBER REV 
PVDDQ_KLM 
P3V3 
PVTT_KLM 
OUT 
IN 
P3V3 
PVTT_KLM 
PVTT DDR SPECIFICATION: 
230 OF 270 
Wed Feb 08 16:35:32 2017 
MIC5166 
THPAD 
VTT 
PGND SNS 
VDDQ 
PG 
AGND BIAS 
VREF 
VIN 
EN 
TP FAB3 CHANGE CAP 0803 
PLACED BETWEEN DIMMS 
TP FAB1 CHANGE CONNECTION 0303 
CRTICAL: PLACE 0 OHM NEAR  VDDQ SENSE RESISTOR. 
TP FAB1 CHANGE RES TO CAP 0311 
DDR VTT VR CHANNEL KLM 
BOM_COST = MEM_VRD_VTT_KLM 
ROOM = VTT_KLM_PWR_VR 
YRANIMILERP
WIWYNN CORPORATION 



TP FAB3 CHANGE RES 0822 
TP FAB1 CHANGE RES PACKAGE TO 0603 
191 232 
91 190 
G21796-242 
FB7F1 
0805 
0.47UH 
GROUP=PWR_MLCC_CAP
GROUP=PWR_MLCC_CAP 
GROUP=PWR_BULK_CAP 
0805 
C95333-006 724613-067 
POSCAP 
47UF 
4V 
20% 
GROUP=PWR_MLCC_CAP 
GROUP=PWR_MLCC_CAP 
C6F5 
10UF 
20% 
X6S 
2
0603LF 0603LF 
2
20% 
4V 
C6F6 
10UF 
X6S 
0603LF 
E15431-001 
2
20% 20% 
4V 
X6S X6S 
E15431-001 E15431-001 
20% 
2 X6S 
10UF 
4V 
X6S 
20% 20% 
10UF 
C4T6 1 10UF 1 C4U2 C4U1 C4U3 
10UF 
4V 
POSCAP 
7343LF 
GROUP=PWR_BULK_CAP 
C6F4 
330UF 
2
C3T7 
4V 
1
20% 
G21497-016 
C7F7 
22UF 
20% 
16V 
X6S 
0805 
C22W10 
22UF 
20% 
16V 
X6S 
0805 
C95333-007 2
R7F13 
20.0K 
1/16W 
0402 
CHIP 
G21796-040 
R7F11 
VR_FB_PVPP_ABC 
1% 
2
1 6.19K 
1% 
2
1
G21497-005 
R7F35 
2
1 1
4V 
2
1 10UF 
C4T5 
0603LF 
4V 
1
2
4V 
2
0603LF 
C6G2 
4V 
2
10UF 
0603LF 
X6S 
1 10UF 
0603LF 
2
4V 
2
1 C6G4 
AGND_PVPP_ABC 
G21796-016 
CHIP 
1/16W 
1% 
0402 
2
1 10.0K 
R7F14 
C7F8 1
0402LF 
A36096-046 
EMPTY 
10% 
50V 
2
1000PF 
1
0402LF 2
2
1/16W 
1% 
1
1 1
0603LF 
E15431-001 E15431-001 
0603LF 
X6S 2
602433-020 
C7F4 
12
25V 
0603LF 
0.1UF 
10% X7R 
0402 
C3T10 
1.0UF 
16V 
1
2
10% 
X6S 
D97712-011 
1
2
1
2
0402 
0.0 5% 
2
CHIP 1/16W AGND_PVPP_ABC 
2
1
5% 
2.2 R7F7 
EMPTY 
0402 
1/16W 
A36096-091 
0402LF 
EMPTY 50V 
2
1 C7F3 
10% 
3300PF 
0603 
2
1
1% 
CHIP 
1/10W 
120.0 
1 2 SM 
IND 
L7F1 
E13358-018 
2 X6S 
4V 
0805 
20% 
47UF 
C95333-006 
C3T9 1
5
16 
EU7F1 
IC 
4
7
1
40 
38 
11 
8
14 
42 
39 
41 
17 
18 
19 
20 
25 
24 
23 
22 
21 
26 
27 
28 
37 
3
2
31 
30 
29 
15 
33 
34 
43 
32 
13 
6
9
12 
10 
35 
36 
0402 
C7F10 1
2
X7R 
5% 
2 1
C7F9 
0402LF COG 
10% 
50V 
X7R 
R7F18 
1.0% 
1 2
0402 
CHIP 1/16W 
7.87K 
1 4.7UF 
X6S 
6.3V 
E15431-003 
10% 
0603 2
C3T11 
AGND_PVPP_ABC 
A36096-030 
X7R 2
16V 
10% 
1 C7F6 
0402V 
0.1UF 
1
1/16W 
2
1.0% 
R7F16 
G21796-250 
C7F5 
10UF 
16V 
10% 
X6S 
0805 
1
2 X6S 
16V 
10% 
C95333-007 
0805 
1 C3T8 
10UF 
2 X6S 
16V 
10% 
C95333-007 
1 10UF 
C3T14 
C95333-007 
10% 
2
0805 
X6S 
1 C3T12 
10UF 
16V 
R7F17 
1.0K 1
2
50V 
1 C7F13 
0402 
CHIP 1/16W 
0.0 5% 
G21497-005 
1
R7F9 
2
1/10W 
5.0% 
G22178-002 CHIP 
R7F8 
0
0603 
FM_PVPP_CPU0_EN 
VR_PVPP_ABC_BOOT_R 
VR_COMP_PVPP_ABC_3 
VR_PVPP_ABC_SNUB 
VR_PVPP_ABC_PHASE 
VR_PVPP_ABC_BOOT 
VR_FET_SW_P12V_STBY_PVPP_ABC 
PWRGD_PVPP_ABC_R 
VR_VB_PVPP_ABC 
FM_PVPP_PVDDQ_CPU0_EN_ABC 
12
0402LF 
2200PF 
A36096-075 
VR_COMP_RC_PVPP_ABC 
0402 
22.1 
PWRGD_PVPP_ABC 
CHIP 
A36096-046 
0402LF 
FB 
1 2
SM 
656554-051 
22 
10% 
A36096-129 AGND_PVPP_ABC 
CONFIG=078.47521.08BD 16V 
0.027UF 
1
10% 
CHIP 
50V 
0402 
1.00K 
G21796-026 
1
X7R 
C7F11 
1000PF 
R7F19 
CHIP 
0402 
R7F15 
1
2
AGND_PVPP_ABC 
NEW_VALUE=3.9K 
CONFIG=64.39015.6DL 
1/16W 
1.0% 
AGND_PVPP_ABC 
H86355-001 
R7F10 
G22026-003 2
1
20% 
6.3V 724613-042 
1
2
C4T3 
220UF 
20% 
4V 
7343 
X6S 
E15431-001 E15431-001 E15431-001 
20% 
0603LF 
E15431-001 
X6S 
20% 
10UF 
C6G1 
AGND_PVPP_ABC 
C7F12 
A36095-026 
50V 100.0PF 
X6S 
R7F12 
0.0 
1/16W 
5% 
CHIP 
0402 
G21497-005 
0.1% 
1/16W 
0402 
CHIP 
G85996-004 
2200PF 
10% 
X7R 
A36096-075 
1/16W 
CHIP 
G21796-161 
0402 
AGND_PVPP_ABC 
GROUP=PWR_MLCC_CAP 
GROUP=PWR_MLCC_CAP 
GROUP=PWR_MLCC_CAP 
GROUP=PWR_MLCC_CAP 
GROUP=PWR_MLCC_CAP 
GROUP=PWR_MLCC_CAP 
GROUP=PWR_MLCC_CAP 
0603LF 
E15431-001 E15431-001 
X6S 
C6G5 
10UF 
4V 
20% 
X6S 20% 
0603LF 
E15431-001 
4V 
10UF 
C4U4 
GROUP=PWR_MLCC_CAP 
GROUP=PWR_MLCC_CAP 
GROUP=PWR_MLCC_CAP 
SC22U16V5MX-4-GP 
SC22U16V5MX-4-GP 
VR_PVPP_ABC_SS 
VSENSE_PVPP_ABC 
VR_COMP_PVPP_ABC 
VR_PVPP_ABC_ISET 
CAD NOTE: 
BOM_COST: PVPP_ABC_VR 
ROOM = PVPP_ABC_VR 
PLACE DECOUPLING SAME SIDE 
1 2
AND CLOSE TO IC PINS 
PUT TOGETHER 
DO NOT SCALE DRAWING SHEET 
B
AA
B
B
SIZE 
SCALE: 
234
1234
DEPARTMENT CODE 
1
DOCUMENT NUMBER REV 
P3V3_STBY 
OUT 
PVPP_ABC 
P12V_STBY 
IN 
PVPP_ABC 
1 2
1 2
Wed Feb 08 16:35:32 2017 
6.25MS 
(0.4V/MS) 
12A OC 
231 OF 270 
PG 
PGND<0> 
PGND<1> 
PGND<2> 
PGND<3> 
PGND<4> 
PGND<5> 
PGND<6> 
PGND<8> 
PGND<7> 
PGND<9> 
PGND<10> 
PGND<11> 
PGND<12> 
PGND<13> 
GND AGND 
EN 
SS 
ISET 
OTS 
VIN<6> 
VIN<7> 
VCC 
VIN<1> 
VIN<5> 
VIN<4> 
VIN<3> 
VIN<2> 
VIN<0> 
VB 
COMP 
FB 
VSWH<1> 
VSWH<0> 
VSW 
VSWH<2> 
VSWH<3> 
VSWH<4> 
VSWH<5> 
VSWH<6> 
BST 
VSWH<7> 
TP FAB1 CHANGE ONE 47UF CPA TO TWO 22UF CAPS 0107 
VOUT = 2.5V 
SW FREQ =  500KHZ 
DC TOL = +/-1.5% 
AC & RIPPLE TOL = +3.5%, -7.3% 
RIPPLE GUIDELINE = +/- 1.0% 
IOUT PK = 10.1A (INCLUDED CPU PVPP) 
IOUT STEP = 5.3A 
IOUT DI/DT = 21.5A/US 
TP FAB1 CHANGE RES 0531 
TP FAB1 CHANGE CAP 0422 
CAPS TO BE PLACED BETWEEN DIMMS 
IOUT TDC = 7.21A (INCLUDED CPU PVPP) 
PLACE ON TOP LAYER 
POINT ONLY TOP TO L2 CONNECT AT SINGLE 
COMPENSATION TYPE III 
VPP ABC VR 
NCP3232L 
SPOF 
WIWYNN CORPORATION 
SPOF 



VR_FET_SW_P12V_STBY_PVPP_DEF 
R7B11 
C3M16 
C95333-007 
2
CHIP 
0402 
5% 
1/16W 
0.0 
1
C6B7 
330UF 
6.3V 
POSCAP 
7343LF 
724613-042 0805 
C95333-006 
0805 
C95333-006 724613-067 
7343 
POSCAP 
20% 
20% 
X6S 
E15431-001 E15431-001 
20% 
10UF 
E15431-001 
C6B1 
0603LF 
1
X6S 2
C6B2 
10UF 
0603LF 
1
2
20% 
E15431-001 
0603LF 0603LF 
2
10UF 
C4L3 
20% 
X6S 
1 C4L4 
E15431-001 
0603LF 0603LF 
E15431-001 
0603LF 
2 X6S 
1
E15431-001 
C4M3 
10UF 
20% 
0603LF 
E15431-001 2
0603LF 
E15431-001 E15431-001 
X6S 
20% 20% 
10UF 
C4M4 
C7B10 
G21497-016 
1/16W 
VR_PVPP_DEF_PHASE 
R7B10 
X6S 
4V 
47UF 
C6B3 
0603 
G22026-003 
20% 4V 
47UF 
2
1
AGND_PVPP_DEF 
X7R 
A36096-129 
0402 
AGND_PVPP_DEF 
1/16W 
CHIP 
R7B14 
0402 
AGND_PVPP_DEF 
1.0% 
2
1
H86355-001 
C4L1 
1% 
R7B17 
20 
38 
X6S 
4.7UF 
1/16W 
FB7B1 
22 
1
FB 
656554-051 
2
SM C7B8 C22W7 C3M8 1
0805 
2
10UF 
AGND_PVPP_DEF 
R7B15 
VR_VB_PVPP_DEF 
FM_PVPP_PVDDQ_CPU0_EN_DEF FM_PVPP_CPU0_EN 
PWRGD_PVPP_DEF_R 
VR_PVPP_DEF_BOOT 
VR_PVPP_DEF_BOOT_R 
VR_COMP_RC_PVPP_DEF 
VR_COMP_PVPP_DEF_3 
PWRGD_PVPP_DEF 
VR_PVPP_DEF_SNUB 
CHIP G22178-002 
R7B19 
5.0% 0
0603 1/10W 
0.0 
2
1/16W 
1
G21497-005 
5% 0402 
CHIP 
R7B9 
A36096-075 
0402LF 
10% 
2200PF 50V 
X7R 
C7B14 
12
20.0K 1
2
1% 1 2200PF 
50V 
X7R 
2
C7B13 
10% 
COG 
100.0PF 
1
50V 
A36095-026 
0402LF 
5% 
2
1/16W 
1.0% 
CHIP 
0402 
G21796-242 
7.87K 
1 2
R7B16 
G21497-005 
G85996-004 
CHIP 
0402 
1/16W 
0.1% 
R7B18 
1.0K 1
2
1
2
X6S 
0805 
10% 
1
16V 
10UF 
C7B5 
C95333-007 2
0805 
10% 
1
16V 
10UF 
C95333-007 
X6S 2
1
16V 
10UF 
C3M15 
10% 
C95333-007 
0805 
X6S 2
10% 
16V 
CHIP 0402 
1.0% 
2
R7B12 
22.1 
1
G21796-250 
AGND_PVPP_DEF 
1
2
C3M10 
6.3V 
10% 
X6S 
0603 
E15431-003 
2
16V 
0.1UF 1 C7B6 
X7R 
10% 
A36096-030 
0402V 
AGND_PVPP_DEF 
AGND_PVPP_DEF 
X7R 10% 
0.1UF 25V 
0603LF 
12
602433-020 
C7B30 
E13358-018 
IND SM 
1
0.47UH 
L7B1 
2
20% 
1
2
C7B7 
X6S 
20% 
1
2CHIP 
1/10W 
1% 
120.0 1
2A36096-091 
0402LF 
EMPTY 50V 
3300PF 
C7A34 1
10% 
2
0402 
EMPTY 
2.2 
2
1 R7A15 
5% 
EU7B1 
IC 
39 
1
32 
36 
35 
5
7
40 
4
6
9
8
42 
14 
13 
12 
41 
3
2
16 
17 
18 
19 
21 
22 
23 
24 
25 
26 
27 
28 
37 
15 
29 
30 
31 
33 
34 
43 
11 
10 
1/16W 
CHIP 
1.00K 
2
G21796-026 
0402 
1
1 1000PF 
50V 
10% 
X7R 
0402LF 
A36096-046 
C7B12 
2
1.0UF 
10% 
16V 
C3M9 1
X6S 2 D97712-011 
0402 
2
1
0.027UF 
C7B11 
16V 
10% 
2
1000PF 
C7B9 1
50V 
10% 
EMPTY 
A36096-046 
0402LF 
AGND_PVPP_DEF 
G21497-005 
5% 
2
R7B20 
0.0 
1/16W 
1
CHIP 
0402 
X6S 2 E15431-001 
20% 
1 10UF 
0603LF 
1
20% 
10UF 
0603LF 
2 X6S 
1
2
20% 
X6S 
C6A6 1 C6A7 
10UF 
2 X6S 
20% 
E15431-001 
1 10UF 
X6S 2
C6A2 1
X6S 
10UF 
C6A3 
10UF 1
2
C4L2 
10UF 
0603LF 
X6S 
1
2
20% 
0402LF 
A36096-075 
6.19K 1
0402 
2
R7B13 
VR_FB_PVPP_DEF 
1/16W 
0402 
CHIP 
G21796-161 
CHIP 
1/16W 
1% 
G21796-040 
C4M1 
220UF 
4V 
TP FAB3 CHANGE RES 0823 
TP FAB1 CHANGE RES PACKAGE TO 0603 
191 231 
190 
22UF 
GROUP=PWR_BULK_CAP 
GROUP=PWR_MLCC_CAP
GROUP=PWR_MLCC_CAP 
GROUP=PWR_BULK_CAP 
GROUP=PWR_MLCC_CAP 
GROUP=PWR_MLCC_CAP 
GROUP=PWR_MLCC_CAP 
GROUP=PWR_MLCC_CAP 
4V 4V 
GROUP=PWR_MLCC_CAP 
GROUP=PWR_MLCC_CAP 
GROUP=PWR_MLCC_CAP 
GROUP=PWR_MLCC_CAP 
GROUP=PWR_MLCC_CAP 
GROUP=PWR_MLCC_CAP 
4V 4V 
GROUP=PWR_MLCC_CAP 
GROUP=PWR_MLCC_CAP 
4V 4V 4V 
CONFIG=64.39015.6DL 
NEW_VALUE=3.9K 
CONFIG=078.47521.08BD 
22UF 
0805 
X6S 
16V 
20% 
0805 
X6S 
16V 
20% 
4V 4V 4V 4V 4V 
VR_PVPP_DEF_ISET 
SC22U16V5MX-4-GP 
SC22U16V5MX-4-GP 
VR_PVPP_DEF_SS 
VSENSE_PVPP_DEF 
VR_COMP_PVPP_DEF 
1 2
PUT TOGETHER 
DO NOT SCALE DRAWING SHEET 
B
AA
B
B
SIZE 
SCALE: 
234
1234
DEPARTMENT CODE 
1
DOCUMENT NUMBER REV 
OUT 
P3V3_STBY 
P12V_STBY 
IN 
PVPP_DEF 
PVPP_DEF 
1
2 1
2
Wed Feb 08 16:35:32 2017 
(0.4V/MS) 
12A OC 
6.25MS 
232 OF 270 
PG 
PGND<0> PGND<1> PGND<2> PGND<3> PGND<4> PGND<5> PGND<6> 
PGND<8> 
PGND<7> 
PGND<9> PGND<10> PGND<11> PGND<12> PGND<13> 
GND AGND 
EN 
SS 
ISET 
OTS 
VIN<6> VIN<7> 
VCC 
VIN<1> 
VIN<5> 
VIN<4> 
VIN<3> 
VIN<2> 
VIN<0> 
VB 
COMP 
FB 
VSWH<1> 
VSWH<0> 
VSW 
VSWH<2> VSWH<3> VSWH<4> VSWH<5> VSWH<6> 
BST 
VSWH<7> 
TP FAB1 CHANGE CAP 0422 
VOUT = 2.5V 
RIPPLE GUIDELINE = +/- 1.0% 
AC & RIPPLE TOL = +3.5%, -7.3% IOUT TDC = 7.21A (INCLUDED CPU PVPP) 
IOUT PK = 10.1A (INCLUDED CPU PVPP) 
IOUT DI/DT = 21.5A/US IOUT STEP = 5.3A 
SW FREQ =  500KHZ 
TOP LAYER 
ROOM = PVPP_DEF_VR 
BOM_COST: PVPP_DEF_VR 
PLACE ON 
COMPENSATION TYPE III 
TP FAB1 CHANGE RES 0531 
TP FAB1 CHANGE ONE 47UF CPA TO TWO 22UF CAPS 0107 
CAPS TO BE PLACED BETWEEN DIMMS 
DC TOL = +/-1.5% 
VPP DEF VR 
NCP3232L 
SPOF 
WIWYNN CORPORATION 
SPOF 



0402LF 
VR_FET_SW_P12V_STBY_PVPP_GHJ 
10% 
FM_PVPP_PVDDQ_CPU1_EN_GHJ 
C95333-007 
L4G1 
20% 
724613-042 
7343LF 
20% 
E15431-001 
0603LF 0603LF 0603LF 0603LF 0603LF 0603LF 
C3G7 
10UF 
20% 
X6S 
E15431-001 
0603LF 
POSCAP 
C4F11 
220UF 
20% 
4V 
POSCAP 
7343 
724613-067 
6.3V 
20% 
330UF 
C4F7 
2
11
2
AGND_PVPP_GHJ 
AGND_PVPP_GHJ 
AGND_PVPP_GHJ 
AGND_PVPP_GHJ 
AGND_PVPP_GHJ 
AGND_PVPP_GHJ 
AGND_PVPP_GHJ 
AGND_PVPP_GHJ 
CHIP 
0402 
1/16W 
2
5
1
1.0% 
A36096-129 
X7R 
0402 
PWRGD_PVPP_GHJ_R 
50V 
R4G12 
G21796-026 
656554-051 
22 
21
FB4G1 
SM FB C4G5 C22W6 
R4G9 
2
1 6.19K 
1% 
PWRGD_PVPP_GHJ 
VR_COMP_RC_PVPP_GHJ 
VR_PVPP_GHJ_SNUB 
FM_PVPP_CPU1_EN 
VR_PVPP_GHJ_BOOT_R 
VR_PVPP_GHJ_PHASE 
VR_PVPP_GHJ_BOOT 
VR_COMP_PVPP_GHJ_3 
VR_VB_PVPP_GHJ 
R4G24 
1/10W 0603 
5.0% 0
G22178-002 
E13358-018 
1 2
SM 0.47UH 
IND 
1
G21497-005 
5% 
1/16W 
0402 
CHIP 
0.0 
R4G4 
2
X7R 
0402LF 
50V 2200PF 
A36096-075 
12
C4G10 
10% 
A36095-026 
100.0PF COG 
5% 
50V 
C4G6 
12
7.87K 
1/16W 
1.0% 
G21796-242 
CHIP 
0402 
R4G13 
21
G21497-005 
0402 
CHIP 
5% 
1/16W 
R4G8 2
1
0.0 
G21796-040 
CHIP 
0402 
1 20.0K 
R4G7 
2
1/16W 
1% 
50V 
X7R 
2
1
10% 
2200PF 
C4G11 
G85996-004 
CHIP 
0402 
1/16W 
0.1% 
1.0K 
R4G10 
1
2
0805 
X6S 
10% 
2
11
2
10% 
16V 
X6S 
0805 
10UF 
16V 
X6S 
22.1 
1/16W 
1
CHIP 
1.0% 
G21796-250 
2
0402 
10% 
A36096-030 
16V 
2 X7R 
1 C6U5 
0402V 
0.1UF 
IC 
30 
29 
11 
21 
4
7
40 
6
1
38 
8
9
10 
12 
13 
14 
39 
42 
H86355-001 
41 
16 
17 
18 
22 
20 
19 
23 
27 
26 
25 
24 
28 
3
2
37 
35 
15 
34 
33 
32 
31 
36 
43 
EU4G1 
2
0603LF 
25V 
X7R 
0.1UF 
10% 
1
602433-020 
C4G26 
C95333-006 
C6U2 1
0805 
47UF 
4V 
X6S 
2
0805 
C95333-006 
C6U3 
47UF 
4V 
20% 
2
1
X6S G22026-003 
CHIP 
0603 
2
1/10W 
1
R4G6 
1% 
120.0 
1
2
10% 
0402LF 
A36096-091 
EMPTY 
C4F12 
50V 
3300PF 
G21497-016 
1/16W 
2.2 5% 
0402 
2
EMPTY 
R4F6 1
X7R 
1 C4G9 
10% 
1000PF 
2 0402LF 
A36096-046 
2 D97712-011 
1.0UF 
0402 
X6S 
10% 
16V 
1 C4G4 
0402 
10% 
16V 
2
C4G8 
0.027UF 1
X6S 
E15431-003 
0603 
10% 
4.7UF 
6.3V 
2
1 C6U6 
1.00K 
1% 
1
1/16W 
2 CHIP 
R4G14 
0402LF 
A36096-046 
EMPTY 
10% 
1000PF 
C4G7 
50V 
2
1
0402 
G21796-016 
CHIP 
R4G5 
2
1
1/16W 
1% 
10.0K 
1/16W 
0402 
5% 0.0 
1 2
CHIP 
G21497-005 
R4G25 
10UF 1 C7U3 
0603LF 
E15431-001 
X6S 2
10UF 
C3G8 
E15431-001 
1
X6S 2
20% 
C3G4 1
2
10UF 1
20% 
2 X6S 
E15431-001 
1
2 X6S 
10UF 
C3G3 
E15431-001 
20% 
2
1
X6S 
10UF 
E15431-001 
20% 
C3F4 C3F3 
10UF 
20% 
X6S 
E15431-001 
0603LF 
2
11
0603LF 
E15431-001 
C7U6 
2 X6S 
20% 
10UF 
C7T3 
10UF 1
X6S 2
20% 
2 X6S 
1 10UF 
E15431-001 
C7T2 
20% 
E15431-001 2 X6S 
1 C7U5 
10UF 
0603LF 
20% 
0603LF 
C7U4 
10UF 
E15431-001 
1
20% 
X6S 
2
VR_FB_PVPP_GHJ 
1/16W 
CHIP 
0402 
G21796-161 
0402LF 
A36096-075 
C95333-007 2
10UF 1 C4G2 
C95333-007 
0805 
C95333-007 
16V 
10UF 
C6U8 C6U7 
10UF 
16V 
10% 
X6S 
2
0805 
1 C6U4 
R4G11 
TP FAB1 CHANGE RES PACKAGE TO 0603 
TP FAB3 CHANGE CAP 0823 
190 
191 234 
GROUP=PWR_MLCC_CAP
GROUP=PWR_MLCC_CAP 
GROUP=PWR_BULK_CAP 
4V 
GROUP=PWR_MLCC_CAP 
GROUP=PWR_MLCC_CAP 
GROUP=PWR_MLCC_CAP 
GROUP=PWR_MLCC_CAP 
GROUP=PWR_MLCC_CAP 
GROUP=PWR_MLCC_CAP 
GROUP=PWR_MLCC_CAP 
GROUP=PWR_MLCC_CAP 
GROUP=PWR_MLCC_CAP 
GROUP=PWR_MLCC_CAP 
GROUP=PWR_MLCC_CAP 
GROUP=PWR_MLCC_CAP 
GROUP=PWR_BULK_CAP 
CONFIG=64.39015.6DL 
NEW_VALUE=3.9K 
22UF 
20% 
16V 
X6S 
0805 
CONFIG=078.47521.08BD 
4V 4V 4V 4V 4V 4V 4V 4V 4V 4V 4V 
0805 
X6S 
16V 
20% 
22UF 
VR_PVPP_GHJ_ISET 
SC22U16V5MX-4-GP 
SC22U16V5MX-4-GP 
VR_PVPP_GHJ_SS 
VSENSE_PVPP_GHJ 
VR_COMP_PVPP_GHJ 
BOM_COST: PVPP_GHJ_VR 
ROOM = PVPP_GHJ_VR 
21
PUT TOGETHER 
DO NOT SCALE DRAWING SHEET 
B
AA
B
B
SIZE 
SCALE: 
234
1234
DEPARTMENT CODE 
1
DOCUMENT NUMBER REV 
OUT 
P12V_STBY 
P3V3_STBY 
IN 
PVPP_GHJ 
PVPP_GHJ 
1 2
1 2
6.25MS 
(0.4V/MS) 
12A OC 
233 OF 270 
Wed Feb 08 16:35:33 2017 
PG 
PGND<0> PGND<1> PGND<2> PGND<3> PGND<4> PGND<5> PGND<6> 
PGND<8> 
PGND<7> 
PGND<9> PGND<10> PGND<11> PGND<12> PGND<13> 
GND AGND 
EN 
SS 
ISET 
OTS 
VIN<6> VIN<7> 
VCC 
VIN<1> 
VIN<5> 
VIN<4> 
VIN<3> 
VIN<2> 
VIN<0> 
VB 
COMP 
FB 
VSWH<1> 
VSWH<0> 
VSW 
VSWH<2> VSWH<3> VSWH<4> VSWH<5> VSWH<6> 
BST 
VSWH<7> 
COMPENSATION TYPE III 
IOUT DI/DT = 21.5A/US IOUT STEP = 5.3A IOUT PK = 10.1A (INCLUDED CPU PVPP) IOUT TDC = 7.21A (INCLUDED CPU PVPP) AC & RIPPLE TOL = +3.5%, -7.3% DC TOL = +/-1.5% 
CONNECT AT SINGLE 
VOUT = 2.5V 
TOP LAYER PLACE ON 
TP FAB1 CHANGE CAP 0422 
TP FAB1 CHANGE RES 0531 
TP FAB1 CHANGE ONE 47UF CPA TO TWO 22UF CAPS 0107 
CAPS TO BE PLACED BETWEEN DIMMS 
RIPPLE GUIDELINE = +/- 1.0% 
POINT ONLY TOP TO L2 
SW FREQ =  500KHZ 
VPP GHJ VR 
NCP3232L 
SPOF 
WIWYNN CORPORATION 
SPOF 



2200PF 
X6S 
16V 
C95333-007 
EU4A3 
C6L10 
724613-042 724613-067 
7343 
POSCAP 
20% 
4V 
47UF 
20% 
C7L2 1
20% 
X6S 
E15431-001 E15431-001 
0603LF 0603LF 0603LF 0603LF 0603LF 
E15431-001 
20% 
10UF 
4V 
1/16W 
AGND_PVPP_KLM 
AGND_PVPP_KLM 
AGND_PVPP_KLM 
A36096-129 
X7R 
1/16W 
R4B6 
1.0% 
2
1
0402 
CHIP 
0402 
656554-051 
SM 
2
FB4A1 
FB 22 
1
1C4B1 10UF 
10% 
10UF 
C6M3 
C22W5 
2
0805 
1
C95333-007 
0805 
C4B5 
2
1
1000PF 
50V 
10% 
EMPTY 
A36096-046 
0402LF 
1
2
10% 
C4B8 
X7R 
50V 
A36096-046 
0402LF 
1000PF 
2
1% 
1
1/16W 
CHIP 
0402 
1.00K 
G21796-026 
R4B10 
X6S 
1 C6L12 
4.7UF 
6.3V 
2 0603 
E15431-003 
10% 
1
2
0.027UF 
16V 
10% 
C4B6 
2
1
16V 
1.0UF 
C6L11 
0402 
D97712-011 
X6S 
10% 
G21497-016 
EMPTY 
0402 1/16W 
2.2 R4A7 
2
1 5% 
2
1 C4A16 
50V 
0402LF 
3300PF 
10% 
EMPTY 
A36096-091 
1 2
IND 0.47UH 
L4A1 E13358-018 
SM C4B3 1
C95333-006 
C4B2 
47UF 
20% 
1
0805 
X6S 2
C4B15 
0.1UF 
X7R 
2
25V 
602433-020 
1
0603LF 
10% 
2
1
CHIP 
1/10W 
1% 
120.0 
R4B2 
0603 
5
7
40 
38 
1
4
6
10 
11 
12 
13 
14 
42 
8
9
39 
IC 
41 
16 
18 
17 
21 
24 
23 
22 
25 
28 
27 
26 
35 
2
3
29 
15 
31 
30 
34 
33 
32 
43 
36 
37 
20 
H86355-001 
19 
AGND_PVPP_KLM 
AGND_PVPP_KLM 
2
1
X7R 
16V 
10% 
C4A20 
0.1UF 
A36096-030 
0402V 
AGND_PVPP_KLM 
1
CHIP 
2
R4B7 
0402 1/16W 
1.0% 22.1 
G21796-250 
16V 16V 
2 X6S 
10% 
C6M5 
10UF 
1
C95333-007 
10% 
X6S 2
0805 
C4A19 
10UF 
16V 
1
10% 
0805 
X6S 2 C95333-007 
X7R 
2
C4B9 
10% 
1
0402LF 
50V 
A36096-075 
12
C4B4 
COG 50V 100.0PF 
A36095-026 5% 
0402LF 
1/16W 
1
1.0% 
2
CHIP 
0402 
G21796-242 
R4B8 
7.87K 
2
1 R4B3 
0.0 5% 
0402 CHIP 
G21497-005 
2
1
1/16W 
CHIP 
0402 
1% 
20.0K 
R4B5 
G21796-040 
C4B7 
2200PF 
50V 
10% 
X7R 
2
1
R4B9 
0.1% 
1/16W 
0402 2
CHIP 
G85996-004 
1.0K 1
0.0 
R4B1 
G21497-005 
1/16W CHIP 
5% 0402 
R4B13 
1/10W 
0
G22178-002 
5.0% 
0603 
AGND_PVPP_KLM CHIP 
1
R4B14 
5% 
2
C3B2 
10UF 
E15431-001 
X6S 2
1
0603LF 
1
2
20% 
X6S 
C3A8 
E15431-001 
10UF 
2
1
0603LF 
X6S 
C7L3 
2 X6S 
20% 
10UF 
E15431-001 2
1
10UF 
C7L7 
2 X6S 
20% 
1
10UF 
C7L6 
2 X6S 
20% 
1 C7M4 
10UF 
E15431-001 2 X6S 
20% 
1 C7M3 
10UF 
0603LF 
E15431-001 2 X6S 
20% 
10UF 
1 C3A4 
E15431-001 
0603LF 
C3B1 
10UF 
1
0603LF 
X6S 2
20% 
E15431-001 E15431-001 
C3A7 1
0603LF 
2
10UF 
X6S 
20% 
E15431-001 
10UF 
0603LF 
X6S 2
1 C3A3 
20% 
FM_PVPP_PVDDQ_CPU1_EN_KLM 
VR_VB_PVPP_KLM 
PWRGD_PVPP_KLM_R 
VR_PVPP_KLM_BOOT 
VR_FET_SW_P12V_STBY_PVPP_KLM 
VR_COMP_RC_PVPP_KLM 
VR_COMP_PVPP_KLM_3 
VR_PVPP_KLM_BOOT_R 
VR_PVPP_KLM_PHASE 
FM_PVPP_CPU1_EN 
PWRGD_PVPP_KLM 
VR_PVPP_KLM_SNUB 
0402LF 
A36096-075 
0402 
1/16W 
0.0 
G21497-005 
AGND_PVPP_KLM 
2
0402 
CHIP 
VR_FB_PVPP_KLM 
R4B4 
1/16W 
1% 
6.19K 1
G21796-161 
C95333-006 
X6S 2
G22026-003 22
1 1
C3B3 
330UF 
20% 
6.3V 4V 
20% 
220UF 
C6L8 
POSCAP 
7343LF 
0805 
TP FAB1 CHANGE RES PACKAGE TO 0603 
TP FAB3 CHANGE CAP 0823 
191 233 
190 
GROUP=PWR_MLCC_CAP
GROUP=PWR_MLCC_CAP GROUP=PWR_BULK_CAP 
GROUP=PWR_MLCC_CAP 
GROUP=PWR_MLCC_CAP 
GROUP=PWR_MLCC_CAP 
GROUP=PWR_MLCC_CAP 
GROUP=PWR_MLCC_CAP 
GROUP=PWR_MLCC_CAP 
GROUP=PWR_MLCC_CAP 
GROUP=PWR_MLCC_CAP 
GROUP=PWR_MLCC_CAP 
GROUP=PWR_MLCC_CAP 
GROUP=PWR_MLCC_CAP 
GROUP=PWR_MLCC_CAP 
4V 
GROUP=PWR_BULK_CAP 
NEW_VALUE=3.9K 
CONFIG=64.39015.6DL 
CONFIG=078.47521.08BD 
0805 
X6S 
16V 
20% 
22UF 22UF 
16V 
20% 
0805 
X6S 
4V 4V 4V 4V 4V 4V 4V 4V 4V 4V 4V 
VR_PVPP_KLM_ISET 
SC22U16V5MX-4-GP 
SC22U16V5MX-4-GP 
VR_PVPP_KLM_SS 
VR_COMP_PVPP_KLM 
VSENSE_PVPP_KLM 
BOM_COST: PVPP_KLM_VR 
ROOM = PVPP_KLM_VR 
PUT TOGETHER 
21
21
DO NOT SCALE DRAWING SHEET 
B
AA
B
B
SIZE 
SCALE: 
234
1234
DEPARTMENT CODE 
1
DOCUMENT NUMBER REV 
PVPP_KLM 
PVPP_KLM 
OUT 
P12V_STBY 
P3V3_STBY 
IN 
1
1 2
2
12A OC 
6.25MS (0.4V/MS) 
234 OF 270 
Wed Feb 08 16:35:33 2017 
PG 
PGND<0> PGND<1> PGND<2> PGND<3> PGND<4> PGND<5> PGND<6> 
PGND<8> 
PGND<7> 
PGND<9> 
PGND<10> PGND<11> PGND<12> PGND<13> 
GND AGND 
EN 
SS 
ISET 
OTS 
VIN<6> VIN<7> 
VCC 
VIN<1> 
VIN<5> 
VIN<4> 
VIN<3> 
VIN<2> 
VIN<0> 
VB 
COMP 
FB 
VSWH<1> 
VSWH<0> 
VSW 
VSWH<2> VSWH<3> VSWH<4> VSWH<5> 
VSWH<6> 
BST 
VSWH<7> 
IOUT DI/DT = 21.5A/US 
TP FAB1 CHANGE ONE 47UF CPA TO TWO 22UF CAPS 0107 
VOUT = 2.5V 
IOUT STEP = 5.3A 
DC TOL = +/-1.5% 
IOUT PK = 10.1A (INCLUDED CPU PVPP) IOUT TDC = 7.21A (INCLUDED CPU PVPP) AC & RIPPLE TOL = +3.5%, -7.3% 
TP FAB1 CHANGE RES 0531 
TP FAB1 CHANGE CAP 0422 
RIPPLE GUIDELINE = +/- 1.0% 
CAPS TO BE PLACED BETWEEN DIMMS 
SW FREQ =  500KHZ 
POINT ONLY TOP TO L2 
TOP LAYER 
CONNECT AT SINGLE 
COMPENSATION TYPE III 
PLACE ON 
VPP KLM VR 
NCP3232L 
SPOF 
WIWYNN CORPORATION 
SPOF 



VR_PVNN_PCH_AIREF1 
ISENSE_PVNN_PCH_PH1_IMON 
A_TSENSE_PVNN_PCH_TMON 
6
1/16W 
0402 
H89187-001 
0.1% 
G85996-004 
RF24 
R8W2 
1.00K 1
IC 
0402V 
SC22P50V2JN-4GP 
220PF 10% 
0.1UF 
G21796-160 
CHIP 
0402V 
C8A3 
100.0K 
1% 
R8A4 
16V 
VR_PVNN_PCH_VINSEN 
10% 
X7R 
0402 
1
1/16W 
1% 
R2L10 
G21796-250 
PWRGD_PVNN_P1V05_PCH 
100.0K 
1
22.1 
A36096-050 
CF24 
R2L9 
1
2
1/16W 
1% 
0402 
CHIP 
1% 
2
X7R 
1/16W 
C4W4 
G21796-180 
0402 
R2L25 
1% 
1/16W 
G21796-010 
CHIP 
1/16W 
1% 
0402 
G21796-010 
100.0K 
CHIP 
R2L26 
0402 
12 
0402 
CHIP 
2.26K 
R8A2 
6.3V 
10% 
2
1.0UF 
X6S 
1
2 X7R 
0402V 
1 C8A8 
0.1UF 
A36096-030 
10% 
16V 
2
CHIP 
1/16W 
1.0% 
R2L24 
1
G21796-026 
R8A6 
1.00K 
1% 
1/16W 
1
2 CHIP 
0402 
X6S 
10% 
1.0UF 
6.3V 
D97712-004 
1
2
C2L8 
1 220PF 
50V 
A36096-050 
0402LF 
X7R 
2
C2L2 
2
G22026-041 
0603 
CHIP 
1% 10.0 
1
1/10W 
R2L8 
G21497-005 
5% 
0.0 
R2L14 
1
2
0402 
CHIP 
1/16W 2
CHIP 
1.5K 1
2
G21796-003 
A36096-030 
0402V 
C2L11 
0.1UF 
16V 
10% 
1
2 X7R 
C8A2 1 220PF 
0402LF 
50V X7R 
10% 
2
R8A1 
2
1% 10.0 
1/16W 
1
G21796-066 
0402 
CHIP 
R8A5 
1.00K 
1/16W 
1% 
G21796-026 
X7R 
A36096-046 
0402LF 
1 1000PF 
50V 
10% 
2
C8A9 
1/16W 
2
5% 0.0 
1
CHIP 0402 
R2L17 
0402 
EMPTY 2
R8A7 
100.0K 
1% 
1
G21796-010 
1
14 
18 
31 
3
17 
21 
EU8A1 
10 
39 
15 
19 
28 
8
16 
37 
20 
29 
27 
30 
7
2
4
5
24 
23 
13 
32 
41 
9
11 
40 
22 
38 
35 
CHIP 
1/16W 0.1% 
G85996-004 
A36096-050 
20402LF 
1
10% 
C4W3 
220PF 
50V X7R 
1
50V 
2
0402 
CHIP 
1% 
G21796-026 
R8W3 
1/16W 
0402 
G21796-026 
CHIP 
1.00K 
1% 
2
1
CHIP 2
R8W8 
1.00K 
1/16W 
1% 
1
VR_P1V05_PCH_BIREF1 
ISENSE_P1V05_PCH_STBY_PH1_IMON 
A_TSENSE_P1V05_PCH_STBY_TMON 
PU_PVNN_PCH_VCLK 
VR_PVNN_PCH_AVSP 
VSENSE_PVNN_PCH_STBY_AVSN 
VR_P1V05_PCH_STBY_AVSP 
VSENSE_P1V05_PCH_STBY_AVSN 
SMB_VR_STBY_LVC3_SCL 
SMB_VR_STBY_LVC3_SDA 
VR_PVNN_PCH_VREN 
VR_PVNN_P1V05_PCH_VD12 
PU_PVNN_PCH_VDIO 
PU_VR_PVNN_PCH_FAULT1 
IRQ_PVNN_PCH_VRHOT_N 
VR_PVNN_PCH_PWM1 
VR_P1V05_PCH_STBY_PWM1 
PWRGD_PVNN_PCH_R 
VSENSE_P1V05_PCH_STBY_AVSP 
VSENSE_PVNN_PCH_STBY_AVSP 
A36096-050 
0402LF 
CHIP 
G21796-082 
1.0% 
1/16W 
0402 
R2L16 
PU_PVNN_PCH_PINALRT_N 
PWRGD_P1V8_PCH_STBY 
VR_PVNN_PCH_VINSEN 
0402V 
D97712-004 
0402 
2 EMPTY 
G21796-311 
0402 
C8A7 
VR_PVNN_P1V05_PCH_VD12 
VID_PCH_CORE_PVNN_AUX_VID_0 
VID_PCH_CORE_PVNN_AUX_VID_1 
G21796-026 
CF23 
0402 1.0K 
RF23 
1/16W 
G21497-005 
4.02K 2.67K 
33 
36 
26 
25 
VR_FET_SW_P12V_STBY_PVDDQ_DEF 
1/16W 
10% 
1/16W 
0402 A36096-030 
SC22P50V2JN-4GP 
34 
1.0K 
CHIP 
TP FAB1 CHANGE RES R2L9 AND NOPOP R8A2 0408 
TP FAB3 CHANGE R2L9 AND POP R8A2 
TP FAB1 CHANGE R2L9 RES 0523 
TP FAB3 CHANGE CAP 0912 
236 
236 
236 
235 
190 
236 
236 
236 
236 
236 
138 159 193 194 201 206 211 213 
215 218 223 226 
235 236 
236 
236 
236 
237 
235 
235 
119 
119 
0402 
50V 
NPO 
GROUP=POWER_FAIR 
50V 
GROUP=POWER_FAIR 
22PF 
0402 
5% 
NPO 
GROUP=POWER_FAIR 
5% 
22PF 
GROUP=POWER_FAIR 
VR_PVNN_PCH_XADDR1 
VR_PVNN_PCH_VDD VR_PVNN_PCH_XADDR2 
DESIGN NOTE: 
DESIGN NOTE: 
SW FREQ: 833KHZ SW FREQ: 833KHZ 
PVNN_PCH SPEC: 
VOUT=0.85V TO 1.0V 
TDC=18A 
STEP=TBD 
DC TOL= +/-1.5% 
AC TOL + RIPPLE=+/-3.0% 
STEP RATE=TBDA/US 
PK=20.5A 
AC TOL + RIPPLE=+/-3.0% 
TDC=12A 
DC TOL= +/-1.5% 
PK=15A 
P1V05_PCH SPEC: 
VOUT=1.05V 
STEP=TBD 
STEP RATE=TBDA/US 
21
21
21
1
2
1
1
2
1
22
1
2
21
DO NOT SCALE DRAWING 
INFINEON:NOPOP 
CF23&CF24 
RF23&RF24 
FAIRCHILD:POP 
SHEET 
B
AA
B
B
SIZE 
SCALE: 
234
1234
DEPARTMENT CODE 
1
DOCUMENT NUMBER REV 
IN 
IN 
IN 
IN 
IN 
IN 
IN 
OUT 
BI 
OUT 
OUT 
IN 
IN 
IN 
IN 
IN 
OUT 
P3V3_STBY 
IN 
IN 
IN 
OUT 
OUT 
P3V3_STBY 
235 OF 270 
Wed Feb 08 16:35:33 2017 
AVID1 
OUTPUT VOLTAGE AVID 
AVID0 
0.950 V 
1.000 V 
0.850 V 
OUTPUT VOLTAGE 
0.900 V 
1
00
0 1
0
1
1
PXE1110C 
AVRRDY 
PINALRT_N 
THPAD 
BPWM1 
APWM1 
SDA 
SCL 
VCLK 
VDIO 
RESET_N 
XADDR1 
XADDR2 
ATSEN 
AISEN1 AIREF1 
VDD 
BTSEN 
BISEN1 BIREF1 
DNC<0> DNC<1> DNC<2> 
DNC<4> 
GND<0> GND<1> 
VRHOT_N 
VALRT_N 
AVSEN 
AVREF 
BVSEN 
BVREF 
VINSEN IINSEN 
VD12 
DNC<3> 
MP0 
MP1 MP2 MP3 MP4 
AVREN 
TP FAB1 DELETE RES 0203 
TP FAB1 CO-LAY WITH 
TP FAB1 DELETE RES 0203 
TP FAB1 DEL RES 0314 
TP FAB1 CO-LAY WITH FAIRCHILD PARTS 1203 
FAIRCHILD PARTS 1203 
TP FAB1 POP RES 0523 
TP FAB1 SWAP AVID1 AND AVID0 0203 
TP FAB1 NC 0321 
TP FAB1 ADD RES 0317 
TP FAB1 NC 0321 
TP FAB1 DEL NETS 0309 
TP FAB1 ADD CAP 0218 
TP FAB1 ADD RES 0218 
TP FAB1 ADD RES 0218 
TP FAB1 NC 0321 
VERIFY 
TP FAB1 ADD CAP 0218 
TP FAB1 NC 0321 
SMBUS ADDRESS: 0XD0 
PVNN P1V05 PCH STBY VR (1 OF 2) 
ROOM=PVNN_PCH_STBY WIWYNN CORPORATION 



VR_P1V05_PCH_STBY_PH1_SW_RC 
CHIP 
1/16W 
VR_PVNN_PCH_PH1_PHASE_SW_RC 
1/16W 
CHIP 
VR_P1V05_PCH_STBY_PH1_PHASE 
A36096-030 
0402V D97712-011 
0402 
X6S 
C95333-007 
C95333-007 
0805 
VR_FET_SW_P12V_STBY_PVDDQ_DEF 
0.220UF 
C7A43 
C95333-007 
VR_FET_SW_P12V_STBY_PVDDQ_DEF 
VR_PVNN_PCH_PWM1 
10% 
A36096-104 
C7A40 
0.1UF C7A10 
VR_P1V05_PCH_STBY_PH1_BOOT 
G22178-002 
1R3F-GP 
CT66 
0402 
VR_PVNN_PCH_PH1_BOOT_R 
TP_PVNN_PCH_GL_0 
TP_PVNN_PCH_GL_1 
A_TSENSE_PVNN_PCH_TMON 
VR_PVNN_PCH_STBY_OCSET 
ISENSE_PVNN_PCH_PH1_IMON 
TP_P1V05_PCH_GL_1 
VR_P1V05_PCH_STBY_PH1_BOOT_R 
41 
A_TSENSE_P1V05_PCH_STBY_TMON 
37 VR_P1V05_PCH_STBY_OCSET 
1000PF 
50V 
10% 
X7R 
A36096-046 
0402LF 
VR_P1V05_PCH_STBY_PH1_PHASE_SW 
39 
C3L8 
IND-300NH-20-GP 
L7A4 
L7A2 
IND-300NH-20-GP 
0.22UF 
16V 
2 X7R 
10% 
A36096-155 
C3L29 
VR_P1V05_PCH_STBY_PH1_VCIN 
0402 5% 
G21497-005 
1 2
0.0 
R3L4 
C7A14 C22W22 
1/16W 
100.0 1% 0402 
G21796-017 
CHIP R7A13 
R7A19 
G21796-066 
1% 
1
1/16W 
2
G21497-005 
0402 
A36096-046 
VSENSE_P1V05_PCH_STBY_AVSN 
VSENSE_P1V05_PCH_STBY_AVSP 
TP_P1V05_PCH_GL_0 
VSENSE_PVNN_PCH_STBY_QAT 
VR_PVNN_PCH_PH1_PHASE 
VR_PVNN_PCH_PH1_BOOT 
VR_PVNN_PCH_AIREF1 
VR_P1V05_PCH_BIREF1 
VSENSE_PVNN_PCH_STBY_FPK 
VR_P1V05_PCH_STBY_PWM1 
R7A14 
G21796-066 
2
10.0 1% 
1/16W 0402 
1
10.0 
C95333-002 
20% 
4V 
0805LF 
X6S 
22UF 
ALUM 
2V 
699013-031 
SM 
20% 
470UF 
C2L25 
ALUM 
C8A15 
699013-031 
20% 
470UF 
SM 
2V 
ALUM 
SM 
2V 
699013-031 
C2L46 
2
699013-031 
SM 
699013-031
20% 
1
2
SM 
ALUM 
2V 
470UF
C7A27
699013-031 
SM 
ALUM 
2V 
20% 
470UF 
C3L21 1
2
699013-031 
ALUM 
C3L20 
SM 
470UF 
1
2
20% 
2V 699013-031 
ALUM 
C3L18 
470UF 
SM 
2
20% 
2V 
1
R8B12 
5% 
2
0.0 
1
0402 
1/16W 
G21796-017 
1/16W 
1% 
EMPTY 
100.0 
R8B15 
1
0402 
2
0402 
G21497-005 
5% 
2
1/16W 
1
0.0 
R8B14 
X6S 
0805LF 
1
0402 
1 C7A41 
D97712-011 
X6S 
10% 
16V 
1.0UF 
2
0402 
116V 
10% 
X7R 
2
1
0.220UF 
A36096-104 
C7A44 
16V 
10% 
X7R 
0402 
1
2
C7A9 
1.0UF 
16V 
1
2
10% 
X6S C95333-007 
10% 
C3L10 
2
0805 
10UF 
16V 
X6S 
1
16V 
10UF 
C3L7 
2
1
X6S 
10% 
1
10% 
C3L9 
10UF 
16V 
0805 
2
C95333-007 
0805 
X6S 2
1
16V 
10UF 
10% 
1 C3L11 
X6S 
16V 
0805 
10UF 
2
10% 
C95333-007 
X6S 
16V 
10% 
0805 
10UF 
C3L12 1
2
1.0UF 
D97712-011 2
1 C7A7 
X6S 
16V 
10% 
16V 
2
0402 
X7R 
1
C7A39 
0.1UF 1
A36096-030 
0402V 
X7R 
16V 
10% 
2
1 1.0UF 
0402 
C7A6 
D97712-011 
16V 
10% 
X6S 
2
2
C7A8 1
5.0% 
CHIP 1/10W 
0603 0
RT46 
CHIP 
5.0% 
0603 
G22178-002 
1/10W 
0
RT44 
X7R 
50V 
1000PF 
CT68 
0402LFX7R 
1000PF 
50V 
CT65 
CT64 
0402LF 
X7R 
10% 
50V 
1000PF 
CT69 
10% 
X7R 
A36096-030 
0402V 
16V 
0.1UF 
0.1UF 
A36096-030 
X7R 
10% 
CT67 16V 
0402V 
0402 
G21796-187 
EMPTY 
1/16W 
68.1K 
R3L14 
1% 
G21796-187 
0402 
1% 
68.1K 
R3L15 
H73684-001 
36 
31 
3
4
EU7A2 
40 
35 
2
10 
5
39 
34 
32 
6
33 
1
25 
30 
IC 
7
38 
32 
33 
H73684-001 
4
41 36 
34 
10 
2
40 
38 
IC 
EU7A3 
30 
25 
3
1
35 
6
7
5
37 
31 
VR_PVNN_PCH_PH1_PHASE_SW 
10% 
2 ALUM 
470UF 
0402LF 
10% 
20% 
20% 
ISENSE_P1V05_PCH_STBY_PH1_IMON 
C7A30 
1
470UF 
C3L19 
1R3F-GP 
RT43 
22UF 
C7A42 
RT45 A36096-046 
C95333-002 
2V 
20% 
2
1
A36096-046 
EMPTY 
1/16W 
R7A18 
0.0 
G21497-005 
5% 
1/16W CHIP 0402 
VSENSE_PVNN_PCH_STBY_AVSN 
VSENSE_PVNN_PCH_STBY_AVSP 
C22W25 C22W27 C22W26 C22W23 C22W24 C7A13 
VR_FET_SW_P12V_STBY_PVDDQ_DEF
5% 
R3L1 
2
0.0 
1
G21497-005 
0402 
VR_PVNN_PCH_PH1_VCIN 
16V 
0.22UF 
X7R 
C3L1 
10% 
0402 
A36096-155 
TP FAB1 CHANGE TO 0 OHM 0107 
TP FAB1 CHANGE TO 0 OHM 0107 
235 
235 
235 
235 
235 
235 
123 
235 
235 
123 
235 
235 
235 
235 
IRMS=66A@DELTA_T<40C 
DCR=0.17MOHM ISAT=33A@25C 
300NH 
IRMS=66A@DELTA_T<40C 
DCR=0.17MOHM 
ISAT=33A@25C 
300NH 
0402 
10V 
10% 
1UF 
16V 
22UF 
20% 
16V 
X6S 
0805 0805 
20% 
0805 
X6S 
16V 
0805 
X6S 
16V 16V 
X6S 
0805 
16V 
X6S 
0805 
20% 20% 
22UF 
20% 
22UF 
20% 
22UF 22UF 
CHIP 
NOPOP 
CHIP 
CHIP 
CHIP 
NOPOP 
1% 
1 OHM 
1/10W 
1% 
1 OHM 
1/10W 
0603 
0603 
0805 
X6S X6S 
16V 
20% 
22UF 22UF 
20% 
16V 
0805 
X6S 
22UF 
1UF 
10% 
10V 
0402 
TP FAB1 ADD NET NAME 12/04 
TP FAB1 ADD NET NAME 12/04 
SC1U10V2KX-4-GP 
SC22U16V5MX-4-GP 
SC22U16V5MX-4-GP 
SC22U16V5MX-4-GP 
SC22U16V5MX-4-GP 
SC22U16V5MX-4-GP 
SC22U16V5MX-4-GP 
SC22U16V5MX-4-GP 
SC22U16V5MX-4-GP 
SC1U10V2KX-4-GP 
4V 
ROUTE AS DIFF PAIR 
5MIL SPACING 
10MIL WIDTH 
PLACE NEAR PCH EDGE 
PUT TOGETHER PUT TOGETHER 
NOPOP 
21
1 2
21
2
1
2
1
2
21
1 2
1
2
2
1
1
2
2
1
1
2
2
1
1
NOPOP 
1
2
21
DO NOT SCALE DRAWING 
TP FAB1 CO-LAY WITH TI PARTS 11/16 
TP FAB1 CO-LAY WITH TI PARTS 11/16 
TP FAB1 CO-LAY WITH TI PARTS 11/16 
TP FAB1 CO-LAY WITH TI PARTS 11/16 
TP FAB1 CO-LAY WITH TI PARTS 11/16 
TP FAB1 CO-LAY WITH TI PARTS 11/16 
SHEET 
B
AA
B
B
SIZE 
SCALE: 
234
1234
DEPARTMENT CODE 
1
DOCUMENT NUMBER REV 
OUT 
OUT 
PVNN_PCH_STBY 
IN 
IN 
PVNN_PCH_STBY 
IN 
IN 
P1V05_PCH_STBY 
OUT 
OUT 
OUT 
P1V05_PCH_STBY
P5V_STBY 
IN 
OUT 
IN 
OUT 
P5V_STBY 
OUT 
2 1
2 1
1 2
2
2
2
2
1
1
1
1
2 1
1 2
2
2
1
1
2 1
P1V05_PCH_STBY_VOLTAGE SENSE 
PVNN_PCH_STBY_VOLTAGE SENSE 
PCH SIDE VR CONTROLLER SIDE 
236 OF 270 
Wed Feb 08 16:35:33 2017 
1
1
1
1
GL<1> 
GL<0> 
PGND<1> 
PGND<0> 
PGND<2> LGND 
VOS 
EN 
VDRV 
VCC 
VIN<0> VIN<1> 
PHASE 
REFIN 
BOOST 
PWM 
SW 
NC 
IOUT 
OCSET 
TOUT_FLT 
GL<1> 
GL<0> 
PGND<1> 
PGND<0> 
PGND<2> LGND 
VOS 
EN 
VDRV 
VCC 
VIN<0> 
VIN<1> 
PHASE 
REFIN 
BOOST 
PWM 
SW 
NC 
IOUT 
OCSET 
TOUT_FLT 
TP FAB1 DEL NET 0309 
TDA21460 
TDA21460 
TP FAB1 CHANGE RES TO 1 OHM 0603 0107 
TP FAB1 CHANGE PN 0310 
TP FAB1 CHANGE PN 0310 
TP FAB1 CHANGE L7A4 PN 0122 
TP FAB1 CHANGE L7A2 PN 0122 
TP FAB1 DEL NET 0309 
TP FAB1 CHANGE RES TO 1 OHM 0603 0107 
TP FAB1 CHANGE ONE 100UF CPA TO FOUR 22UF CAPS 0107
NOPOP 
NOPOP 
NOPOP 
NOPOP 
PVNN P1V05 PCH STBY VR (2 OF 2) 
SPOF 
PLACE ON TOP 
PLACE ON TOP 
ROOM= PVNN_PCH_STBY 
ROOM= P1V05_PCH_STBY_VR 
WIWYNN CORPORATION 
SPOF 
SPOF 



VOLTAGE 
VR_P1V8_PCH_STBY_FB 
PWRGD_P1V8_PCH_STBY PWRGD_P1V8_PCH_STBY_R 
1/16W 
22.1 
CHIP 0402 
1.0% 
1
R8A11 
2
G21796-250 
6
7
8
9
10 
H65765-001 
IC 
EU8A2 
4
3
2
1
5
11 
2
CHIP 
0402 
1/16W 
1.0% 
1
R2L20 
63.4K 
G21796-327 
0402 
2
1
1% 
1/16W 
49.9K 
R2L19 
G21796-048 
CHIP 
2 X6S 
0805 
C2L32 
47UF 
20% 
4V 
1
C95333-006
0805 
47UF 
X6S 
4V 
20% 
2
1 C8A12 
C95333-006 
PWRGD_P3V3_STBY 
A36096-046 
1000PF 
C8A10 
EMPTY 
10% 
50V 
1
2
0402LF 
1
2 X7R 
50V 
10% 
0402LF 
1000PF 
A36096-046 
C8A11 
0603LF 
2
1
X7R 
25V 
10% 
0.1UF 
C8A4 
602433-020 
CHIP 2
0402 
1
1% 
1/16W 
5.11K 
G21796-140 
R8A10 
2 0603 
X6S 
1 C8A6 
10UF 
20% 
6.3V 
0603 
G22026-030 
2
1
1/10W 
CHIP 
1% 
475.0 
R8A12 
0805 
22UF 
2
20% 
6.3V 
X6S 
C8A14 1
C95333-008 
0805 
C95333-008 2
1 C2L45 
22UF 
X6S 
6.3V 
20% 
235 
240 101 189 191 196 239 
E15431-002 
DESIGN NOTE: 
DESIGN NOTE: 
DO NOT SCALE DRAWING SHEET 
B
AA
B
B
SIZE 
SCALE: 
234
1234
DEPARTMENT CODE 
1
DOCUMENT NUMBER REV 
P3V3_STBY 
P3V3_STBY 
IN 
P1V8_PCH_STBY
OUT 
237 OF 270 
Wed Feb 08 16:35:34 2017 
VDD PGOOD 
GND 
ADJ_NC 
VOUT<2> 
VOUT<1> 
VOUT<0> 
EN 
VIN<2> 
VIN<1> 
VIN<0> 
RIPPLE TOLERANCE = +- 1 % 
STEP LOAD = 0.0035A 
SLEW RATE = 8A/US 
DC+AC+RIPPLE = +-5 % 
STEP RATE = TBDA/US 
VOUT = 1.8 V 
P1V8_PCH_STBY VR SPECIFICATION 
DC TOLERANCE = +- 1 % 
AC TOLERANCE = +- 3.0 % 
IMAX =1.0 A 
TDC = 0.6 A 
P1V8 PCH STBY VR 
49.9K 
R2 
ROOM=P1V8_PCH_STBY_VR 
BOM COST=P1V8_PCH_STBY_VR 
PCH 
WELLSBURG (INTERPOSER) 
LEWISBURG 
R1 
43.2K 
63.4K 
49.9K 
R2 
VOLTAGE SETTING 
1.5V 
1.8V 
R1 
RT9059 
WIWYNN CORPORATION 



20% 
X6S 
E15431-004 
C9F4 
22UF 
0603V 
1
4V 
X6S 
20% 
0805LF 
C95333-002 2
C9W16 
22.0UF 
4V 
20% 
6.3V 
4K42R2F-GP 
R9F6 
C9W14 
VR_P1V15_BMC_STBY_FB 
0402LF 
6.3V 
20% 
H65765-001 
1
2
E15431-002 
PWRGD_P1V15_BMC_STBY 
0402 
10UF 
X6S 
1
2
0603 
C9E10 
E15431-002 
10UF 
0603 
1
X6S 
E15431-002 
C9F3 
10UF 
6.3V 
20% 
X6S 
1
2
PWRGD_P1V2_BMC_STBY 
0603 
2
7
3
CHIP 
R9F8 
1
A36096-046 2
C9F8 
1000PF 
X7R 
10% 
2
1
R9F13 
10.0K 
1% 
1/16W 
CHIP 
G21796-016 
0402 
1.0UF 
C9E11 
16V 
1
0402 
D97712-011 2 X6S 
10% 
9
8
10 
EU9F1 
5
1
2
IC 
4
11 
6
1
G21796-250 
R9F11 
2
1.0% 22.1 
1/16W 
50V 
C9F9 
10% 
2
1
1000PF 
0402LF 
EMPTY 
A36096-046 
PWRGD_P1V15_BMC_STBY_R 
TP FAB3 RESERVE CAP 1031 
TP FAB3 RESERVE CAP 1031 
191 
239 
NOPOP 
4.42KOHM 
NOPOP 
1/16W 
0402 
1% 
0402 
1% 
1
10.0K 
G21796-016 
CHIP 
2
1/16W 
NEXT TO INPUT PIN 
MUST PLACE 
DESIGN NOTE: 
CAD NOTE: 
DO NOT SCALE DRAWING 
50V 
TP FAB1 CHANGE POWER RAIL FOR BMC 1120 
TP FAB1 CHANGE R9F6 FOR 1.15V POWER RAIL 1123 
P1V15_AUX_BMC 
SHEET 
B
AA
B
B
SIZE 
SCALE: 
234
1234
DEPARTMENT CODE 
1
DOCUMENT NUMBER REV 
P3V3_STBY 
P3V3_STBY 
OUT 
P3V3_STBY 
IN 
2 1
238 OF 270 
Wed Feb 08 16:35:34 2017 
VDD PGOOD 
GND 
ADJ_NC 
VOUT<2> 
VOUT<1> 
VOUT<0> 
EN 
VIN<2> 
VIN<1> 
VIN<0> 
VOUT=1.15V 
IOUT=700MA 
P1V15 BMC STBY VR 
RT9059 
WIWYNN CORPORATION 



50V 
50V 
10UF 
10UF 
C1T15 1
2 E15431-002 
0603 
PWRGD_P1V2_BMC_STBY 
2 X6S 
1
4V 
20% 
CHIP 
A36096-030 
16V 
C9W5 
0.1UF 
6.3V 
10UF 
C1W7 
E15431-002 
X6S 
20% 
0603 
2
6.3V 
1 C9W17 
2
1
0603 
10UF 
C1T7 
20% 
6.3V 
PWRGD_P3V3_STBY 
PWRGD_P1V2_BMC_STBY_R 
PWRGD_P2V5_BMC_STBY_R 
0402LF 
EMPTY 
10% 
50V 
C9W6 
A36096-046 
1000PF 
C9W10 
X7R 
0402LF 
X6S 
1/16W 
CHIP 
1% 
R9W12 
10.0K 
R1W9 
1.0% 
CHIP IC 
CHIP 
1.0% 
1/16W 
22.1 
0402 
G21796-250 
R1T9 
21
1
2
0402V 
H65765-001 
1
5
2
39
8
7
10 
6
EU9F2 
IC 
4
11 
1/16W 
1% 
10.0K 
R9F12 
1
0402 
G21796-016 
CHIP 2
A36096-046 
2
1000PF 
10% 
X7R 
C9F10 1
1
2EMPTY 
1000PF 
C9F6 
10% 
50V 
X6S 
20% 
6.3V 
CHIP 
1/16W 
1% 
1 10.0K 
R9W32 
2
1/16W 
0402 
R9F32 
10.0K 
1% 2
1
10UF 
C1W15 
1000PF 
10% 
G21796-016 
VR_P1V2_BMC_STBY_FB 
22.1 
1/16W 
5K1R2F-2-GP 
R9F31 
22.0UF 
4V 2
20% 
X6S 
1
0603V 
E15431-004 
4V 
22UF 
6.3V 
20% 
VR_P2V5_BMC_STBY_FB 
R9W31 
21K5R2F-GP 
A36096-046 
PWRGD_P2V5_BMC_STBY 
0603 
X6S 
20% C9F5 
X7R 
10% 
0402LF 
C9W19 
C9F13 
22UF 
C95333-002 
0805LF 
0402 
0402 
H65765-001 
EU25F2 
C9W13 
0805LF 
PWRGD_P2V5_BMC_STBY 
0603 
E15431-002 
E15431-002 
0.1UF 
16V 
A36096-046 
0402LF 
X6S 
E15431-002 
0402 G21796-250 
10% 
X7R 
0402V 
A36096-030 
20% 
X6S 
C95333-002 
TP FAB3 DELETE C9W22 1101 
TP FAB3 RESERVE C9W22 1031 TP FAB3 RESERVE C9W20 1031 
TP FAB3 DELETE C9W20 1101 
TP FAB3 RESERVE CAP 1031 
TP FAB3 RESERVE CAP 1031 
TP FAB1 CHANGE POWER RAIL 1120 
238 
240 101 189 191 
196 237 
239 
239 
NOPOP 
5.1KOHM 
1/16W 
0402 
1/16W 
0402 
21.5KOHM 
1% 
1% 
NOPOP 
G21796-016 
G21796-016 
NEXT TO INPUT PIN 
NEXT TO INPUT PIN 
MUST PLACE 
MUST PLACE 
DESIGN NOTE: 
DESIGN NOTE: 
CAD NOTE: 
CAD NOTE: 
7
8
9
6
1
2
3
11 
4
10 5
11
2
2
1
1
2
1
1
1 2
2
2
1
2
2
DO NOT SCALE DRAWING 
P1V2_AUX_BMC 
P2V5_AUX_BMC 
SHEET 
B
AA
B
B
SIZE 
SCALE: 
234
1234
DEPARTMENT CODE 
1
DOCUMENT NUMBER REV 
IN 
P3V3_STBY 
OUT 
P3V3_STBY 
P3V3_STBY 
OUT 
P3V3_STBY 
IN 
2 1
1 2
239 OF 270 
Wed Feb 08 16:35:34 2017 
VDD PGOOD 
GND 
ADJ_NC 
VOUT<2> 
VOUT<1> 
VOUT<0> 
EN 
VIN<2> 
VIN<1> 
VIN<0> 
VDD PGOOD 
GND 
ADJ_NC 
VOUT<2> 
VOUT<1> 
VOUT<0> 
EN 
VIN<2> 
VIN<1> 
VIN<0> 
IOUT=0.2A 
TP FAB1 CHANGE PWRGD FROM P2V5 1204 
TP FAB1 CHANGE RES 0429 
TP FAB1 R9W31 CHANGE TO 21.5K 1123 
TP FAB1 ADD P2V5 FOR DDR4 1120 
TP FAB1 CHANGE RES 0429 
TP FAB1 CHANGE VALUE FOR 1.2V 
VOUT=2.5V 
IOUT=0.5A 
VOUT=1.2V 
P1V2 & P2V5 BMC STBY VR 
RT9059 
RT9059 
WIWYNN CORPORATION 



2 1
VOUT=3.3V 
RIPPLE=+-1% 
STEP=6A 
SW FREQ=  500 KHZ 
IOUT DI/DT=1A/US 
AC TOLERANCE & RIPPLE=+/-3.0% 
DC TOLERANCE=+-1.5% 
IMAX= 25.59A 
0402 
AGND_P3V3_STBY 
AGND_P3V3_STBY 
AGND_P3V3_STBY 
AGND_P3V3_STBY 
AGND_P3V3_STBY 
AGND_P3V3_STBY 
VR_P3V3_STBY_PHASE 
C2T9 
VR_P3V3_STBY_BOOT 
A36096-046 
G21796-016 
R8F9 
G21796-048 
0402 
CHIP 
1/16W 
1% 
49.9K 
VR_P3V3_STBY_OCSELECT 
H66262-001 
10 
G21497-005 
C8F14 
2
G85996-004 
0402 
1.0K 
CHIP 
1
0.1% 
1/16W 
R2T4 
SC4D7U16V3KX-GP 
C2R11 
PWRGD_P3V3_STBY_R 
1VR_P3V3_STBY_BOOT_R 
1.0% 0402 
G21796-026 
CHIP 
1/16W 
1% 
1.00K 
R8F5 
R8F1 
10.0K 
1% 
0402 
1
2
1C8E17 
50V 
EMPTY 
0402LF 
X7R 
1000PF 
C8F2 
A36096-046 
1
2 0402LF 
10% 
50V 
1
2
8
IC 
EU8F1 
4
1
2
3
6
7
5
9
11 
13 
CHIP 
G21497-005 
0402 
R8E35 
21
5% 
1/16W 
0.0 
602433-020 
10% 
C8E12 
0.1UF 25V 
0603LF 
X7R 
2
1
2 X6S 
1.0UF 
2 X6S 
0402 
21
R8E38 
G21497-005 
1/16W 
5% 0.0 
10.0K 1
1% 
1/16W 
CHIP 2
R8E34 
0402 
G21796-016 
23.2K 
R8E31 
1
1% 
CHIP 2
G21796-114 
0402 
1/16W 
R8E25 
0.0 
5% 
1/16W G21497-005 
1
CHIP 
0402 
2
5% 
2
R8F11 
CHIP 
1
1/16W 
0402 
0.0 
G21497-005 
2
1
2
1
0402 
2
CHIP 
R8F10 
G21796-250 
22.1 
1/16W 
1
0805 
0402 0.0 
CHIP 
R8F2 
0402 
1% 
100.0K 
1/16W 
EMPTY 
G21796-010 
R8E40 
VSENSE_RGND_P3V3_STBY 
PWRGD_P5V_STBY 
VSENSE_VOUT_P3V3_STBY 
VR_P3V3_STBY_EN 
1C8E10 
C2T6 
22UF 
20% 
6.3V 
C2T7 
22UF 
6.3V C95333-008 
20% 
6.3V 
22UF 
20% 
X6S 
0805 
X6S 
22UF 
D97712-011 
16V 16V 10% 10% 
1206LF 
D38464-005 
C22W12 C8E11 C9F1 C22W11 
VR_FET_SW_P12V_STBY_P3V3_STBY 
C8E14 
PWRGD_P3V3_STBY 
FB9E1 
BLM31SN500SN1L-GP 
4
1
2
IC 
EU8E1 
3
5
VR_P3V3_STBY_LGATE 
VR_P3V3_STBY_UGATE 
H66258-001 
C8F3 
3300PF 
10% 
0402LF 
A36096-091 
EMPTY 
EMPTY 
R8F3 
50V 
0402 
1
2
2
1
G21497-016 
VR_P3V3_STBY_SNUB 
2.2 
5% 
1/16W 
L8F1 
IND-1UH-361-GP 
0805 
C95333-008 C95333-008 
X6S 
C8F8 
10% 
2 EMPTY 
1/16W 
1000PF 
1/16W 
5% 
12 
TP FAB1 CHANGE PN 0310 
TP FAB1 CHANGE SMALL SIZE CHOCK FOR PLACEMENT 0203 
TP FAB1 CHANGE CAP PN TO AVOID ME INTERFERENCE 0203
TP FAB3 CHANGE RES  0823 
241 
101 189 191 
196 237 239 
ESR=35MOHM 
TMAX=105C 
6.3V 
IRP=1.7A 
470UF 
0603 
16V 
10% 
4.7UF 
50OHM@100MHZ 
CHIP 
22UF 
20% 
X6S 
0805 
16V 
22UF 
20% 
X6S 
0805 
16V 16V 
22UF 
X6S 
0805 0805 
X6S 
16V 
20% 
22UF 
20% 
1MA 
DCR=1.6MOHM 
1.0UH 
ISAT=24A@25C 
DCR=4.6MOHM 470UF 
IRP=1.7A 
6.3V 
ESR=35MOHM 
TMAX=105C 
ST470U6D3VDM-7-GP 
VSENSE_P3V3_STBY 
SC22U16V5MX-4-GP 
SC22U16V5MX-4-GP 
SC22U16V5MX-4-GP 
SC22U16V5MX-4-GP 
ST470U6D3VDM-7-GP 
DESIGN NOTE: 
PUT TOGETHER PUT TOGETHER 
10MIL WIDTH 
BOM_COST: P3V3_STBY_VR 
ROOM = P3V3_STBY_VR 
5MIL SPACING 
ROUTE VSENSE_RGND_P3V3_STBY/VSENSE_P3V3_STBY AS DIFF PAIR 
2
1
2
21
2
1
1
2
1
21
DO NOT SCALE DRAWING SHEET 
B
AA
B
B
SIZE 
SCALE: 
234
1234
DEPARTMENT CODE 
1
DOCUMENT NUMBER REV 
P3V3_STBY 
P3V3_STBY 
P12V_STBY 
P3V3_STBY 
OUT 
P5V_STBY 
IN 
2 1
2
1 2
2 1
2
2 1
1
1
2 1
P3V3_STBY _VOLTAGE SENSE 
23.5A OC 
240 OF 270 
Wed Feb 08 16:35:34 2017 
PGND 
VSW BG 
VIN 
TG 
CSD87384M 
VCC 
PGOOD 
EN 
G0 
BOOT 
UGATE 
PHASE 
LGATE 
VOUT 
RGND CS 
GND<1> 
GND<0> 
TP FAB3 CHANGE BEAD 0803 TP FAB1 CHANGE ONE 47UF CPA TO TWO 22UF CAPS 0107 
PLACE ON TOP LAYER 
CONNECT AT SINGLE POINT ONLY TOP TO L2 
P3V3 STBY VR 
RT8240 
SPOF 
WIWYNN CORPORATION 
SPOF 



AGND_P5V_STBY 
CHIP 
0402 
0.022UF 
AGND_P5V_STBY 
AGND_P5V_STBY 
AGND_P5V_STBY 
AGND_P5V_STBY 
5% 
X7R 
1C8E15 
10% 
0402LF 
2
16V 
C8E9 C8E7 SM IND 
0.1% 
1/16W 
CHIP 
0402 
22UF 
C7E11 
10% 
16V 
1206LF 
X6S 
2
1.0UF 
C7E14 
G21497-005 
0.0 VR_P5V_STBY_SS 
VR_P5V_STBY_RC_COMP 
PWRGD_P5V_STBY 
VR_P5V_STBY_VSENSE 
VR_P5V_STBY_BOOT VR_P5V_STBY_VSENSE_R 
VR_P5V_STBY_EN PWRGD_P12V_HSC_DLY 
VR_P5V_STBY_VIN 
VR_FET_SW_P5V_STBY_PVIN 
PWRGD_P5V_STBY_R 
1/16W CHIP 
1 2
R8E33 
1
2
1.0K 
1/16W 
1
G21796-250 
R7E15 
2
0402 
22.1 1.0% 
CHIP 
1
H63269-001 
8
10 
9
6
4
EU7E2 
IC 
15 
2
3
11 
7
14 
13 
12 
5
22 FB SM 
FB7E1 
656554-051 
R8E37 
1/16W 
21
0402 
G21497-005 
0.0 5% 
1
1/16W 
0.0 
G21497-005 
R7E13 
CHIP 
0402 5% 
2
0402LF 
X7R 10% 
1
2200PF 
A36096-075 
50V 
2
C8F1 
1/16W CHIP 
1
24.9K 
G21796-254 
2
R8E39 
0402 
1% 
10% A36096-065 
X7R 50V 
0402LF 
270PF 
1
C8E16 
2
2
1
1/16W 
CHIP 
0402 
1% 
1.37K 
R7E16 
2
1
1% 
10.0K 
R7F1 
0402 
CHIP 
1/16W 
EMPTY 
0402LF 
10% 
50V 
2
1
1000PF 
C8E13 
R7E17 
5% 
1/16W 
1
2
0402 
0.0 
16V 
10% 
0402 
X6S 
1
2
0402 
R7E14 
2 CHIP 
1
1/16W 
1% 
75K 
G21796-224 
1 C7E10 
50V 
1000PF 
2 10% 
X7R 
0402LF 
0.1UF 10% 
602433-020 
1
C8E6 0603LF 2
25V X7R 
2
1 R7E12 
0402 
CHIP 
1% 
1.00K 
1/16W 
1
C7E13 C22W8 C7E12 C22W9 
1 2
2.2UH 
VR_P5V_STBY_PHASE 
L8E1 
E98761-003 
C8E4 R8E18 
TP FAB1 CHANGE PN 0331 
TP FAB1 CHANGE PN 0310 
240 
196 181 
248 
16V 
CHIP 
X6S 
0805 
20% 
X6S 
0805 
16V 
22UF 
20% 
0805 
X6S 
22UF 
16V 
20% 
22UF 22UF 
20% 
16V 
X6S 
0805 
0805 
X6S 
16V 
20% 20% 
22UF 
X6S 
16V 
220UF 
IRP=2400MA 
10V 
TMAX=105C 
ESR=25MOHM 
22UF 
0805 
21
SC22U16V5MX-4-GP 
A36096-073 
SC22U16V5MX-4-GP 
G85996-004 
ST220U10VDM-LGP 
D97712-011 
A36096-046 
VR_P5V_STBY_COMP 
VR_P5V_STBY_RT 
G21796-095 G21796-016 
G21497-005 
A36096-046 
G21796-026 
D38464-005 
SC22U16V5MX-4-GP 
SC22U16V5MX-4-GP 
SC22U16V5MX-4-GP 
SC22U16V5MX-4-GP 
DESIGN NOTE: 
CAD NOTE: 
PUT TOGETHER PUT TOGETHER 
DO NOT SCALE DRAWING 
650KHZ 
5.8MS 
SHEET 
B
AA
B
B
SIZE 
SCALE: 
234
1234
DEPARTMENT CODE 
1
DOCUMENT NUMBER REV 
P5V_STBY 
P12V_STBY 
P5V_STBY 
IN 
OUT 
2
2 1
1 2
1 2
1 2
2
2 1
1
1
241 OF 270 
Wed Feb 08 16:35:35 2017 
PLACE DECOUPLING SAME SIDE 
IMAX = 7.05A 
TDC = 4.33 A 
P5V_STBY VR SPECIFICATION 
DC TOLERANCE = +- 2 % 
AC TOLERANCE = +- 2.5 % 
STEP RATE= TBDA/US 
VIN=FSW=650KHZ 
VOUT = 5.0 V 
AND CLOSE TO IC PINS 
VSENSE 
PH<0> PH<1> 
GND<1> 
THPAD GND<0> 
SS_TR 
RT_CLK 
COMP 
EN 
VIN 
PVIN<0> PVIN<1> PWRGD 
BOOT 
TP FAB1 CHANGE ONE 47UF CPA TO TWO 22UF CAPS 0107 TRUE 
P5V STBY VR 
CONNECT AT SINGLE 
POINT ONLY 
COMPENSATION TYPE II 
SPOF TPS54821 
SPOF 
WIWYNN CORPORATION BOM_COST=P5V_STBY_VR 
ROOM=P5V_STBY_VR 



X6S 
C5G78 
C95333-006 
0805 
20% 
0805 
C5G60 
22.0UF 
4V 
20% 
E15431-004 
C5G55 
22.0UF 
4V E15431-004 
C5G43 
22.0UF 
X6S 
E15431-004 
C95333-006 
C5G62 
22.0UF 
X6S 
E15431-004 
E15431-004 
0603V 
22.0UF 
4V 
0603V 
4V 
C5G69 
22.0UF 
4V E15431-004 
0603V 
C5G47 
X6S 
20% 
C5G49 
47UF 
20% 
4V 
20% 
4V 
22.0UF 22.0UF 22.0UF 22.0UF 
C5G59 C5G63 
20% 
E15431-004 
0603V 
22.0UF 
0603V 
0603V 
4V 
22.0UF 
20% 
C5G42 
0603V 
X6S 
E15431-004 
4V 
20% 
22.0UF 
C5G67 
E15431-004 
20% 
C5G66 
0603V 
X6S 
22.0UF 
4V 
20% 
4V 
0603V 
X6S 
E15431-004 
22.0UF 
C5G65 
20% 
4V 
X6S 
22.0UF 
C5G64 
E15431-004 
0603V 
22.0UF 
C5G76 
X6S 
20% 
4V 4V 
20% 
X6S 
E15431-004 
22.0UF 
C5G75 
0603V 
E15431-004 
C5G74 
X6S 
4V 
20% 
22.0UF 
0603V 
22.0UF 
0603V 
20% 
4V 
X6S 
C5G73 
E15431-004 
X6S 
E15431-004 
0603V 
4V 
20% 
22.0UF 
20% 
X6S 
E15431-004 
0603V 
4V 
C5G61 
22.0UF 
4V 
0603V 
0805 
47UF 
X6S 
20% 
X6S 
22.0UF 
4V 
4V 
C5G72 
22.0UF 
20% 
X6S 
E15431-004 
0603V 
C5G71 
0603V 
E15431-004 
20% 
X6S 
4V 
22.0UF 
X6S 
20% 
E15431-004 
22.0UF 
C5G70 
20% 
X6S 
20% 
4V 
C5G68 
E15431-004 
0603V 
X6S 
0603V 
X6S 
20% 
4V 
C5G48 
20% 
0603V 
X6S X6S 
20% 
4V 
X6S 
20% 
0603V 
E15431-004 
4V 
C5G46 
E15431-004 
C5G58 
0603V 
22.0UF 
X6S 
4V 
20% 
4V 
C5G57 
20% 
22.0UF 
0603V 
E15431-004 
X6S 
0603V 
X6S 
22.0UF 
4V 
20% 
E15431-004 
C5G56 
X6S 
0603V 
20% 
E15431-004 
E15431-004 
0603V 
X6S 
0603V 
0805 
X6S 
C5G22 
X6S 
C5G21 
47UF 
20% 
22.0UF 
4V 
0603V 
X6S 
20% 
C5G41 
C5G54 
4V 
22.0UF 
20% 
X6S 
0603V 
22.0UF 
C5G53 
X6S 
4V 
0603V 
E15431-004 
20% 
E15431-004 
X6S 
0603V 
C5G52 
20% 
4V 
22.0UF 
0603V 
X6S 
E15431-004 
C5G51 
20% 
4V 
22.0UF 
4V 
C5G50 
22.0UF 
20% 
X6S 
0603V 
E15431-004 
X6S 
20% 
C5G45 
E15431-004 E15431-004 E15431-004 
0603V 0603V 
E15431-004 
C5G44 
X6S 
E15431-004 
22.0UF 
4V 
E15431-004 
C5G77 
20% 
C95333-006 
47UF 
C95333-006 
TP FAB3-DVT NOPOP 20161220 TP FAB3-DVT NOPOP 20161220 
BOM_DS=NOPOP BOM_DS=NOPOP 
GROUP=PWR_MLCC_CAP 
GROUP=PWR_MLCC_CAP 
NOPOP 
GROUP=PWR_MLCC_CAP 
BOM_DS=NOPOP BOM_DS=NOPOP BOM_DS=NOPOP BOM_DS=NOPOP BOM_DS=NOPOP BOM_DS=NOPOP BOM_DS=NOPOP BOM_DS=NOPOP BOM_DS=NOPOP 
BOM_DS=NOPOP BOM_DS=NOPOP BOM_DS=NOPOP BOM_DS=NOPOP BOM_DS=NOPOP BOM_DS=NOPOP BOM_DS=NOPOP 
BOM_DS=NOPOP BOM_DS=NOPOP BOM_DS=NOPOP BOM_DS=NOPOP BOM_DS=NOPOP 
GROUP=PWR_MLCC_CAP 
BOM_DS=NOPOP BOM_DS=NOPOP BOM_DS=NOPOP BOM_DS=NOPOP 
BOM_DS=NOPOP BOM_DS=NOPOP BOM_DS=NOPOP BOM_DS=NOPOP BOM_DS=NOPOP BOM_DS=NOPOP BOM_DS=NOPOP BOM_DS=NOPOP BOM_DS=NOPOP 
GROUP=PWR_MLCC_CAP 
GROUP=PWR_MLCC_CAP 
GROUP=PWR_MLCC_CAP 
GROUP=PWR_MLCC_CAP 
GROUP=PWR_MLCC_CAP 
GROUP=PWR_MLCC_CAP
GROUP=PWR_MLCC_CAP GROUP=PWR_MLCC_CAP GROUP=PWR_MLCC_CAP 
GROUP=PWR_MLCC_CAP 
GROUP=PWR_MLCC_CAP GROUP=PWR_MLCC_CAP 
GROUP=PWR_MLCC_CAP
GROUP=PWR_MLCC_CAP 
GROUP=PWR_MLCC_CAP 
GROUP=PWR_MLCC_CAP 
GROUP=PWR_MLCC_CAP 
GROUP=PWR_MLCC_CAP 
GROUP=PWR_MLCC_CAP 
4V 4V 
GROUP=PWR_MLCC_CAP 
GROUP=PWR_MLCC_CAP 
GROUP=PWR_MLCC_CAP 
GROUP=PWR_MLCC_CAP 
GROUP=PWR_MLCC_CAP 
GROUP=PWR_MLCC_CAP 
GROUP=PWR_MLCC_CAP 
GROUP=PWR_MLCC_CAP 
GROUP=PWR_MLCC_CAP 
GROUP=PWR_MLCC_CAP 
GROUP=PWR_MLCC_CAP 
GROUP=PWR_MLCC_CAP 
GROUP=PWR_MLCC_CAP 
GROUP=PWR_MLCC_CAP GROUP=PWR_MLCC_CAP 
GROUP=PWR_MLCC_CAP 
4V 
NOPOP NOPOP NOPOP 
GROUP=PWR_MLCC_CAP 
4V 
2
2
1
1 1
1
2
1
22
11
22
1
2
11
22
11
2
1
22
11
2
1
2
11
2
1
2
1
22
1
2
2
11
22
1
1
22
11
22
1
2
11
22
1
1
2
1
2
2
1
1
22
1
2
11
2
1
2
2
1
2
DO NOT SCALE DRAWING SHEET 
B
AA
B
B
SIZE 
SCALE: 
234
1234
DEPARTMENT CODE 
1
DOCUMENT NUMBER REV 
PVDDQ_ABC 
PVDDQ_DEF 
PVDDQ_DEF 
PVDDQ_ABC PVDDQ_DEF 
PVDDQ_ABC 
242 OF 270 
Wed Feb 08 16:35:35 2017 
TP FAB1 ADD CAP ON DIMM BOTTOM SIDE 1116 
WIWYNN CORPORATION 
ADD DIMM CAP FOR SINGLE SIDE MB (1/2) 



C5G117 
0805 
C95333-006 C95333-006 
0805 
X6S 
20% 20% 
22.0UF 
4V E15431-004 E15431-004 E15431-004 E15431-004 E15431-004 
X6S 
X6S 
X6S 
C5G85 
X6S 
C5G83 
0603V 
22.0UF 
E15431-004 
E15431-004 
0603V 
E15431-004 E15431-004 
X6S 
E15431-004 
X6S 
E15431-004 
X6S 
E15431-004 
0603V 
20% 
0603V 
C5G96 
22.0UF 
20% 
4V 
X6S 
22.0UF 
0603V 
C5G95 
4V 
X6S 
20% 
4V 
20% 
C5G94 
4V 
22.0UF 
C5G93 
0603V 
20% 
4V 
22.0UF 
C5G92 
20% 
4V 
22.0UF 
C5G91 
X6S 
0603V 
20% 
0603V 
X6S 
22.0UF 
C5G90 
4V 
20% 
C5G89 
X6S 
22.0UF 
4V 
0603V 
4V 
X6S 
C5G105 
20% 
22.0UF 
E15431-004 
20% 
0603V 
X6S 
4V 
22.0UF 
C5G104 
20% 
X6S 
C5G103 
22.0UF 
4V 
0603V 
E15431-004 
20% 
4V 
E15431-004 
0603V 
C5G102 
X6S 
22.0UF 22.0UF 
4V 
20% 
E15431-004 
C5G101 
X6S 
0603V 0603V 
E15431-004 E15431-004 E15431-004 
4V 
20% 
4V 22.0UF 
4V 
20% 
22.0UF 
C5G99 
4V 
X6S 
20% 
4V 
20% 
22.0UF 
C5G100 
X6S 
E15431-004 
0603V 
C5G98 
22.0UF 
X6S X6S 
C5G97 
22.0UF 
0603V 
22.0UF 
C5G87 
0603V 
20% 
X6S 
20% 
4V 
0603V 
C5G86 
X6S 
20% 
0603V 
4V 
22.0UF 
20% 
4V 
0603V 
22.0UF 
C5G84 
20% 
E15431-004 
0603V 
X6S 
20% 
4V 
22.0UF 
C5G82 
X6S 
4V 
20% 
22.0UF 
C5G81 
X6S 
E15431-004 
0603V 
20% 
4V 
0603V 
22.0UF 
X6S 
C5G80 
C5G118 
47UF 
E15431-004 
C5G88 
E15431-004 
4V 
0603V 
X6S 
20% 
47UF 
0603V 
20% 
4V 
22.0UF 
C5G79 
X6S 
22.0UF 
20% 
0603V 
X6S 
4V 
22.0UF 
E15431-004 
X6S 
22.0UF 
4V 
20% 
22.0UF 
C5G109 
X6S 
20% 
E15431-004 
0603V 
4V 
E15431-004 
0603V 
X6S 
22.0UF 
C5G110 
4V 
20% 
0603V 
E15431-004 
X6S 
22.0UF 
C5G111 
4V 
20% 
0603V 
E15431-004 
22.0UF 
X6S 
4V 
20% 
4V 
22.0UF 
C5G113 
20% 
0603V 0603V 
20% 
E15431-004 
C5G114 
22.0UF 
4V E15431-004 
X6S 
20% 
C5G107 
0603V 0603V 0603V 
E15431-004 
E15431-004 
X6S 
C5G112 C5G108 
22.0UF 
4V 
20% 
E15431-004 
C5G106 
E15431-004 
0603V 
E15431-004 
X6S 
0805 
47UF 
C5G115 
20% 
X6S 
0805 
C95333-006 C95333-006 
47UF 
C5G116 
TP FAB3-DVT NOPOP 20161220 TP FAB3-DVT NOPOP 20161220 
BOM_DS=NOPOP BOM_DS=NOPOP 
GROUP=PWR_MLCC_CAP 
GROUP=PWR_MLCC_CAP 
NOPOP 
BOM_DS=NOPOP BOM_DS=NOPOP BOM_DS=NOPOP BOM_DS=NOPOP BOM_DS=NOPOP BOM_DS=NOPOP BOM_DS=NOPOP 
BOM_DS=NOPOP BOM_DS=NOPOP BOM_DS=NOPOP BOM_DS=NOPOP BOM_DS=NOPOP BOM_DS=NOPOP BOM_DS=NOPOP BOM_DS=NOPOP BOM_DS=NOPOP BOM_DS=NOPOP BOM_DS=NOPOP BOM_DS=NOPOP BOM_DS=NOPOP BOM_DS=NOPOP BOM_DS=NOPOP 
GROUP=PWR_MLCC_CAP 
GROUP=PWR_MLCC_CAP 
GROUP=PWR_MLCC_CAP 
GROUP=PWR_MLCC_CAP 
GROUP=PWR_MLCC_CAP 
GROUP=PWR_MLCC_CAP 
GROUP=PWR_MLCC_CAP 
GROUP=PWR_MLCC_CAP 
GROUP=PWR_MLCC_CAP 
GROUP=PWR_MLCC_CAP 
GROUP=PWR_MLCC_CAP 
GROUP=PWR_MLCC_CAP GROUP=PWR_MLCC_CAP 
GROUP=PWR_MLCC_CAP
GROUP=PWR_MLCC_CAP 
GROUP=PWR_MLCC_CAP GROUP=PWR_MLCC_CAP 
GROUP=PWR_MLCC_CAP 
GROUP=PWR_MLCC_CAP 
GROUP=PWR_MLCC_CAP 
GROUP=PWR_MLCC_CAP 
GROUP=PWR_MLCC_CAP 
GROUP=PWR_MLCC_CAP 
GROUP=PWR_MLCC_CAP 
GROUP=PWR_MLCC_CAP 
GROUP=PWR_MLCC_CAP 
GROUP=PWR_MLCC_CAP 
GROUP=PWR_MLCC_CAP 
GROUP=PWR_MLCC_CAP 
GROUP=PWR_MLCC_CAP 
GROUP=PWR_MLCC_CAP 
4V 4V 
GROUP=PWR_MLCC_CAP 
BOM_DS=NOPOP 
GROUP=PWR_MLCC_CAP 
GROUP=PWR_MLCC_CAP
GROUP=PWR_MLCC_CAP 
BOM_DS=NOPOP 
GROUP=PWR_MLCC_CAP 
BOM_DS=NOPOP BOM_DS=NOPOP BOM_DS=NOPOP BOM_DS=NOPOP BOM _DS=NOPOP BOM_DS=NOPOP BOM_DS=NOPOP BOM_DS=NOPOP BOM_DS =NOPOP BOM_DS=NOPOP 
NOPOP NOPOP 
4V 
NOPOP 
GROUP=PWR_MLCC_CAP 
GROUP=PWR_MLCC_CAP 
4V 
2
2 2
11
22
11
2
111
22
1
1
2
1
22
11
22
1
2
1
2
2
1
2
11
2
111
22
1
2
1
2
1
2
1
2
1
2
1
2
1
2
1
1
2
1
2
1
2 2
1 1
2 2
1 1
2 2
1 1
2
1
2
1
22
2
1
DO NOT SCALE DRAWING SHEET 
B
AA
B
B
SIZE 
SCALE: 
234
1234
DEPARTMENT CODE 
1
DOCUMENT NUMBER REV 
PVDDQ_GHJ 
PVDDQ_KLM 
PVDDQ_KLM 
PVDDQ_GHJ PVDDQ_KLM 
PVDDQ_GHJ 
243 OF 270 
Wed Feb 08 16:35:35 2017 
TP FAB1 ADD CAP ON DIMM BOTTOM SIDE 1116 
WIWYNN CORPORATION 
ADD DIMM CAP FOR SINGLE SIDE MB (2/2) 



G21497-005 
0402 
A36096-155 A36096-155 
X7R 
C843 
16V 
0.22UF 
10% 
X7R 
A36096-155 
A36096-155 
X7R 
A36096-155 
X7R 
10% 
0.22UF 
0.22UF 
A36096-155 
0402 
G21497-005 
1/16W 
R769 
0402 
0.0 
0402 
G21497-005 
0402 
1/16W 1/16W 
R781 
0.0 
0402 0402 
0402 
G21497-005 
R784 
CHIP 
R775 
0.0 
1/16W 
0.0 
R768 
0.0 
CHIP 
1/16W 
G21497-005 
0.0 
R778 
0.0 
5% 
0402 
CHIP 
G21497-005 
CHIP 
5% 
1/16W 
R771 
R767 
0402 
G21497-005 
5% 
A36096-155 
X7R 
R782 
R785 
0.22UF 
CHIP 
1/16W 
5% 
0402 
R780 
G21497-005 
0402 
0.0 
1/16W 
CHIP 
R777 
CHIP 
5% 
1/16W 
0402 
C833 
0.22UF 
16V 
10% 
X7R CHIP 
G21497-005 
1/16W 
0402 
R783 
0.0 
5% 
R779 
CHIP 
0.0 
5% 
0402 
5% 
CHIP 
CHIP 
0402 
5% 
0.0 
R760 
1/16W 
CHIP 
CHIP 
5% 
0.0 
C842 
A36096-155 
X7R 
10% 
0.22UF 
16V 
0402 
16V 
C844 
10% 
X7R 
0.22UF 
0402 
16V 
0.22UF 
C834 
A36096-155 
X7R 
10% 
0402 
C829 
0.22UF 
X7R 
16V 
10% 
0402 
X7R 
10% 
16V 
0.22UF 
C835 
0402 
0402 
0.0 
CHIP 
5% 
1/16W 
0402 
16V 
0.22UF 
C845 
10% 
X7R 
A36096-155 
X7R 
10% 
C832 
0.22UF 
16V 
A36096-155 
10% 
16V 
C840 
0402 
16V 
C828 
10% 
0.22UF 
0402 
C826 
A36096-155 
X7R 
10% 
16V 
0.22UF 
0402 
10% 
A36096-155 
16V 
X7R 
0.22UF 
C830 
0402 
0402 
16V 
C831 
A36096-155 
10% 
X7R 
0402 
10% 
A36096-155 
16V 
C841 
0.22UF 
0402 
A36096-155 
16V 
C827 0.0 
5% 
1/16W 
G21497-005 
0402 
CHIP 
G21497-005 G21497-005 
0402 
G21497-005 
1/16W 
0.0 
1/16W 
5% 
0.0 
5% 
CHIP 
G21497-005 
5% 
R774 
G21497-005 
G21497-005 
1/16W 
5% 
108 
30 105 
108 
105 30 
108 
108 109 
30 105 105 30 
GROUP=PCIE_RISER 
GROUP=PCIE_RISER 
GROUP=PCIE_RISER 
GROUP=PCIE_RISER 
GROUP=PCIE_RISER 
GROUP=PCIE_RISER 
GROUP=PCIE_RISER 
GROUP=PCIE_RISER 
GROUP=PCIE_RISER GROUP=PCIE_RISER 
GROUP=PCIE_RISER GROUP=PCIE_RISER 
GROUP=PCIE_RISER GROUP=PCIE_RISER 
GROUP=PCIE_RISER GROUP=PCIE_RISER GROUP=PCIE_RISER GROUP=PCIE_RISER GROUP=PCIE_RISER GRO UP=PCIE_RISER 
GROUP=PCIE_RISER GROUP=PCIE_RISER 
GROUP=PCIE_RISER 
GROUP=PCIE_RISER GROUP=PCIE_RISER GROUP=PCIE_RISER GROUP=PCIE_RISER 
GROUP=PCIE_RISER GROUP=PCIE_RISER GROUP=PCIE_RISER 
GROUP=PCIE_RISER GROUP=PCIE_RISER 
11 
14 
15 
8
15 
15 
13 
11 
10 10 
11 
8
12 
9
13 
12 
8
8
9
12 
11 
13 
10 
11 
11 
13 
14 
15 
14 
12 
8
9
10 
8
8
9
10 
9
10 
14 
13 
8
9
10 
11 
12 
14 
13 
14 
15 
12 
13 
11 
12 
13 
14 
15 
14 
15 
9
15 
9
10 
12 
1
1
2
2
1 1
1
2
2
1
1
2
2
2
1
2
1
2
1
2
1
2
1
2
1
2
1
2
1
1
2
1
2
1
2
1
2
2
1
2
1
2
1
1
22
1
2
1
2
1
2
1
2
1
2
2
1
22
1 1
2
1
DO NOT SCALE DRAWING SHEET 
B
AA
B
B
SIZE 
SCALE: 
234
1234
DEPARTMENT CODE 
1
DOCUMENT NUMBER REV 
IN 
OUT 
IN 
IN 
OUT 
OUT 
OUT 
IN 
244 OF 270 
Wed Feb 08 16:35:35 2017 
PCIE_UPLINK POP: C6B4, C6B6, C6B9, C6B11, C6B14, C6B15, C6B17, C6B19, C6B5, C6B8, C6B10, C6B12, C6B13, C6B16, C6B18, C6B20, 
C3M2, C3M11, C3M13, C3M3, C3M25, C3M28, C3M36, C3M34, C3M1, C3M12, C3M14, C3M4, C3M26, C3M32, C3M35 AND C3M33 
P3E_CPU0_PE1_PCH_RXP<15:8> 
P3E_CPU0_PE1_PCH_CON_TXN<15:8> 
P3E_CPU0_PE1_PCH_TXP<15:8> 
P3E_CPU0_PE1_PCH_CON_TXP<15:8> 
P3E_CPU0_PE1_PCH_CON_RXN<15:8> 
P3E_CPU0_PE1_PCH_CON_RXP<15:8> 
P3E_CPU0_PE1_PCH_TXN<15:8> P3E_CPU0_PE1_PCH_RXN<15:8> 
TP FAB1 ADD PE1[8:15] PATH TO X24  SLOT 
WIWYNN CORPORATION 
x8 PCIe Co-lay path 



74CBTLV1G125 
G21497-005 
G21497-005 
5% 1/16W 
USB2_P02_DP 2
R8W11 
R8W10 
1
1
1
2
JTAG_PLD_TDO 
CHIP 
JTAG_PLD_TDO_MUX_R 
3
4
4.75K 
C8W6 1C8W5 
0402 
2
R8W15 
G21796-072 
6
U8W2 
SMLF 
42
1
IC 
U8W1 
0.0 
5% 
5% 
G21497-005 CHIP 1/16W 
1/16W CHIP 
0402 
0402 1/16W 
SMC-CONN60A-22-GP 
0.0 
2
CONX8 
P3E_CPU0_PE2_SS_RXP<15:8> 
P3E_CPU0_PE2_SS_RXN<15:8> 
P3E_CPU0_PE2_SS_C_TXN<15:8> 
P3E_CPU0_PE2_SS_C_TXP<15:8> 
1
2
SMLF 
25V 
X7R 
1
2
D97712-004 
1.0UF 
10% 
0402V 
6.3V 
X6S 2
IC 
0.01UF 
10% 
A36096-045 
0402V 
5
C99406-001 
VCC=P3V3_STBY;GND=GND; 
C88177-001 
CHIP G21497-005 
G21497-005 0402 
JTAG_PLD_TMS_MUX 
JTAG_PLD_TCK_MUX 
1/16W 
1% 
1
USB2_P02_DN 
5% 1/16W CHIP 0402 
CHIP 1 2
21
R8W14 
R8W13 
0.0 
0.0 
0402 
R8W12 
0.0 
5% 
TP FAB4 ADD 0OHM RES 20170111 
TP FAB4 ADD 0OHM RES 20170111 
115 
191 
145 
189 
144 189 254 
31 
31 
105 
105 
189 
189 
115 
JTAG_RISER_TRST 
JTAG_RISER_N 
JTAG_RISER_TDO_R 
JTAG_RISER_TDI_R 
JTAG_BMC_TRST_N 
JTAG_RISER_TMS 
JTAG_RISER_TCK 
JTAG_RISER_TDO_R 
JTAG_RISER_TDI_R 
JTAG_RISER_TDO 
JTAG_RISER_TDI 
245 
245 
245 
245 
15 
15 
12 
15 
14 14 
12 
11 
8
8
9
9
10 
10 
11 
11 
13 
8
8
9
10 
11 
12 
13 
14 
9
10 
13 
12 
14 
13 
15 
47 48 
51 
56 
36 
42 
33 
NP1 
2
10 
65
9
11 
13 
19 
23 
25 
27 
31 
35 
12 
14 
18 
24 
26 
30 
16 
7
15 
22 21 
37 
8
20 
32 
34 
17 
3
38 
41 
28 
39 
44 
4
1
59 
29 
PTH1 
40 
60 
58 
45 
49 
57 
43 
46 
50 
52 
54 
PTH2 
53 
55 
NP2 
DO NOT SCALE DRAWING 
A B
OE_N 
S
B0 
B1 
VCC 
A
GND 
TP FAB1 ADD X8 SLOT 
SHEET 
B
AA
B
B
SIZE 
SCALE: 
234
1234
DEPARTMENT CODE 
1
DOCUMENT NUMBER REV 
IN 
IN 
IN 
OUT 
P3V3_STBY 
IN 
P3V3_STBY 
NC7SB3157 
IN 
BI 
BI 
OUT 
OUT 
IN 
IN 
245 OF 270 
Wed Feb 08 16:35:36 2017 
S=1: A=B1 
S=0: A=B0 
TP FAB1 NC 1225 
TP FAB1 NC 1225 
NEW ADD 
NEW ADD 
TP FAB1 SWAP USB DP/DN TO FOLLOW OCP PIN DEFINITION 0106 
NEW ADD 
TP FAB4 ADD CIRCUIT 20170111 
WIWYNN CORPORATION 
X8 SLOT FOR PCIE RISER CARD 



TP_TPM_SPI_4 
TP_TPM_SPI_3 
TP_TPM_SPI_2 
UN8F2 
THIS PART WILL BE IN SOCKET, PLEASE 
10 
11 
H25002-001 
D97712-004 A36096-045 
0402V 
TP_TPM_SPI_6 
TP_TPM_SPI_5 
PU_TPM_SPI_BMC_HOLD_N 
SPI_BMC_BT_DO 
SPI_BMC_BT_CLK 
TPM_SPI_BMC_WP_N 
PU_TPM_SPI_FLASH_RESET_2_N 
SPI_BMC_BT_DI 
TP_TPM_SPI_1 
TP_TPM_SPI_0 
SOCKET IS D91187-001 
USE ALT SYMBOL ASSOCIATED WITH PART FOOTPRINT 
1 2 33.2 RN8F5 
1
2 X7R 
10% 
25V 
0.01UF 
CN8F2 
0402V 
X6S 
10% 
6.3V 
1.0UF 
CN8F1 1
2
1% 
EMPTY 
4.75K 
RN8F2 
0402 
1/16W 
G21796-072 
3
9
16 
7
4
14 
5
8
2
6
13 
IC 
12 
1
15 
G21796-072 
2
1
RN8F4 
1% 
EMPTY 
4.75K 
1/16W 
0402 
CHIP 
1
RN8F3 
2
4.75K 
1% 
0402 
1/16W 
G21796-072 
SPI_TPM_BMC_DI_R 
RN8F6 
82KR2F-1-GP 
146 150 162 
146 150 162 
137 146 
137 
162 146 150 
1/16W 
0402 
1% 
82KOHM 
SPI_BMC_BT_CS0_N 
CAD NOTE: 
BOM NOTE: 
CAD NOTE: 
2
1
DO NOT SCALE DRAWING SHEET 
B
AA
B
B
SIZE 
SCALE: 
234
1234
DEPARTMENT CODE 
1
DOCUMENT NUMBER REV 
P3V3_STBY 
OUT 
IN 
IN 
IN 
IN 
2 1
246 OF 270 
Wed Feb 08 16:35:36 2017 
CLK 
CS_N 
DI_IO<0> DO_IO<1> 
GND 
NC<6> 
NC<5> 
NC<4> 
NC<3> 
NC<2> 
NC<1> 
NC<0> 
VCC 
WP_N_IO<2> HOLD_N_IO<3> 
RESET_N 
UN8F2 IS SOCKET. 
TP FAB1 MOVE PU RN8F1 TO PAGE 137 0308 
PLACE CAPS NEAR VCC PIN ON W25Q256 COMPONENT 
W25Q256 
TP FAB1 CONNECT WP_N TO BMC GPIO  BY A JUMPER 
TP FAB1 ADD TPM FLASH 
WIWYNN CORPORATION 
BMC SECURE FLASH 



P17 
P16 
P15 
P14 
P13 
P12 
P11 
P10 
A0 SCL 
SDA 
VCC 
GND P07 
P06 
P05 
P04 
P03 
P02 
P01 
P00 
A2 
A1 
INT# 
EN 
SDAB 
SCLB 
VCCB 
GND 
SDAA 
SCLA 
VCCA 
0402 
2
CR6W2 
G21796-010 
SMLF 
0402 
R6W35 
G21796-173 
FM_CPU_CATERR_MSMI_LVT3_N 
R6W21 
VCC=P3V3_STBY;GND=GND; 
C47049-001 
IC 
1/16W 
PD_ID_EEPROM_WP 
10% 
C73510-001 
BAT54WS 
PWRGD_SYS_PWROK 
LED_POSTCODE_2_R 
LED_POSTCODE_1_R 
LED_POSTCODE_0_R 
0402V 
A36096-030 
X7R 
10% 
16V 
0.1UF 
PWRGD_DSW_PWROK 
RST_PLTRST_N CHIP 
1
U6W1 
LED_POSTCODE_6_R 
LED_POSTCODE_7_R 
1
2
C6W1 
0402 
R6W10 
4.75K 
1% 
1/16W 
CHIP 
G21796-072 
4.75K 
R6W24 
CHIP 
1/16W 
1% 
G21796-072 
0402 
R6W25 
4.75K 
1% 
G21796-072 
CHIP 
1/16W 
0402 
A36096-030 2
1 C6W4 
0.1UF 
16V 
10% 
X7R 
0402V 0402V 
2X7R 
1
16V 
C6W2 
R6W28 
4.75K 
1/16W 
1% 
G21796-072 
CHIP 
0402 
TCA9517DGKR-GP 
U6W2 
1
16V 
2
CHIP 
R6W20 
1% 20.0 
0402 
7
6
1% 
1.00K 1
R6W23 
2 CHIP 
0402 
R6W22 
1/16W 
21
0402 
SMB_PMBUS_BMC_STBY_LVC3_SDA_R1 
SMB_PMBUS_BMC_STBY_LVC3_SCL_R1 
SMB_PMBUS_BMC_STBY_LVC3_SDA_R1 
SMB_PMBUS_BMC_STBY_LVC3_SCL_R1 
SMLF 
IC 
1LED_POSTCODE_5_R 
FM_SLPS3_N 
TCA9555PWR-GP 
LED_POSTCODE_3_R 
LED_POSTCODE_4_R 
G21796-072 
EMPTY 
0402 
R6W8 
1/16W 
EMPTY 
1% 
0402 
1/16W 
1% 
4.75K 4.75K 
R6W7 
0402 
CHIP 
G21796-072 
CHIP 
1/16W 
1% 1% 
CHIP 
0402 
4.75K 
1/16W 
1% 
1/16W 
EMPTY 
0402 
G21796-072 
4.75K 
G21796-072 
1/16W 
1% 
R6W4 
G21796-072 
R6W9 
4.75K 4.75K 
R6W6 R6W5 
C73510-001 
CR6W1 IC BAT54WS 
2
FM_CPU_CATERR_LVT3_N 
A36096-030 
10% 
0.1UF 
G21796-072 
5
X7R 
1
1
2
0402V 
20.0 1% 
CHIP 
1/16W 
G21796-026 
PU_ID_EEPROM_A0 
C6W3 
A36096-030 
0.1UF 
3
U6W3 
2
1.00K 
1% 
G21796-173 
0402 
CHIP 
1/16W 
G21796-026 
1/16W 
1% 
100.0K 
TP FAB3 RECONNECTION 0926 
TP FAB3 CHANGE P18 ABD P20 CONNECTION 0803 
TP FAB1 CONNECT P20 0314 
TP FAB1 CONNECT P12~P16 1221 
TP FAB3 RECONNECTION 0905 
TP FAB3 POP R6W4, R6W5 AND R6W6; NOPOP R6W7, R6W8 AND R6W9 0819 
TP FAB3 RECONNECTION 0902 
111 155 175 190 
145 176 247 
145 176 247 
175 
155 
168 
133 191 118 144 
155 
155 
155 
196 200 118 157 
191 
119 136 139 191 
155 
155 
119 
247 
119 
247 
138 159 101 102 111 156 
155 
118 148 190 155 
155 92 
147 
120 
190 
92 
144 
190 
146 247 
138 159 181 
199 
R6W12 FM_UART_SWITCH_N 
1% 
0402 
SMB_BMC_PMBUS_STBY_LVC3_SDA 
G21796-072 
CHIP 
1/16W 
4.75K 
R6W11 
4.75K 
0402 
1/16W 
1% 
G21796-072 
CHIP 
FM_CPU_MSMI_LVT3_N 
SMB_BMC_PMBUS_STBY_LVC3_SCL 
247 
247 247 
119 247 
119 247 
146 247 
247 
145 176 247 
145 176 247 
247 
247 
247 
247 
FM_DEBUG_RST_BTN_N 
SMB_DEBUG_STBY_LVC3_SCL 
SMB_DEBUG_STBY_LVC3_SDA 
PCA9555_INT_N 
SMB_HOST_STBY_LVC3_SDA 
PCA9555_A1 PCA9555_A0 
SMB_HOST_STBY_LVC3_SCL 
PCA9555_INT_N 
SMB_DEBUG_STBY_LVC3_SCL 
SMB_DEBUG_STBY_LVC3_SDA 
PCA9555_A1 
PCA9555_A2 
PCA9555_A2 
PCA9555_A0 
SMB_HOST_STBY_LVC3_SCL_R3 
FP_PWR_BTN_R_N 
HSC_SMBUS_SWITCH_EN 
HSC_SMBUS_SWITCH_EN 
SMB_HOST_STBY_LVC3_SDA_R3 
CAD NOTE: 
DESIGN NOTE: CAD NOTE: 
2
5
14 
13 
23 
1
18 
1
2
15 
2
3
6
10 
11 
24 
22 
16 
19 
1
2
1
2
1
2
1
2
4 5
3
2
6
8
7
1
21
PLACE SERIES RESISTORS ON SMB_HOST_STBY_LVC3_SDA/SCL NETS CLOSE TO AT24C64 
21 
7
9
4
8
12 
20 
17 
2
1
2
1
2 2
1
1
2
11
DO NOT SCALE DRAWING SHEET 
B
AA
B
B
SIZE 
SCALE: 
234
1234
DEPARTMENT CODE 
1
DOCUMENT NUMBER REV 
BI 
IN 
P3V3_STBY 
BI 
P3V3_STBY 
BI 
IN 
IN 
OUT 
P3V3_STBY 
P3V3_STBY 
IN 
IN 
IN 
P3V3_STBY 
BI 
IN 
BI 
BI 
BI 
BI 
BI 
BI 
BI 
BI 
IN 
IN 
IN 
IN 
OUT 
OUT 
P3V3_STBY 
P3V3_STBY P3V3_STBY 
P3V3_STBY 
1 2
1 2
A2 
A1 
A0 
SCL 
WP 
SDA 
AT24C64 
247 OF 270 
Wed Feb 08 16:35:36 2017 
SMBUS ADDRESS 0XA2 
TP FAB1 ADD I2C TO GPIO BRIDGE FOR USB3.0 BEBUG PORT 1117 
CONNECT TO SWITCH DIRECTLY 
TP FAB1 ADD ONE SMALL EEPROM UNDER HOST SMBUS FOR BIOS SOFT BROAD_ID 
TP FAB3 CHANGE R6W35 RES 0825 TP FAB3 ADD RES AND DIODES 0803 
TP FAB1 CHANGE PCA9555 TO TCA9555 
TP FAB1 CHANGE U6W2 FROM PCA9515 TO PCA9517 1210 
TP FAB1 ADD   R6W24 AND R6W25 PU RESISTOR 1210 
TP FAB1 U6W2 FROM PCA9517 CHANGE TO TCA9517 0106 
ADDRESS 0X4E 
TP FAB1 ADD A SMBUS MASTER SWITCH FOR HSC ACCESS FROM ME OR BMC, CONTROLLED BY BMC 1127 
TO AT24C64 
PLACE CAP CLOSE 
USB3.0 DEBUG PORT, SMBUS MASTER SWITCH & BIOS SPFT BOARD ID 
WIWYNN CORPORATION 



EN 
SDAB 
SCLB 
VCCB 
GND 
SDAA 
SCLA 
VCCA 
SMB_CPU0_PE_HP_GTL_SDA 
SMB_CPU0_PE_HP_GTL_R_SCL 
A36096-030 
NC7SZ08 
RST_PCIE_M2_DEV_N 
RST_PCIE_M2_DEV_AND 
SMB_CPU0_PE_HP_GTL_R_SDA 
TP_SMB_PEHPCPU0_EN 
SMB_PEHPCPU0_STBY_LVC3_R_SCL 
SMB_PEHPCPU0_STBY_LVC3_R_SDA 
SMB_PEHPCPU0_STBY_LVC3_SCL 
RST_PCIE_M2_DEV_IC_N 
SMB_CPU0_PE_HP_GTL_SCL 
SMB_PEHPCPU0_STBY_LVC3_SDA 
PLACE CAP CLOSE 
TO IC 
TO IC 
PLACE CAP CLOSE 
U1W2 
TCA9517DGKR-GP 
R9W13 
G21796-173 
1/16W CHIP 
1% 20.0 
0402 
G21796-173 
20.0 
1/16W 
1% 
0402 
CHIP 
R9W14 
G21796-001 
R9W17 
1/16W 
CHIP 
0402 
1% 
1
2
2.0K 
G21796-001 
0402 
2
1
CHIP 
1% 
1/16W 
R9W16 
2.0K 
0402V 
X7R 
1
10% 
16V 
0.1UF 
C9W7 
2
0.1UF 
16V 
A36096-030 2 X7R 
10% 
0402V 
1 C9W8 
0402 
1/16W 
CHIP 2
G21796-294 
1.0% 
240 
R9W18 
1
0402 
2
G21796-294 
CHIP 
1/16W 
1.0% 
240 
R9W19 
1
0402 CHIP 
10.0 1% R6W27 1/16W 
G21796-066 
21
0402 CHIP G21796-066 
R6W26 1/16W 1% 10.0 
1 2
VCC=P3V3;GND=GND; 
NC7SZ08 
U14E3 
D10321-001 
SOTLF 
IC 
C14W2 
X7R 2
16V 
0402V 
A36096-030 
10% 
0.1UF 
1
0402V 
0.1UF 1
A36096-030 
C14W1 
16V 
10% 
X7R 
2
VCC=P3V3;GND=GND; 
D10321-001 
SOTLF 
IC 
U14E2 
21 
196 175 190 
196 181 241 
190 
145 
145 
145 
185 
21 
145 
DESIGN NOTE: 
CAD NOTE: 
CAD NOTE: 
CAD NOTE: 
CAD NOTE: 
PLACE SEIRES RESISTORS NO MORE 
THAN 3"  FROM CPU0 
4
2
1
8
7
6
5
1
2
3
4
1 2
1 2
1
4
2
DO NOT SCALE DRAWING SHEET 
B
AA
B
B
SIZE 
SCALE: 
234
1234
DEPARTMENT CODE 
1
DOCUMENT NUMBER REV 
P3V3 
OUT 
BI 
PVCCIO_CPU0 
PVCCIO_CPU0 
OUT 
BI 
P3V3_STBY 
P3V3_STBY 
IN 
BI 
IN 
IN 
P3V3 
IN 
OUT 
248 OF 270 
Wed Feb 08 16:35:36 2017 
TP FAB1  ADD FOR CPU0 HOT PLUG LEVER SHIFT 
TP FAB1 ADD FOR M.2 RESET CIRCUIT1204 
PE HP SMBUS ADDRESS 0X22 
TP FAB1 CONNECT TO BMC SMB13 0121 
PLACE CAPS & PU RESISTORS NEAR TCA9517 
PWRGD_P3V3 
PWRGD_P12V_HSC_DLY 
WIWYNN CORPORATION 
CPU0 HOT PLUG AND M.2 RESET CIRCUIT 



4.75K 
SM 
C52245-001 
0402 
CHIP 
G21796-016 
Q9W4 
0402V 
C52245-001 
SM 
Q9W2 
MMBT3904 
CHIP 
0402 
Q9W3 
IC 
LMV331IDCKRG4-GP 
1/16W 
1% 
10.0K 
G21796-072 
0402 
10% 
16V 
0.1UF 
C3W2 R3W2 
100.0K 
1/16W 
CHIP 
G21796-010 
0402 
1
2
CR3W1 
C73510-001 
BAT54WS 
IC 
SMLF 
CHIP 1/16W 
0.0 
R3W6 
CHIP 
1% 
1/16W 
X7R 
16V 
0.1UF 
C8W2 1
2
10% 
A36096-030 
IC 
4.75K 
CHIP 
1% 
R3W7 
1/16W 
G21796-072 
1/16W 
0402 
1% 
R3W9 
10.0K 
0402 
R3W4 
FET 
2N7002 
Q9W1 
1% 
0402 
SC1U16V3KX-2GP 
1/16W 
1% 
2
C8W1 
5% 
G21497-005 
R8W1 
CHIP 
R3W1 
0402 
1
C79254-001 
G21796-016 
1% 
10.0K 
R3W3 
1/16W 
EMPTY 
0402V 
X7R 
A36096-030 
MMBT3904 
47KR2F-GP 
2
1
R3W5 
-
+
TP FAB3 CHANGE DIODE 0919 
TP FAB3 ADD CAP 0919 
TP FAB3 CHANGE RES 0919 
TP FAB3 DEL SCHMITT BUFFER AND ADD BJT 0905 
TP FAB3 CHANGE RES 0919 
TP FAB3 CHANGE RES 0902 
TP FAB3 CHANGE RES 0905 
TP FAB3 ADD SCHMITT BUFFER 0831 
TP FAB1 CHANGE TO P5V_STBY 1221 
133 119 146 
146 
146 
119 157 184 
0402 
10% 
1% 
CONFIG=64.47035.L0L 
NEW_VALUE=470K 
1UF 
X5R 
16V 
0603 
1/16W 
47KOHM 
FM_TPM_PRES_N 
FM_TPM_PRES_RST_N_R 
FM_TPM_PRES_RST 
RST_BMC_EXTRST_N 
VREF_2V2 
BMC_SELF_HW_RST 
BMC_SELF_HW_D_RST 
FM_TPM_PRES_RST_N 
BMC_TPM_HW_C_RST S
D
G
G21796-016 
21
4
3
1
2
1
2
1
2
1
1
1
1
2
1 2
2
2
DO NOT SCALE DRAWING 
1
3
2
SHEET 
B
AA
B
B
SIZE 
SCALE: 
234
1234
DEPARTMENT CODE 
1
DOCUMENT NUMBER REV 
P3V3_STBY 
OUT 
IN 
P5V_STBY 
P3V3_STBY 
OUT 
P3V3_STBY 
IN 
2 5
2
1
3
1
3
2
Wed Feb 08 16:35:36 2017 
249 OF 270 
TP FAB1 FOR BMC TPM 1120 
TP FAB1 NOPOP 1221 
WITH TPM MODULE: V=1.64V 
NOPOP 
WIWYNN CORPORATION 
TPM PRESENT AND RESET CIRCUIT 



R1W1 
FM_OCP_MEZZA_PRES_N 
1MR2F-L-GP 
FM_OCP_MEZZB_PRES_N 
R1W6 
1MR2F-L-GP 
10.0K 
1% 
1
FM_OCP_MEZZC_PRES_N 
FM_OCP_MEZZB_PRES_1V05_PCH_N 
FM_OCP_MEZZB_PRES_LVT3_BMC 
FET 
2N7002DW 
D24280-001 
Q1W4 
10.0K 
1% 
1/16W 
R1W7 
CHIP 
0402 
G21796-016 
Q1W4 
2N7002DW 
FET 
D24280-001 
C79254-001 
FET 
2
2N7002 
3
Q1W1 
Q1W2 
D24280-001 
FET 
2N7002DW 
R1W4 
CHIP 
Q1W2 
2N7002DW 
D24280-001 
FET 
0402 
G21796-016 
1/16W 
1MR2F-L-GP 
R1W3 
186 
187 
188 
145 
133 121 
133 119 146 
133 121 
145 
1MOHM 
1/16W 
0402 
0402 
1% 
1% 
0402 
1MOHM 
1% 
1/16W 
1/16W 
1MOHM 
S
D
G
S
D
G
S
D
G
S
D
G
S
D
G
FM_OCP_MEZZC_PRES_1V05_PCH_N 
FM_OCP_MEZZC_PRES_LVT3_BMC 
FM_OCP_MEZZA_PRES 
DO NOT SCALE DRAWING 
3
4
5
6
1
2
6
4
5
3
2
1
SHEET 
B
AA
B
B
SIZE 
SCALE: 
234
1234
DEPARTMENT CODE 
1
DOCUMENT NUMBER REV 
P3V3_STBY 
P3V3_STBY 
IN 
P3V3_STBY 
IN 
P3V3_STBY 
P3V3_STBY 
OUT 
OUT 
OUT 
OUT 
OUT 
IN 
2 1
1 22 1
2 1
2 1
Wed Feb 08 16:35:37 2017 
250 OF 270 
TP FAB1 RENAME 1218 
VGS(TH)=1V~2V 
TP FAB1 RENAME 1218 
VGS(TH)=1V~2V 
TP FAB1 RENAME 1218 
TP FAB1 RENAME 1218 
TP FAB1  ADD MEZZ PRESENT CIRCUIT 1210 
TP FAB1  ADD MEZZ  C PRESENT CIRCUIT 1214 
TP FAB1 RENAME 1218 
TP FAB1 RENAME 1218 
VGS(TH)=1V~2V 
TP FAB1 RENAME 1218 
WIWYNN CORPORATION 
MEZZ PRESENT CIRCUIT 



H71799-001 
C10W3 
0.1UF 
A36096-030 
0402V 
C10W2 
X7R 
16V 
10% 
C95333-007 
0805 
H71799-001 
CR10W1 
SDMK0340L 
IC 
SM 
4.75K 
1% 
EMPTY 
C74770-005 
IC 
SM 
0402 
1/16W 
100.0 
G21796-017 
R10W6 
R10W7 
4.75K 
1/16W 
SDMK0340L 
SM 
SDMK0340L 
0402V 
A36096-045 
25V 
0.01UF 
G21796-072 
PLACE CAP CLOSE 
C88419-001 
0402 
4.75K 
CHIP 
0402 
G21796-271 
G21796-017 
0402V 
CR10W2 
1/16W 
221 
R10W4 
CHIP 
1% 
C10W4 
CHIP 
J1B2 
1
HDR 
4
3
5
6
1% 
A36096-030 
R10W1 
X6S 
0805 
1/8W 
0.0 
R10W5 
CHIP 
5% 
10% 
C10W1 
16V 
10UF 
R10W3 
U10W1 
2
VCC=P3V3_STBY;GND=GND 
0.1UF 
10% 
16V 
X7R 
0402V 
1/16W 
CHIP 
0402 
G21796-072 
0402 
CHIP 
1% 
1.0% 
1/16W 
TO IC 
IC 
74LVC1G07 
10% 
X7R 
10% 
C10W5 
G22179-004 
R10W2 
1/16W 
100.0 
1% 
CHIP 
CR10W3 
H71799-001 
25V 
X7R 
A36096-045 
0.01UF 
0402 
G21796-072 
TP FAB3 ADD PARTS FOR 6 PIN HEADER 0819 
TP FAB3 UNIFY THE NAMING AS PUMP_TACH1 0831 
TP FAB3 RECONNECTION 0831 
TP FAB3 RECONNECTION 0823 
TP FAB3 RECONNECT ION 0831 147 
147 
147 
TP_PUMP 
PUMP_TACH1_D 
PUMP_TACH0 PUMP_TACH_D PUMP_TACH_R 
PUMP_TACH1_R PUMP_TACH1 
2
1
CAD NOTE: 
TP FAB1 CHANGE PN  0216 
TP FAB3 CHANGE HEADER TO 6 PIN 0819 
TP FAB3 EXCHANGE LOCATION TO J1B2 0824 
TP FAB3 EXCHANGE LOCATION TO J1F2 0824 
2
1
1
PUMP_PWM_OUT_BUF 
1
1
2
1
2
PUMP_PWM_OUT_R 
2
1
2
1
P12V_PUMP 21
2
1
2
1
42PUMP_PWM_OUT 
1
2
2
2
2
1
DO NOT SCALE DRAWING 
1
12
2
SHEET 
B
AA
B
B
SIZE 
SCALE: 
234
1234
DEPARTMENT CODE 
1
DOCUMENT NUMBER REV 
P5V_STBY 
P3V3_STBY 
P12V_FAN 
P3V3_STBY 
OUT 
IN 
P3V3_STBY 
OUT 
CONN6 
TTL1G07_A 
251 OF 270 
Wed Feb 08 16:35:37 2017 
TP FAB1 ADD PUMP HEADER CIRCUIT 1225 
WIWYNN CORPORATION 
PUMP HEADER 



VCC 
YGND 
A
OE# 
VCC 
YGND 
A
OE# 
U74AHCT1G125G-AL5-R-GP-U 
0402LF 
A36094-025 
C25W82 
C25W79 
100.0PF 
A36095-026 
0402LF 
A36095-043 
COG 
50V 
A36095-043 
A36096-030 
G18435-001 G18435-001 
4.75K 
R25W135 
R25W132 
1% 
10% 
F25W1 
A36095-043 
L25W2 
IND-68NH-15-GP 
A36095-043 
12.0PF 12.0PF 
50V 
12.0PF 
C25W72 
COG 
A36095-043 
5% 5% 5% 
C25W75 C25W76 C25W77 
5% 
COG 
5% 
50V 
0402LF 
A36095-043 
50V 
COG 
0402LF 
50V 
0402LF 
COG 
0402LF 
COG 
0402LF 
12.0PF 
C25W73 
12.0PF 12.0PF 
G21796-072 
CHIP 
0402 
1% 
33.2 
10.0PF 
50V 
FET 
2N7002DW 
Q25W4 
FET 
D24280-001 
Q25W4 
2N7002DW 
C25P83 
X7R 2
1
10% 
0.1UF 
A36096-030 
16V 
1
COG 
1 C25W81 
50V 
10.0PF 
2
1% 
1/16W 
0402 
CHIP 
1/16W 
4.75K 
1% 
1
2 G21796-072 
1/16W 
1
CHIP 
100.0PF 
5% 
COG 
50V 
1
0402 
4.75K 
CHIP 
1/16W 
R25W131 
1
2
0402 
G21796-072 
CHIP 
1/16W 
1% 
4.75K 
R25W126 
1/16W 
CHIP CHIP 
0402 
1% 
R25W127 
0402 
J25W1 
10% C25P80 
2
X7R 
8
6
1
2
7
IC 
5
4
ESD3V3U4ULC 
CR25W2 
9
3
ESD3V3U4ULC 
7
2
1
4
5
8
3
6
9
RB551V30-GP 
D25W8 
1
X7R 
1/16W 
33.2 
1% 
1% 
33.2 
G21796-074 
2
0402V 
CHIP 
2
1
16V 
0402V 
U25W8 
IC 
CR25W1 
G21796-072 
5% 
G21796-009 
CHIP 
1/16W 
1% 
150.0 
1/16W 
G21796-009 
0402 
0402 
33.2 
CHIP 
5% 
G21796-074 
2
0.1UF 
0402 
0402LF 
COG 
50V 
5% 
C25W78 
1
C25W90 
COG 2
A36094-025 
0402LF 
R25W138 1% 
2
16V 
U25W7 
U74AHCT1G125G-AL5-R-GP-U 
SMC-CON13-GP 
D24280-001 
1/16W 
CHIP 
0402 
G21796-074 
2
R25W136 
0402LF 
A36095-026 
R25W133 
G21796-009 
150.0 
1% 
150.0 
R25W128 
L25W3 
R25W134 
G21796-074 
R25W139 
1/16W 
1
0402 
0402V A36096-030 
0.1UF 
POLYSW-D5A6V-2-GP-U 
5% 
IND-68NH-15-GP 
50V 
C25W74 
L25W1 
IND-68NH-15-GP 144 
144 
144 
146 
146 
146 
146 
GROUP=AST2500 
GROUP=AST2500 
V_IO_VSYNC_J 
GROUP=AST2500 
GROUP=AST2500 
V_IBMC_5V_DDC_SDA_J 
GROUP=AST2500 GROUP=AST2500 GROUP=AST2500 
V_IO_G_J 
GROUP=AST2500 
GROUP=AST2500 
GROUP=AST2500 GROUP=AST2500 
V_IO_G_J 
Q25W2_GATE 
I2C_BMC_VGA_DDC_SDA GROUP=AST2500 
GROUP=AST2500 
300MA 
68NH 
GROUP=AST2500 
GROUP=AST2500 
GROUP=AST2500 
GROUP=AST2500 
I2C_BMC_VGA_DDC_SDA_G 
GROUP=AST2500 
V_IO_HSYNC_J 
V_IO_R_J 
DCR=800MOHM 
DCR=800MOHM 
V_IO_B_J 
V_IBMC_5V_DDC_SCL_J 
P5V_VGA 
V_IO_VSYNC_J 
BMC_VGA_HSYNC 
V_IO_R_J 
V_IBMC_5V_DDC_SDA_J 
V_IO_HSYNC_J 
V_IO_VSYNC_J 
V_IO_B_J 
V_IO_G_J 
V_IO_B_J 
BMC_VGA_VSYNC 
V_IO_G_J 
V_IBMC_5V_DDC_SDA_J 
Q25W1_GATE 
I2C_BMC_VGA_DDC_SCL 
V_IO_R_J 
P5V_VGA 
V_IBMC_5V_DDC_SCL_J 
V_IO_HSYNC_J 
V_IO_R_J 
V_IBMC_5V_DDC_SCL_J 
GROUP=AST2500 
GROUP=AST2500 
V_IO_B_J 
GROUP=AST2500 
GROUP=AST2500 
GROUP=AST2500 
GROUP=AST2500 
68NH 
300MA 
I2C_BMC_VGA_DDC_SCL_G 
GROUP=AST2500 
GROUP=AST2500 
GROUP=AST2500 
GROUP=AST2500 
GROUP=AST2500 
VGA_REAR_HSYNC_S 
VGA_REAR_VSYNC_S 
GROUP=AST2500 
CONFIG=069.50007.0071 
GROUP=AST2500 
GROUP=AST2500 
300MA 
68NH 
GROUP=AST2500 
DCR=800MOHM 
GROUP=AST2500 GROUP=AST2500 
252 
252 
252 
252 
252 
252 
252 
252 
252 
252 
252 
252 
252 
252 
252 
252 
252 
252 
252 
252 
252 
252 
252 
252 
252 
252 
BMC_VGA_RED 
BMC_VGA_GREEN 
BMC_VGA_BLUE 
5
1
13 
4
2
1
2
2
2
2
1
2 2 2 2 2
1 1 1 1 1
1
2
2
1
1
2
3
4
5
6
7
8
9
10 
11 
12 
A K
4
1
3
2
1
3
2
1
5
PTH2 
PTH1 
2
1
1
DO NOT SCALE DRAWING 
S
D
GS
D
G
P5V_VGA_D 
P5V_VGA_D 
P5V_VGA_D 
4
P5V_VGA_D 
P5V_VGA_D 
5
3
2
61
P5V_VGA_D 
SHEET 
B
AA
B
B
SIZE 
SCALE: 
234
1234
DEPARTMENT CODE 
1
DOCUMENT NUMBER REV 
IN 
IN 
BI 
P3V3 
IN 
P3V3 
IN 
P5V 
IN 
IN 
Wed Feb 08 16:35:37 2017 
252 OF 270 
OUT0 
GND 
OUT1 
OUT3 
OUT2 
AC0 AC1 AC2 AC3 
OUT0 
GND 
OUT1 
OUT3 
OUT2 
AC0 AC1 AC2 AC3 
CLOSE TO CONNECTOR 
PLACE NEAR BMC 
TP FAB1 POP WHEN AST2500 0106 
TP FAB1 CHANGE FUSE 0428 
1.75A 8V 
TP FAB1 CHANGE VGA CONNECTOR'S PN 0125 
TP FAB1 ADD VGA CONNECTOR 0108 
TP FAB1 COMBINED TWO MOS TO A DUAL MOS 0112 
TP FAB1 CHANGE VGA POWER SOURCE TO NORMAL SOURCE 0216 
TP FAB1 ADD ESD IC CR25W1 AND CR25W2 0115 
TP FAB1 ADD SOME PARTS OF VGA CIRCUIT, THE OTHER PARTS ARE WAITING FOR HDL SYMBOL. 0106 
TP FAB1 CHANGE FUSE 0111 
TP FAB1 ADD VGA VOLTAGE SOURCE CIRCUIT 0114 
GROUP=AST2500 
WIWYNN CORPORATION 
VGA 



GND 
GND 
GND 
GND 
PTH8 
PTH7 
PTH6 
PTH5 
PTH4 
PTH3 
PTH2 
PTH1 
SBU2 
SBU1 
NP2 
NP1 
SSTXN2 
SSTXP2 
SSRXN2 
SSRXP2 
VBUS 
VBUS 
VBUS 
VBUS 
SSRXP1 
SSRXN1 
DN2 
DP2 
CC2 
DN1 
DP1 
CC1 
SSTXN1 
SSTXP1 
POLYSW-1D1A6V-2-GP-U 
F30W1 
ESD3V3U4ULC 
C30W7 C30W5 C30W6 C30W9 
J30W1 
C30W3 
R30W2 
0402 
1 2
1/16W 
5% G21497-005 
CHIP 
0.0 
CHIP 
G21497-005 
21
5% 
1/16W 0402 
0.0 
0.0 
R30W4 
5% 
0402 CHIP 1/16W 
G21497-005 
1 2
0.0 
1/16W 0402 
1 2
CHIP 
5% G21497-005 
R30W3 
X7R 0402V 
1
10% C30W2 0.1UF 16V 
2
A36096-030 
A36096-030 
16V 
1 2
C30W1 
X7R 
0.1UF 10% 
0402V 
SKT-USB32-8-GP 
CR30W1 
1
2
5
9
6
7
3
4
G18435-001 
8
IC 
OVERLAPPING FOOTPRINT 
C30W4 C30W8 
OVERLAPPING FOOTPRINT 
R30W1 
TP FAB4 CHANGE F30W1 TO POLYSW SYMBOL 20170203 
TP FAB1 ADD RES AND CONNECT TO P5V_STBY 0331 
RES AND CHOKE 
RES AND CHOKE 
115 
115 
115 
115 
GROUP=NO_KR 
GROUP=NO_KR 
P5V_STBY_USBC 
GROUP=NO_KR GROUP=NO_KR GROUP=NO_KR GROUP=NO_KR GROUP=NO_KR GROUP=NO_KR 
22UF 
20% 
16V 
0805 
X6S 
22UF 
16V 
22UF 
X6S 
0805 0805 
X6S 
20% 
22UF 22UF 
20% 
16V 16V 
X6S 
0805 0805 
X6S 
20% 20% 
16V 
20% 
22UF 
X6S 
GROUP=NO_KR 
16V 
22UF 
20% 
0805 
X6S 
USB3_P01_RXP USB3_P01_FB_RXP 
USB3_P01_FB_TXN 
USB3_P01_FB_RXN 
USB3_P01_FB_TXP 
USB3_P01_C_TXN 
USB3_P01_RXN 
USB3_P01_TXP 
USB3_P01_TXN 
USB3_P01_C_TXP 
16V 
0805 
SC22U16V5MX-4-GP 
SC22U16V5MX-4-GP 
SC22U16V5MX-4-GP 
SC22U16V5MX-4-GP 
SC22U16V5MX-4-GP 
SC22U16V5MX-4-GP 
SC22U16V5MX-4-GP 
CAD NOTE: 
CAD NOTE: 
2
4 3
1 2
2
3
1
4
B9 
B11 
B10 
B12 
A11 
A10 
PTH1 
PTH2 
PTH3 
PTH4 
PTH5 
PTH6 
NP2 
A9 
A3 
PTH8 
PTH7 
B1 A2 
A4 A5 
B8 
B7 
B2 
B3 
A7 
A6 
A1 
B6 
B5 
A12 
NP1 
A8 
B4 
1
DO NOT SCALE DRAWING SHEET 
B
AA
B
B
SIZE 
SCALE: 
234
1234
DEPARTMENT CODE 
1
DOCUMENT NUMBER REV 
P5V_STBY 
OUT 
OUT 
IN 
IN 
2
1
2
2
2
1 2
1 2
1
1
2 1
1
L30W2 
EMPTY 
67 OHM 
752402-028 
EMPTY 
67 OHM 
L30W1 
752402-028 
CHOKE 4PIN 
CHOKE 4PIN 
Wed Feb 08 16:35:37 2017 
253 OF 270 
OUT0 
GND 
OUT1 
OUT3 
OUT2 
AC0 AC1 AC2 AC3 
L30W1 CANNOT POP WHEN THE PORT IS USED AS DCI 
TP FAB1 SWAP L30W2.2 AND L30W2.3 FOR LAYOUT ROUTING 0118 
TP FAB1 ADD CAP 0406 
TP FAB1 SWAP L30W1.1 AND L30W1.4 FOR LAYOUT ROUTING 0118 
TP FAB1 ADD USB3.0 TYPE C CONNECTOR 0113 
TP FAB1 SWAP L30W2.1 AND L30W2.4 FOR LAYOUT ROUTING 0118 
TP FAB1 RECONNECTION 0307 
WIWYNN CORPORATION 
USB TYPE C CONNECTOR 



COM 
EN# 
V- 
GND NO 
IN 
V+ 
NC 
74CBTLV3126 
D97712-011 
PD_GTL2014_3_VREF 
2 A36096-030 
NC7SZ08 
1/16W 0402 
1% 
FB25W1 
U25W19 
IC 
0402 
A79322-001 
VCC=P3V3_STBY;GND=GND; 
4
1
MAX4564EKA-GP 
U25W13 
FB25W4 
16V 
X7R 2
SOTLF 
IC 
U25W17 
D10321-001 
5
C25W99 
0.1UF 1
2 2
1% 
D66151-001 
X6S 
C25W94 
16V 
4
1.00K 
1
2
0402V 
4
1% 
2
G21796-026 
0402 0402 
G21796-026 
2
12 
1
CHIP 
1.00K R25W167 
1/16W 0402 G21796-026 CHIP 
1% 
2
1
1
CHIP 
IC 
1
CHIP 
1/16W 
1.00K 
1/16W 
CHIP 
2
1.00K 
1% 
1
1/16W 
1% 1
0402 
G21796-026 
X6S 
CHIP 
D97712-004 
U25W10 
1.0UF 
G21796-026 
1/16W 
1PU_GTL2014_3_DIR 
12 
0402 
G21796-026 
CHIP 
1/16W 
1% 1
1.00K 
6
10 
R25W159 
1
1% 
0402 
1
R25W178 
1% 
2 G21796-026 
R25W160 
2
0402 
CHIP 
1.00K 
1/16W 
CHIP 
1.00K 
1% 
1
2
R25W161 
1.00K 
2
2
1
C25W91 
6.3V 
10% 
0402V 2
IC 
4
11 
8
7
2
69
14 
3
5
R25W158 R25W177 
9
13 
8
U25W12 
1
1.0UF 
0402 
2
10% 
10.0K 
13 
3
G21796-026 
VCC=P3V3_STBY;GND=GND 
1/16W 
G21796-026 
FB25W2 
BLM15AG121SN-1GP 
BLM15AG121SN-1GP 
FB25W3 
11 
A36096-030 
10% 
CHIP G21796-026 
1.00K 
0402 
1 2
10 
1.00K 
BLM15AG121SN-1GP 
D18317-001 
0402 
R25W168 
1/16W 
R25W169 
VCC=P3V3_STBY;GND=GND; 
R25W170 
BLM15AG121SN-1GP BLM15AG121SN-1GP 
FB25W5 
1
2
16V 
C25W95 
10% 
1
2 X7R 
0402V 
A36096-030 
0.1UF 
X7R 
0402V 
10% 
R25W174 
1% 
74HC1G126 
1
16V 
0.1UF 
C25W101 
CHIP 
1/16W 
TP FAB3-DVT CHANGE RES R25W162-163 TO BEAD FB25W4-5 20161117 
120OHM @ 100MHZ 120OHM @ 100MHZ 
TP FAB3 ADD C25W99 AND U25W17 1021 
TP FAB3 CONNECT TO P1V05_PCH_STBY 1014 
120OHM @ 100MHZ 
TP FAB3-DVT CHANGE RES R25W171-173 TO BEAD FB25W1-3 20161116 
120OHM @ 100MHZ 
120OHM @ 100MHZ 
TP FAB3 RECONNECT 1014 
TP FAB3 DISCONNECT FROM XDP_TDO 1014 
TP FAB3 CHANGE CONNECTION 1024 
TP FAB3 CHANGE CONNECTION 1024 
TP FAB3 RECONNECT 1014 
TP FAB3 RECONNECT 1014 
TP FAB3 RECONNECT 1024 
TP FAB3-DVT CHANGE CONNECTION 20161108 
TP FAB3 CHANGE CONNECTION 1024 
TP FAB4 DELETE 3PIN HEADER J25W2 20170111 
TP FAB4 ADD BUFFER 20170111 
TP FAB3 RENAME 0922 
TP FAB4 REONNECT 20170111 
144 189 
144 189 245 
255 254 
111 118 112 
111 118 112 
111 118 22 56 
111 118 112 
254 
111 112 118 
111 21 55 112 
255 
254 
147 
255 
254 
111 118 112 
146 
254 
255 
255 
255 
148 
189 
255 
JTAG_BMC_TCK1 
JTAG_BMC_TCK 
JTAG_BMC_TRST_N 
BMC_JTAG_SEL_BUF 
XDP_TMS 
XDP_TDI 
XDP_CPU_PWR_DEBUG_N 
XDP_TDI_R 
XDP_TMS_R 
XDP_PREQ_N 
JTAG_BMC_TCK0 
JTAG_BMC_TCK1 
BMC_PREQ_BUF_N 
XDP_TRST_R_N 
XDP_PCH_TCK1 
XDP_CPU_TCK0 
BMC_JTAG_SEL_BUF 
JTAG_BMC_TCK0 
BMC_PREQ_N 
BMC_JTAG_SEL_BUF 
XDP_TRST_N 
XDP_PCH_TCK1_R 
XDP_CPU_TCK0_R 
JTAG_BMC_TRST_BUF_N 
BMC_TCK_MUX_SEL 
BMC_PREQ_BUF_N 
JTAG_BMC_BUF_TDI 
JTAG_BMC_BUF_TMS 
BMC_PWR_DEBUG_BUF_N 
BMC_JTAG_SEL_N 
JTAG_BMC_TCK_BUF 
254 
254 
254 
254 
B
B
OE 
OE 
OE 
B
OE 
B
A
A
A
A
G21796-016 
CAD NOTE: 
4
2
21
1
7
5
6
8
1
1
2
21
2
1
3
2
DO NOT SCALE DRAWING SHEET 
B
AA
B
B
SIZE 
SCALE: 
234
1234
DEPARTMENT CODE 
1
DOCUMENT NUMBER REV 
IN P3V3_STBY 
IN 
OUT 
IN 
IN 
IN 
IN 
P3V3_STBY 
P3V3_STBY 
IN 
P3V3_STBY 
IN 
IN 
IN 
OUT 
OUT 
OUT 
OUT 
OUT 
OUT 
OUT 
P1V05_PCH_STBY 
P3V3_STBY 
IN 
IN 
P3V3_STBY 
Wed Feb 08 16:35:38 2017 
254 OF 270 
DIR 
VREF VCC 
GND<0> GND<1> GND<2> 
B0 B1 B2 B3 
A0 A1 A2 A3 
TP FAB3 ADD BMC REMOTE CIRCUIT 0920 
PLACE NEAR U25W19 
U25E17 PLACE CAP CLOSE TO 
GTL2014 
WIWYNN CORPORATION 
BMC REMOTE DEBUG CIRCUIT - 1 OF 2 



1/16W 
TP FAB3-DVT ADD 0OHM RES R25W187 20161205 
TP FAB3 RECONNECT 1014 
TP FAB3 ADD RES 0922 
WILL ADD A SWITCH 62.40018.461 (DIPTRONICS/MSS3-V-T/R). 
TP FAB3 ADD CIRCUIT 1014 
TP FAB3 NOPOP R25W164 0922 
TP FAB3 CHANGE CONNECTION 1024 TP FAB3 CHANGE CONNECTION 1024 
TP FAB3 ADD C25W100 AND U25W18 1021 
1-2: ENABLE BMC DEBUG 
2-3: DISABLE BMC DEBUG (DEFAULT) 
TP FAB3-DVT ADD SWITCH S9W1 20161116 
144 189 
254 
144 189 
147 
254 
111 
146 
255 
111 146 255 
254 
112 118 111 
144 
112 118 111 
144 189 255 
254 
111 22 56 
146 
148 189 
254 
255 
IC 
R25W187 
PD_GTL2014_6_B0 
TP_GTL2014_6_A2 
G21796-026 
D97712-011 
1
R25W166 
SW-SLIDE75-GP 
C79254-001 
FET 
2N7002 
A36096-030 
S9W1 
0402V 
16V 
10% 
Q25W5 
G21796-072 
VCC=P3V3_STBY;GND=GND 
JTAG_BMC_TDI 
U25W18 
BMC_JTAG_SEL_BUF 
D18317-001 
10 
5
4
2
1
JTAG_BMC_TMS 
74CBTLV3126 
13 
9
12 BMC_PWR_DEBUG_N 
JTAG_BMC_BUF_TDI 
6
0402 
10% 
XDP_PRESENT_N 
BMC_JTAG_SEL 
C25W98 
1.0UF 
16V 
4
1
0402 
D97712-011 
2 CHIP 
1/16W 
1 4.75K 
1% 
P0V7_GTL2014_VREF_6 
XDP_PRESENT_N 
1/16W 
X7R 
TO IC 
U25W16 
X6S 
JTAG_BMC_BUF_TMS 
IC 
2
3
U25W14 
74LVC1G07 
TO IC 
X7R 
A36096-030 
0402V 
2
IC 
C25W97 
G21796-026 
0402 
PLACE CAP CLOSE 
0402 
1/16W 
1% 
374 OHM 
R25W183 
374R2F-1-GP G21796-047 
CHIP 
1/16W 
2
1 1% 
49.9 
NOPOP 
0402 
1/16W 
1% 1
2
R25W165 
1
2
1 1.0UF 
C25W92 
2
10% 
16V 
X6S 
0402 
U25W11 
1
6
IC 
2
14 
5
3
4
D66151-001 
8
7
12 
1/16W 
CHIP 
G21796-026 
0402 
2
1 1% 
1.00K 
R25W175 R25W176 
1.00K 
1/16W 
CHIP 
G21796-026 
0402 
2
1 1% 
4
10% 
16V 1
2
0.1UF 
C25W96 
1.00K 
1% 
CHIP 
G21796-026 
0402 
2
1
R25W179 
1/16W 
0.1UF 
A36096-030 2
1 16V 
0402V 
10% 
R25W180 
1.00K 
1% 
CHIP 
1
2 IC 
VCC=P3V3_STBY;GND=GND 
2
74LVC1G07 
4
C88419-001 
U25W15 
PD_GTL2014_6_B2 
XDP_TDO 
BMC_DEBUG_EN_N 
13 
10 
9
16V 
0.1UF 
C25W93 
XDP_PRDY_N 
11 
C25W100 
2
1 0.1UF 
X7R 
JTAG_BMC_TDO 8
11 
JTAG_BMC_BUF_TDO 
BMC_PWR_DEBUG_BUF_N 
SOTLF 
NC7SZ08 
R25W185 
0402 
D10321-001 
1
2
VCC=P3V3_STBY;GND=GND; 
C88419-001 
VCC=P3V3_STBY;GND=GND 
CPU_XDP_PRESENT_N 
PLACE CAP CLOSE 
R25W164 
2
1.00K 
CHIP 
10% 
X7R 
A36096-030 
0402V 
1% 
21
TP_GTL2014_6_A0 
0.0 5% 
0402 
0402 
BMC_PRDY_N 
1/16W 
G21497-005 
PD_GTL2014_DIR_6 
BMC_JTAG_SEL_N 
JTAG_BMC_BUF_TDO 
CHIP 
G21796-017 
100.0 
JTAG_BMC_BUF_TDO_R 
S
D
G
B
B
OE 
OE 
OE 
B
OE 
B
A
A
A
A
CAD NOTE: 
CAD NOTE: 
CAD NOTE: 
NP2 
2
1
3
NP1 
DO NOT SCALE DRAWING 
2
1
3
SHEET 
B
AA
B
B
SIZE 
SCALE: 
234
1234
DEPARTMENT CODE 
1
DOCUMENT NUMBER REV 
P3V3_STBY 
OUT 
OUT 
IN 
P3V3_STBY 
P3V3_STBY 
P3V3_STBY 
IN 
OUT 
IN 
IN 
IN 
IN 
OUT 
OUT 
OUT 
P3V3_STBY 
P3V3_STBY 
IN 
OUT 
OUT 
P1V05_PCH_STBY 
P3V3_STBY 
P3V3_STBY 
IN 
IN 
P3V3_STBY 
IN 
2 1
5
4
7
6
TTL1G07_A 
TTL1G07_A 
PLACE R25W187 NEAR U25W11 
TP FAB3 ADD BMC REMOTE CIRCUIT 0920 
Wed Feb 08 16:35:38 2017 Tue Sep 20 14:39:26 2016 
255 OF 270 
PLACE CAP CLOSE TO 
U25E18 
DIR 
VREF VCC 
GND<0> GND<1> GND<2> 
B0 B1 B2 B3 
A0 A1 A2 A3 
GTL2014 
WIWYNN CORPORATION 
BMC REMOTE DEBUG CIRCUIT - 2 OF 2 



T1P1 
TPAD-DIFF-4P-GP 
T1P36 
TPAD-SE-2P-GP 
TPAD-DIFF-4P-GP TPAD-DIFF-4P-GP 
T1P3 
TPAD-DIFF-4P-GP 
TPAD-DIFF-4P-GP 
TPAD-DIFF-4P-GP 
TPAD-DIFF-4P-GP 
T1P35 
T1P34 
T1P33 
T1P32 
T1P31 
T1P27 
TPAD-SE-2P-GP 
T1P26 
TPAD-SE-2P-GP 
TPAD-SE-2P-GP 
T1P25 
T1P29 
TPAD-SE-2P-GP 
T1P30 
TPAD-SE-2P-GP 
T1P28 
TPAD-SE-2P-GP TPAD-SE-2P-GP 
TPAD-SE-2P-GP 
TPAD-SE-2P-GP 
TPAD-SE-2P-GP 
TPAD-SE-2P-GP 
TPAD-DIFF-4P-GP 
T1P11 
TPAD-DIFF-4P-GP 
TPAD-DIFF-4P-GP 
T1P12 
TPAD-DIFF-4P-GP 
T1P7 
TPAD-DIFF-4P-GP 
T1P8 
TPAD-DIFF-4P-GP 
T1P9 
T1P10 
TPAD-DIFF-4P-GP 
TPAD-DIFF-4P-GP 
TPAD-DIFF-4P-GP 
T1P24 
T1P23 
T1P19 
TPAD-DIFF-4P-GP 
T1P17 
T1P14 
T1P4 
T1P2 
TPAD-DIFF-4P-GP 
T1P5 
T1P6 
T1P22 
TP FAB3-DVT CORRECT THE NET NAME 20161128 
TP FAB3-DVT CORRECT THE NET NAME 20161124 
L1_95OHM_6INCH_DN 
L12_95OHM_6INCH_DN 
L1_50OHM_6INCH 
L14_50OHM_6INCH 
L14_100OHM_6INCH_DN 
L3_73OHM_6INCH_DP 
L3_73OHM_6INCH_DN 
L12_95OHM_6INCH_DP L12_73OHM_6INCH_DP 
L12_50OHM_6INCH 
L3_40OHM_6INCH 
L5_50OHM_6INCH 
L3_50OHM_6INCH 
L10_50OHM_6INCH 
L1_40OHM_6INCH 
L5_40OHM_6INCH 
L10_40OHM_6INCH 
L12_40OHM_6INCH 
L14_40OHM_6INCH 
L10_73OHM_6INCH_DN 
L12_73OHM_6INCH_DN 
L14_73OHM_6INCH_DN 
L10_85OHM_6INCH_DN 
L12_85OHM_6INCH_DP 
L14_73OHM_6INCH_DP 
L14_85OHM_6INCH_DN 
L14_85OHM_6INCH_DP 
L12_85OHM_6INCH_DN 
L1_73OHM_6INCH_DP 
L1_73OHM_6INCH_DN 
L5_73OHM_6INCH_DP 
L5_73OHM_6INCH_DN 
L10_73OHM_6INCH_DP L10_85OHM_6INCH_DP 
L3_85OHM_6INCH_DP 
L3_85OHM_6INCH_DN 
L1_85OHM_6INCH_DP 
L1_85OHM_6INCH_DN 
L5_85OHM_6INCH_DP 
L5_85OHM_6INCH_DN 
L1_100OHM_6INCH_DP 
L1_100OHM_6INCH_DN 
L10_100OHM_6INCH_DN 
L12_100OHM_6INCH_DP 
L12_100OHM_6INCH_DN 
L14_100OHM_6INCH_DP 
L1_95OHM_6INCH_DP 
L10_100OHM_6INCH_DP 
GND1 
1
GND1 
1
GND1 
1
GND1 
1
GND1 
1
GND1 
1
GND1 
1
GND1 
1
GND1 
1
GND1 
1
GND1 
1
GND1 
1
GND1 
GND1 
GND1 
GND2 
GND1 
11GND1 GND1 
GND1 
GND2 
2
1
GND1 
1
2
1
2
1
2GND2 GND2 
1
GND2 
2
GND1 
2
GND1 
GND2 
1
2GND2 
1
2
GND1 
GND2 
1
2
GND1 
GND2 
1
2
2GND2 
1
2
1
2
1
2
1
GND1 
GND2 
GND1 
GND2 
2
GND1 
GND2 
1
2GND2 
1
2
GND1 
GND2 
1
GND2 
GND1 
GND1 
GND2 
GND2 
2
DO NOT SCALE DRAWING SHEET 
B
AA
B
B
SIZE 
SCALE: 
234
1234
DEPARTMENT CODE 
1
DOCUMENT NUMBER REV 
Wed Feb 08 16:35:38 2017 
256 OF 270 
TP FAB3-DVT ADD COUPON SYMBOLS 20161118 
WIWYNN CORPORATION 
COUPON - 1 OF 3 



DN 
DP 
GND 
GND 
GND 
GND 
GND 
GND 
GND 
GND 
GND 
GND 
DN 
DP 
GND 
GND 
GND 
GND 
GND 
GND 
GND 
GND 
GND 
GND 
DN 
DP 
GND 
GND 
GND 
GND 
GND 
GND 
GND 
GND 
GND 
GND 
DN 
DP 
GND 
GND 
GND 
GND 
GND 
GND 
GND 
GND 
GND 
GND 
DN 
DP 
GND 
GND 
GND 
GND 
GND 
GND 
GND 
GND 
GND 
GND 
DN 
DP 
GND 
GND 
GND 
GND 
GND 
GND 
GND 
GND 
GND 
GND 
DN 
DP 
GND 
GND 
GND 
GND 
GND 
GND 
GND 
GND 
GND 
GND 
DN 
DP 
GND 
GND 
GND 
GND 
GND 
GND 
GND 
GND 
GND 
GND 
DN 
DP 
GND 
GND 
GND 
GND 
GND 
GND 
GND 
GND 
GND 
GND 
DN 
DP 
GND 
GND 
GND 
GND 
GND 
GND 
GND 
GND 
GND 
GND 
DN 
DP 
GND 
GND 
GND 
GND 
GND 
GND 
GND 
GND 
GND 
GND 
DN 
DP 
GND 
GND 
GND 
GND 
GND 
GND 
GND 
GND 
GND 
GND 
L1_85OHM_5INCH_DN 
L14_85OHM_5INCH_DP 
L14_85OHM_5INCH_DP 
L14_85OHM_5INCH_DN 
L14_85OHM_5INCH_DN 
L12_85OHM_5INCH_DP 
L12_85OHM_5INCH_DN L12_85OHM_5INCH_DP 
L12_85OHM_5INCH_DN 
L5_85OHM_5INCH_DP 
L5_85OHM_5INCH_DN 
L3_85OHM_5INCH_DP L3_85OHM_5INCH_DN 
L1_85OHM_5INCH_DP L1_85OHM_5INCH_DN 
L1_85OHM_5INCH_DP 
L3_85OHM_5INCH_DN L3_85OHM_5INCH_DP 
L5_85OHM_5INCH_DN 
L5_85OHM_5INCH_DP 
L10_85OHM_5INCH_DP L10_85OHM_5INCH_DN 
L10_85OHM_5INCH_DP L10_85OHM_5INCH_DN 
T1D11 T1D12 
TEST-PAD-12P-1-GP-U 
T1D9 
TEST-PAD-12P-1-GP-U 
T1D10 
TEST-PAD-12P-1-GP-U TEST-PAD-12P-1-GP-U TEST-PAD-12P-1-GP-U 
T1D5 T1D6 
T1D3 
TEST-PAD-12P-1-GP-U 
T1D4 
TEST-PAD-12P-1-GP-U 
TEST-PAD-12P-1-GP-U TEST-PAD-12P-1-GP-U 
T1D1 T1D2 
TEST-PAD-12P-1-GP-U 
TEST-PAD-12P-1-GP-U 
T1D8 T1D7 
TEST-PAD-12P-1-GP-U 
4
1
11 
10 
4
2
1
12 
11 
10 
9
8
7
6
5
4
3
2
1
12 
9
8
7
6
5
3
3
4
5
6
7
8
9
10 
11 
12 
1
2
3
4
5
6
7
8
9
10 
11 
12 
2
11 
12 
2
1
9
8
7
6
5
4
3
2
1
12 
11 
10 
9
8
7
6
5
4
3
2
1
12 
11 
10 
9
8
7
6
5
4
3
2
1
12 
11 
10 
9
8
7
6
5
4
3
8
3
5
6
7
8
9
10 
11 
12 
1
2
3
4
5
6
7
12 
1
2
10 
11 
10 
9
3
4
5
6
7
8
9
10 
11 
12 
1
2
3
4
5
6
7
8
9
10 
11 
12 
1
2
DO NOT SCALE DRAWING SHEET 
B
AA
B
B
SIZE 
SCALE: 
234
1234
DEPARTMENT CODE 
1
DOCUMENT NUMBER REV 
Wed Feb 08 16:35:38 2017 
257 OF 270 
Thu Nov 17 16:16:25 2016 
TP FAB3-DVT ADD COUPON SYMBOLS 20161118 
WIWYNN CORPORATION 
COUPON - 2 OF 3 



DN 
DP 
GND 
GND 
GND 
GND 
GND 
GND 
GND 
GND 
GND 
GND 
DN 
DP 
GND 
GND 
GND 
GND 
GND 
GND 
GND 
GND 
GND 
GND 
DN 
DP 
GND 
GND 
GND 
GND 
GND 
GND 
GND 
GND 
GND 
GND 
DN 
DP 
GND 
GND 
GND 
GND 
GND 
GND 
GND 
GND 
GND 
GND 
DN 
DP 
GND 
GND 
GND 
GND 
GND 
GND 
GND 
GND 
GND 
GND 
DN 
DP 
GND 
GND 
GND 
GND 
GND 
GND 
GND 
GND 
GND 
GND 
DN 
DP 
GND 
GND 
GND 
GND 
GND 
GND 
GND 
GND 
GND 
GND 
DN 
DP 
GND 
GND 
GND 
GND 
GND 
GND 
GND 
GND 
GND 
GND 
DN 
DP 
GND 
GND 
GND 
GND 
GND 
GND 
GND 
GND 
GND 
GND 
DN 
DP 
GND 
GND 
GND 
GND 
GND 
GND 
GND 
GND 
GND 
GND 
DN 
DP 
GND 
GND 
GND 
GND 
GND 
GND 
GND 
GND 
GND 
GND 
DN 
DP 
GND 
GND 
GND 
GND 
GND 
GND 
GND 
GND 
GND 
GND 
L14_85OHM_10INCH_DP 
L14_85OHM_10INCH_DN 
L14_85OHM_10INCH_DN 
L14_85OHM_10INCH_DP 
L12_85OHM_10INCH_DP 
L12_85OHM_10INCH_DN 
L12_85OHM_10INCH_DN 
L12_85OHM_10INCH_DP 
L10_85OHM_10INCH_DP 
L10_85OHM_10INCH_DN 
L10_85OHM_10INCH_DN 
L10_85OHM_10INCH_DP 
L5_85OHM_10INCH_DP 
L5_85OHM_10INCH_DN 
L5_85OHM_10INCH_DN 
L5_85OHM_10INCH_DP 
L3_85OHM_10INCH_DP 
L3_85OHM_10INCH_DN 
L3_85OHM_10INCH_DN 
L3_85OHM_10INCH_DP 
L1_85OHM_10INCH_DP 
L1_85OHM_10INCH_DN 
L1_85OHM_10INCH_DN 
L1_85OHM_10INCH_DP 
T1D24 T1D23 
T1D22 T1D21 
T1D20 T1D19 
T1D18 T1D17 
T1D16 T1D15 
T1D14 T1D13 
TEST-PAD-12P-1-GP-U 
TEST-PAD-12P-1-GP-U 
TEST-PAD-12P-1-GP-U 
TEST-PAD-12P-1-GP-U 
TEST-PAD-12P-1-GP-U 
TEST-PAD-12P-1-GP-U TEST-PAD-12P-1-GP-U TEST-PAD-12P-1-GP-U 
TEST-PAD-12P-1-GP-U TEST-PAD-12P-1-GP-U 
TEST-PAD-12P-1-GP-U TEST-PAD-12P-1-GP-U 
8
2
1
12 
11 
10 
9
8
7
6
5
4
3
2
1
12 
11 
10 
9
8
7
6
5
4
3
3
4
5
6
7
8
9
10 
11 
12 
1
2
2
1
12 
11 
10 
9
8
7
6
5
4
3
2
1
12 
11 
10 
9
8
7
6
5
4
3
2
1
12 
11 
10 
9
8
7
6
5
4
3
2
1
12 
11 
10 
9
8
7
6
5
4
3
2
1
12 
11 
10 
9
7
6
5
4
3
2
1
12 
11 
10 
9
8
7
6
5
4
3
3
4
5
6
7
8
9
10 
11 
12 
1
2 2
1
12 
11 
10 
9
8
7
6
5
4
3
2
1
12 
11 
10 
9
8
7
6
5
4
3
DO NOT SCALE DRAWING SHEET 
B
AA
B
B
SIZE 
SCALE: 
234
1234
DEPARTMENT CODE 
1
DOCUMENT NUMBER REV 
258 OF 270 
Wed Feb 08 16:35:39 2017 
257 OF 270 
Thu Nov 17 16:16:25 2016 
TP FAB3-DVT ADD COUPON SYMBOLS 20161118 
WIWYNN CORPORATION 
COUPON - 3 OF 3 



DO NOT SCALE DRAWING SHEET 
B
AA
B
B
SIZE 
SCALE: 
234
1234
DEPARTMENT CODE 
1
DOCUMENT NUMBER REV 
Wed Feb 08 16:35:39 2017 
259 OF 270 
WIWYNN CORPORATION 
SMBUS BLOCK DIAGRAM - 1 OF 2 



DO NOT SCALE DRAWING SHEET 
B
AA
B
B
SIZE 
SCALE: 
234
1234
DEPARTMENT CODE 
1
DOCUMENT NUMBER REV 
260 OF 270 
Wed Feb 08 16:35:39 2017 
WIWYNN CORPORATION 
SMBUS BLOCK DIAGRAM - 2 OF 2 



DO NOT SCALE DRAWING SHEET 
B
AA
B
B
SIZE 
SCALE: 
234
1234
DEPARTMENT CODE 
1
DOCUMENT NUMBER REV 
Wed Feb 08 16:35:39 2017 
261 OF 270 
WIWYNN CORPORATION 
UART BLOCK DIAGRAM 



DO NOT SCALE DRAWING SHEET 
B
AA
B
B
SIZE 
SCALE: 
234
1234
DEPARTMENT CODE 
1
DOCUMENT NUMBER REV 
262 OF 270 
Wed Feb 08 16:35:40 2017 
WIWYNN CORPORATION 
SPI BLOCK DIAGRAM 1 OF 2 



DO NOT SCALE DRAWING SHEET 
B
AA
B
B
SIZE 
SCALE: 
234
1234
DEPARTMENT CODE 
1
DOCUMENT NUMBER REV 
263 OF 270 
Wed Feb 08 16:35:40 2017 
WIWYNN CORPORATION 
SPI BLOCK DIAGRAM 2 OF 2 



DO NOT SCALE DRAWING SHEET 
B
AA
B
B
SIZE 
SCALE: 
234
1234
DEPARTMENT CODE 
1
DOCUMENT NUMBER REV 
264 OF 270 
Wed Feb 08 16:35:40 2017 
WIWYNN CORPORATION 
SYMBOL DEFINITIONS 



DO NOT SCALE DRAWING SHEET 
B
AA
B
B
SIZE 
SCALE: 
234
1234
DEPARTMENT CODE 
1
DOCUMENT NUMBER REV 
265 OF 270 
Wed Feb 08 16:35:40 2017 
WIWYNN CORPORATION 
TPM BLOCK DIAGRAM 



DO NOT SCALE DRAWING SHEET 
B
AA
B
B
SIZE 
SCALE: 
234
1234
DEPARTMENT CODE 
1
DOCUMENT NUMBER REV 
266 OF 270 
Wed Feb 08 16:35:41 2017 
WIWYNN CORPORATION 
BUTTON BLOCK DIAGRAM 



DO NOT SCALE DRAWING SHEET 
B
AA
B
B
SIZE 
SCALE: 
234
1234
DEPARTMENT CODE 
1
DOCUMENT NUMBER REV 
Wed Feb 08 16:35:41 2017 
267 OF 270 
WIWYNN CORPORATION 
XDP BLOCK DIAGRAM 



DO NOT SCALE DRAWING SHEET 
B
AA
B
B
SIZE 
SCALE: 
234
1234
DEPARTMENT CODE 
1
DOCUMENT NUMBER REV 
268 OF 270 
Wed Feb 08 16:35:41 2017 
WIWYNN CORPORATION 
FAST PROCHOT BLOCK DIAGRAM 



DO NOT SCALE DRAWING SHEET 
B
AA
B
B
SIZE 
SCALE: 
234
1234
DEPARTMENT CODE 
1
DOCUMENT NUMBER REV 
269 OF 270 
Wed Feb 08 16:35:41 2017 
WIWYNN CORPORATION 
MCP JTAG BLOCK DIAGRAM 



DO NOT SCALE DRAWING SHEET 
B
AA
B
B
SIZE 
SCALE: 
234
1234
DEPARTMENT CODE 
1
DOCUMENT NUMBER REV 
270 OF 270 
Wed Feb 08 16:35:42 2017 
WIWYNN CORPORATION 
JTAG DEBUG HEADER BLOCK DIAGRAM 